; Packager-XL run on 16-Jun-2017 AT 17:50:48 CONSTRAINTS_VIEW_GENERATED
( ConstraintFile "baseboard_fab2"
	( constraintHeader
		( objectKey
			( physical )
		)
		( version
			( 16.6 )
		)
		( revisionNumber
			( logicalViewRevNum 4375 )
			( physicalViewRevNum 0 )
			( otherViewRevNum 0 )
		)
		( contents
			( dictionaryExtensions )
			( worksheetCustomizations )
			( electricalConstraints )
			( netClasses )
			( properties )
		)
		( precision
			( units mil )
			( numberOfDecimalPlaces 2 )
		)
	)
	( DictionaryExtensions
		( Attribute
			( Name "BOM_COST" )
			( Description " " )
			( Value
				( DataType ( dString ) )
				( Status  sProperty  sPackage )
			)
			( Objects
				( ValidObjects  oGate  oGateDefn  oBlock  oPart  oDesign  oSystem  oPartDefn  oNet )
				( NoInherit
					( oGate oPin )
				)
			)
			( Analysis
			)
		)
		( Attribute
			( Name "MATERIAL" )
			( Description " " )
			( Value
				( DataType ( dString ) )
				( Status  sProperty  sPackage )
			)
			( Objects
				( ValidObjects  oGate  oGateDefn  oBlock  oPart  oDesign  oSystem  oPartDefn )
				( NoInherit
					( oGate oPin )
				)
			)
			( Analysis
			)
		)
		( Attribute
			( Name "SEC_TYPE" )
			( Description " " )
			( Value
				( DataType ( dString ) )
				( Status  sProperty  sPackage )
			)
			( Objects
				( ValidObjects  oGate  oGateDefn  oBlock  oPart  oDesign  oSystem  oPartDefn )
				( NoInherit
					( oGate oPin )
				)
			)
			( Analysis
			)
		)
		( Attribute
			( Name "TOLERANCE" )
			( Description " " )
			( Value
				( DataType ( dString ) )
				( Status  sProperty  sPackage )
			)
			( Objects
				( ValidObjects  oGate  oGateDefn  oBlock  oPart  oDesign  oSystem  oPartDefn )
				( NoInherit
					( oGate oPin )
				)
			)
			( Analysis
			)
		)
		( Attribute
			( Name "WATTAGE" )
			( Description " " )
			( Value
				( DataType ( dString ) )
				( Status  sProperty  sPackage )
			)
			( Objects
				( ValidObjects  oGate  oGateDefn  oBlock  oPart  oDesign  oSystem  oPartDefn )
				( NoInherit
					( oGate oPin )
				)
			)
			( Analysis
			)
		)
		( Attribute
			( Name "SKT_NUMBER" )
			( Description " " )
			( Value
				( DataType ( dString ) )
				( Status  sProperty  sPackage )
			)
			( Objects
				( ValidObjects  oGate  oGateDefn  oBlock  oPart  oDesign  oSystem  oPartDefn )
				( NoInherit
					( oGate oPin )
				)
			)
			( Analysis
			)
		)
		( Attribute
			( Name "CD_SEC" )
			( Description " " )
			( Value
				( DataType ( dString ) )
				( Status  sProperty  sPackage )
			)
			( Objects
				( ValidObjects  oGate  oGateDefn  oBlock  oPart  oDesign  oSystem  oPartDefn )
				( NoInherit
					( oGate oPin )
				)
			)
			( Analysis
			)
		)
		( Attribute
			( Name "CDS_LMAN_SYM_OUTLINE" )
			( Description " " )
			( Value
				( DataType ( dString ) )
				( Status  sProperty  sPackage )
			)
			( Objects
				( ValidObjects  oGate  oGateDefn  oBlock  oPart  oDesign  oSystem  oPartDefn )
				( NoInherit
					( oGate oPin )
				)
			)
			( Analysis
			)
		)
		( Attribute
			( Name "SKU" )
			( Description " " )
			( Value
				( DataType ( dString ) )
				( Status  sProperty  sPackage )
			)
			( Objects
				( ValidObjects  oGate  oGateDefn  oBlock  oPart  oDesign  oSystem  oPartDefn )
				( NoInherit
					( oGate oPin )
				)
			)
			( Analysis
			)
		)
		( Attribute
			( Name "COLOR" )
			( Description " " )
			( Value
				( DataType ( dString ) )
				( Status  sProperty  sPackage )
			)
			( Objects
				( ValidObjects  oGate  oGateDefn  oBlock  oPart  oDesign  oSystem  oPartDefn )
				( NoInherit
					( oGate oPin )
				)
			)
			( Analysis
			)
		)
		( Attribute
			( Name "VOLATGE" )
			( Description " " )
			( Value
				( DataType ( dString ) )
				( Status  sProperty  sPackage )
			)
			( Objects
				( ValidObjects  oNet  oXnet  oPinPair  oBus  oDiffPair  oECSet )
			)
			( Analysis
			)
		)
		( Attribute
			( Name "SPOF" )
			( Description " " )
			( Value
				( DataType ( dString ) )
				( Status  sProperty  sPackage )
			)
			( Objects
				( ValidObjects  oGate  oGateDefn  oBlock  oPart  oDesign  oSystem  oPartDefn )
				( NoInherit
					( oGate oPin )
				)
			)
			( Analysis
			)
		)
		( Attribute
			( Name "PIN_SHORT" )
			( Description " " )
			( Value
				( DataType ( dString ) )
				( Status  sProperty  sPackage )
			)
			( Objects
				( ValidObjects  oGate  oGateDefn  oBlock  oPart  oDesign  oSystem  oPartDefn )
				( NoInherit
					( oGate oPin )
				)
			)
			( Analysis
			)
		)
		( Attribute
			( Name "BOM" )
			( Description " " )
			( Value
				( DataType ( dString ) )
				( Status  sProperty  sPackage )
			)
			( Objects
				( ValidObjects  oGate  oGateDefn  oBlock  oPart  oDesign  oSystem  oPartDefn )
				( NoInherit
					( oGate oPin )
				)
			)
			( Analysis
			)
		)
		( Attribute
			( Name "FIN" )
			( Description " " )
			( Value
				( DataType ( dString ) )
				( Status  sProperty  sPackage )
			)
			( Objects
				( ValidObjects  oGate  oGateDefn  oBlock  oPart  oDesign  oSystem  oPartDefn )
				( NoInherit
					( oGate oPin )
				)
			)
			( Analysis
			)
		)
		( Attribute
			( Name "P1V5_STBY_IBMC" )
			( Description " " )
			( Value
				( DataType ( dString ) )
				( Status  sProperty  sPackage )
			)
			( Objects
				( ValidObjects  oGate  oGateDefn  oBlock  oPart  oDesign  oSystem  oPartDefn )
				( NoInherit
					( oGate oPin )
				)
			)
			( Analysis
			)
		)
		( Attribute
			( Name "P1V5_STBY_IBMC_VR" )
			( Description " " )
			( Value
				( DataType ( dString ) )
				( Status  sProperty  sPackage )
			)
			( Objects
				( ValidObjects  oGate  oGateDefn  oBlock  oPart  oDesign  oSystem  oPartDefn )
				( NoInherit
					( oGate oPin )
				)
			)
			( Analysis
			)
		)
		( Attribute
			( Name "DIMMSIED" )
			( Description " " )
			( Value
				( DataType ( dString ) )
				( Status  sProperty  sPackage )
			)
			( Objects
				( ValidObjects  oGate  oGateDefn  oBlock  oPart  oDesign  oSystem  oPartDefn )
				( NoInherit
					( oGate oPin )
				)
			)
			( Analysis
			)
		)
		( Attribute
			( Name "DIMMSIDE" )
			( Description " " )
			( Value
				( DataType ( dString ) )
				( Status  sProperty  sPackage )
			)
			( Objects
				( ValidObjects  oGate  oGateDefn  oBlock  oPart  oDesign  oSystem  oPartDefn )
				( NoInherit
					( oGate oPin )
				)
			)
			( Analysis
			)
		)
		( Attribute
			( Name "$location" )
			( Description "" )
			( Value
				( DataType ( dString ) )
				( Status  sProperty )
			)
			( Objects
				( ValidObjects  oAll )
			)
			( Analysis
			)
		)
		( Attribute
			( Name "$sec" )
			( Description "" )
			( Value
				( DataType ( dString ) )
				( Status  sProperty )
			)
			( Objects
				( ValidObjects  oAll )
			)
			( Analysis
			)
		)
		( Attribute
			( Name "RATED_CURRENT" )
			( Description " " )
			( Value
				( DataType ( dString ) )
				( Status  sProperty  sPackage )
			)
			( Objects
				( ValidObjects  oGate  oGateDefn  oBlock  oPart  oDesign  oSystem  oPartDefn )
				( NoInherit
					( oGate oPin )
				)
			)
			( Analysis
			)
		)
		( Attribute
			( Name "STATUS" )
			( Description " " )
			( Value
				( DataType ( dString ) )
				( Status  sProperty  sPackage )
			)
			( Objects
				( ValidObjects  oGate  oGateDefn  oBlock  oPart  oDesign  oSystem  oPartDefn )
				( NoInherit
					( oGate oPin )
				)
			)
			( Analysis
			)
		)
		( Attribute
			( Name "STTATUS" )
			( Description " " )
			( Value
				( DataType ( dString ) )
				( Status  sProperty  sPackage )
			)
			( Objects
				( ValidObjects  oGate  oGateDefn  oBlock  oPart  oDesign  oSystem  oPartDefn )
				( NoInherit
					( oGate oPin )
				)
			)
			( Analysis
			)
		)
		( Attribute
			( Name "SIDE_SKU" )
			( Description " " )
			( Value
				( DataType ( dString ) )
				( Status  sProperty  sPackage )
			)
			( Objects
				( ValidObjects  oGate  oGateDefn  oBlock  oPart  oDesign  oSystem  oPartDefn )
				( NoInherit
					( oGate oPin )
				)
			)
			( Analysis
			)
		)
		( Attribute
			( Name "POP" )
			( Description " " )
			( Value
				( DataType ( dString ) )
				( Status  sProperty  sPackage )
			)
			( Objects
				( ValidObjects  oGate  oGateDefn  oBlock  oPart  oDesign  oSystem  oPartDefn )
				( NoInherit
					( oGate oPin )
				)
			)
			( Analysis
			)
		)
		( Attribute
			( Name "CONFIG" )
			( Description " " )
			( Value
				( DataType ( dString ) )
				( Status  sProperty  sPackage )
			)
			( Objects
				( ValidObjects  oGate  oGateDefn  oBlock  oPart  oDesign  oSystem  oPartDefn )
				( NoInherit
					( oGate oPin )
				)
			)
			( Analysis
			)
		)
		( Attribute
			( Name "BOM_SS_CAP" )
			( Description " " )
			( Value
				( DataType ( dString ) )
				( Status  sProperty  sPackage )
			)
			( Objects
				( ValidObjects  oGate  oGateDefn  oBlock  oPart  oDesign  oSystem  oPartDefn )
				( NoInherit
					( oGate oPin )
				)
			)
			( Analysis
			)
		)
		( Attribute
			( Name "NOPOP" )
			( Description " " )
			( Value
				( DataType ( dString ) )
				( Status  sProperty  sPackage )
			)
			( Objects
				( ValidObjects  oGate  oGateDefn  oBlock  oPart  oDesign  oSystem  oPartDefn )
				( NoInherit
					( oGate oPin )
				)
			)
			( Analysis
			)
		)
		( Attribute
			( Name "MODULE" )
			( Description " " )
			( Value
				( DataType ( dString ) )
				( Status  sProperty  sPackage )
			)
			( Objects
				( ValidObjects  oGate  oGateDefn  oBlock  oPart  oDesign  oSystem  oPartDefn )
				( NoInherit
					( oGate oPin )
				)
			)
			( Analysis
			)
		)
		( Attribute
			( Name "BOM_DS" )
			( Description " " )
			( Value
				( DataType ( dString ) )
				( Status  sProperty  sPackage )
			)
			( Objects
				( ValidObjects  oGate  oGateDefn  oBlock  oPart  oDesign  oSystem  oPartDefn )
				( NoInherit
					( oGate oPin )
				)
			)
			( Analysis
			)
		)
		( Attribute
			( Name "BOM_SS" )
			( Description " " )
			( Value
				( DataType ( dString ) )
				( Status  sProperty  sPackage )
			)
			( Objects
				( ValidObjects  oGate  oGateDefn  oBlock  oPart  oDesign  oSystem  oPartDefn )
				( NoInherit
					( oGate oPin )
				)
			)
			( Analysis
			)
		)
		( Attribute
			( Name "ATTRIBUTE" )
			( Description " " )
			( Value
				( DataType ( dString ) )
				( Status  sProperty  sPackage )
			)
			( Objects
				( ValidObjects  oGate  oGateDefn  oBlock  oPart  oDesign  oSystem  oPartDefn )
				( NoInherit
					( oGate oPin )
				)
			)
			( Analysis
			)
		)
		( Attribute
			( Name "RATED" )
			( Description " " )
			( Value
				( DataType ( dString ) )
				( Status  sProperty  sPackage )
			)
			( Objects
				( ValidObjects  oGate  oGateDefn  oBlock  oPart  oDesign  oSystem  oPartDefn )
				( NoInherit
					( oGate oPin )
				)
			)
			( Analysis
			)
		)
		( Attribute
			( Name "PACK_SIZE" )
			( Description " " )
			( Value
				( DataType ( dString ) )
				( Status  sProperty  sPackage )
			)
			( Objects
				( ValidObjects  oGate  oGateDefn  oBlock  oPart  oDesign  oSystem  oPartDefn )
				( NoInherit
					( oGate oPin )
				)
			)
			( Analysis
			)
		)
		( Attribute
			( Name "TYPE" )
			( Description " " )
			( Value
				( DataType ( dString ) )
				( Status  sProperty  sPackage )
			)
			( Objects
				( ValidObjects  oGate  oGateDefn  oBlock  oPart  oDesign  oSystem  oPartDefn )
				( NoInherit
					( oGate oPin )
				)
			)
			( Analysis
			)
		)
		( Attribute
			( Name "NEW_VALUE" )
			( Description " " )
			( Value
				( DataType ( dString ) )
				( Status  sProperty  sPackage )
			)
			( Objects
				( ValidObjects  oGate  oGateDefn  oBlock  oPart  oDesign  oSystem  oPartDefn )
				( NoInherit
					( oGate oPin )
				)
			)
			( Analysis
			)
		)
		( Attribute
			( Name "NEW_PACK_SIZE" )
			( Description " " )
			( Value
				( DataType ( dString ) )
				( Status  sProperty  sPackage )
			)
			( Objects
				( ValidObjects  oGate  oGateDefn  oBlock  oPart  oDesign  oSystem  oPartDefn )
				( NoInherit
					( oGate oPin )
				)
			)
			( Analysis
			)
		)
		( Attribute
			( Name "NEW_RATED" )
			( Description " " )
			( Value
				( DataType ( dString ) )
				( Status  sProperty  sPackage )
			)
			( Objects
				( ValidObjects  oGate  oGateDefn  oBlock  oPart  oDesign  oSystem  oPartDefn )
				( NoInherit
					( oGate oPin )
				)
			)
			( Analysis
			)
		)
		( Attribute
			( Name "NEW_TYPE" )
			( Description " " )
			( Value
				( DataType ( dString ) )
				( Status  sProperty  sPackage )
			)
			( Objects
				( ValidObjects  oGate  oGateDefn  oBlock  oPart  oDesign  oSystem  oPartDefn )
				( NoInherit
					( oGate oPin )
				)
			)
			( Analysis
			)
		)
		( Attribute
			( Name "NEW_MATERIAL" )
			( Description " " )
			( Value
				( DataType ( dString ) )
				( Status  sProperty  sPackage )
			)
			( Objects
				( ValidObjects  oGate  oGateDefn  oBlock  oPart  oDesign  oSystem  oPartDefn )
				( NoInherit
					( oGate oPin )
				)
			)
			( Analysis
			)
		)
		( Attribute
			( Name "NEW_SIZE" )
			( Description " " )
			( Value
				( DataType ( dString ) )
				( Status  sProperty  sPackage )
			)
			( Objects
				( ValidObjects  oGate  oGateDefn  oBlock  oPart  oDesign  oSystem  oPartDefn )
				( NoInherit
					( oGate oPin )
				)
			)
			( Analysis
			)
		)
		( Attribute
			( Name "NEW_PN" )
			( Description " " )
			( Value
				( DataType ( dString ) )
				( Status  sProperty  sPackage )
			)
			( Objects
				( ValidObjects  oGate  oGateDefn  oBlock  oPart  oDesign  oSystem  oPartDefn )
				( NoInherit
					( oGate oPin )
				)
			)
			( Analysis
			)
		)
		( Attribute
			( Name "SS_VALUE" )
			( Description " " )
			( Value
				( DataType ( dString ) )
				( Status  sProperty  sPackage )
			)
			( Objects
				( ValidObjects  oGate  oGateDefn  oBlock  oPart  oDesign  oSystem  oPartDefn )
				( NoInherit
					( oGate oPin )
				)
			)
			( Analysis
			)
		)
		( Attribute
			( Name "DS_VALUE" )
			( Description " " )
			( Value
				( DataType ( dString ) )
				( Status  sProperty  sPackage )
			)
			( Objects
				( ValidObjects  oGate  oGateDefn  oBlock  oPart  oDesign  oSystem  oPartDefn )
				( NoInherit
					( oGate oPin )
				)
			)
			( Analysis
			)
		)
		( Attribute
			( Name "SS_ISAT" )
			( Description " " )
			( Value
				( DataType ( dString ) )
				( Status  sProperty  sPackage )
			)
			( Objects
				( ValidObjects  oGate  oGateDefn  oBlock  oPart  oDesign  oSystem  oPartDefn )
				( NoInherit
					( oGate oPin )
				)
			)
			( Analysis
			)
		)
		( Attribute
			( Name "FAIR_SS" )
			( Description " " )
			( Value
				( DataType ( dString ) )
				( Status  sProperty  sPackage )
			)
			( Objects
				( ValidObjects  oGate  oGateDefn  oBlock  oPart  oDesign  oSystem  oPartDefn )
				( NoInherit
					( oGate oPin )
				)
			)
			( Analysis
			)
		)
	)
	( designConstraints
		( ruleChanges
			( allRules )
			( design "baseboard_fab2"
				( objectFlag fObjectReadOnly )
				( objectStatus sObjectLogicalNet )
			)
			( signal "A_CPU0_ABC_RCOMP0"
				( objectStatus "@baseboard_fab2_lib.baseboard_fab2(sch_1):a_cpu0_abc_rcomp0" )
			)
			( signal "A_CPU0_ABC_RCOMP1"
				( objectStatus "@baseboard_fab2_lib.baseboard_fab2(sch_1):a_cpu0_abc_rcomp1" )
			)
			( signal "A_CPU0_ABC_RCOMP2"
				( objectStatus "@baseboard_fab2_lib.baseboard_fab2(sch_1):a_cpu0_abc_rcomp2" )
			)
			( signal "A_CPU0_DEF_RCOMP0"
				( objectStatus "@baseboard_fab2_lib.baseboard_fab2(sch_1):a_cpu0_def_rcomp0" )
			)
			( signal "A_CPU0_DEF_RCOMP1"
				( objectStatus "@baseboard_fab2_lib.baseboard_fab2(sch_1):a_cpu0_def_rcomp1" )
			)
			( signal "A_CPU0_DEF_RCOMP2"
				( objectStatus "@baseboard_fab2_lib.baseboard_fab2(sch_1):a_cpu0_def_rcomp2" )
			)
			( signal "A_CPU0_MCP01_RBIAS"
				( objectStatus "@baseboard_fab2_lib.baseboard_fab2(sch_1):a_cpu0_mcp01_rbias" )
			)
			( signal "A_CPU0_PE012_RBIAS"
				( objectStatus "@baseboard_fab2_lib.baseboard_fab2(sch_1):a_cpu0_pe012_rbias" )
			)
			( signal "A_CPU0_PE3_RBIAS"
				( objectStatus "@baseboard_fab2_lib.baseboard_fab2(sch_1):a_cpu0_pe3_rbias" )
			)
			( signal "A_CPU0_UPI01_RBIAS"
				( objectStatus "@baseboard_fab2_lib.baseboard_fab2(sch_1):a_cpu0_upi01_rbias" )
			)
			( signal "A_CPU0_UPI2_RBIAS"
				( objectStatus "@baseboard_fab2_lib.baseboard_fab2(sch_1):a_cpu0_upi2_rbias" )
			)
			( signal "CLK_100M_CPU0_BCLK0_DN"
				( objectStatus "@baseboard_fab2_lib.baseboard_fab2(sch_1):clk_100m_cpu0_bclk0_dn" )
			)
			( signal "CLK_100M_CPU0_BCLK0_DP"
				( objectStatus "@baseboard_fab2_lib.baseboard_fab2(sch_1):clk_100m_cpu0_bclk0_dp" )
			)
			( signal "CLK_100M_CPU0_BCLK1_DN"
				( objectStatus "@baseboard_fab2_lib.baseboard_fab2(sch_1):clk_100m_cpu0_bclk1_dn" )
			)
			( signal "CLK_100M_CPU0_BCLK1_DP"
				( objectStatus "@baseboard_fab2_lib.baseboard_fab2(sch_1):clk_100m_cpu0_bclk1_dp" )
			)
			( signal "CLK_100M_CPU0_BCLK2_DN"
				( objectStatus "@baseboard_fab2_lib.baseboard_fab2(sch_1):clk_100m_cpu0_bclk2_dn" )
			)
			( signal "CLK_100M_CPU0_BCLK2_DP"
				( objectStatus "@baseboard_fab2_lib.baseboard_fab2(sch_1):clk_100m_cpu0_bclk2_dp" )
			)
			( signal "FM_CPU0_PKGID0"
				( objectStatus "@baseboard_fab2_lib.baseboard_fab2(sch_1):fm_cpu0_pkgid0" )
			)
			( signal "FM_CPU0_PKGID1"
				( objectStatus "@baseboard_fab2_lib.baseboard_fab2(sch_1):fm_cpu0_pkgid1" )
			)
			( signal "FM_CPU0_PKGID2"
				( objectStatus "@baseboard_fab2_lib.baseboard_fab2(sch_1):fm_cpu0_pkgid2" )
			)
			( signal "FM_CPU0_PROC_ID0"
				( objectStatus "@baseboard_fab2_lib.baseboard_fab2(sch_1):fm_cpu0_proc_id0" )
			)
			( signal "FM_CPU0_PROC_ID1"
				( objectStatus "@baseboard_fab2_lib.baseboard_fab2(sch_1):fm_cpu0_proc_id1" )
			)
			( signal "FM_CPU0_SKTOCC_LVT3_N"
				( objectStatus "@baseboard_fab2_lib.baseboard_fab2(sch_1):fm_cpu0_sktocc_lvt3_n" )
			)
			( signal "FM_CPU0_SM_WP"
				( objectStatus "@baseboard_fab2_lib.baseboard_fab2(sch_1):fm_cpu0_sm_wp" )
			)
			( signal "GND"
				( attribute "VOLTAGE" "0.0V"
					( Units "uVoltage" "V" 1.000000)
					( Status sAliasFlattened )
					( Status sAliasConflict )
					( Origin gFrontEnd )
				)
				( objectStatus "@baseboard_fab2_lib.baseboard_fab2(sch_1):gnd" )
			)
			( signal "BMC_VGA_VSYNC"
				( objectStatus "@baseboard_fab2_lib.baseboard_fab2(sch_1):bmc_vga_vsync" )
			)
			( signal "FM_ADR_SMI_GPIO_N"
				( objectStatus "@baseboard_fab2_lib.baseboard_fab2(sch_1):fm_adr_smi_gpio_n" )
			)
			( signal "IRQ_DIMM_SAVE_LVT3_N"
				( objectStatus "@baseboard_fab2_lib.baseboard_fab2(sch_1):irq_dimm_save_lvt3_n" )
			)
			( signal "H_CPU0_BMCINIT"
				( objectStatus "@baseboard_fab2_lib.baseboard_fab2(sch_1):h_cpu0_bmcinit" )
			)
			( signal "H_CPU0_CATERR_G_N"
				( objectStatus "@baseboard_fab2_lib.baseboard_fab2(sch_1):h_cpu0_caterr_g_n" )
			)
			( signal "H_CPU0_ERR0_G_N"
				( objectStatus "@baseboard_fab2_lib.baseboard_fab2(sch_1):h_cpu0_err0_g_n" )
			)
			( signal "H_CPU0_ERR1_G_N"
				( objectStatus "@baseboard_fab2_lib.baseboard_fab2(sch_1):h_cpu0_err1_g_n" )
			)
			( signal "H_CPU0_ERR2_G_N"
				( objectStatus "@baseboard_fab2_lib.baseboard_fab2(sch_1):h_cpu0_err2_g_n" )
			)
			( signal "H_CPU0_FAST_WAKE_N"
				( objectStatus "@baseboard_fab2_lib.baseboard_fab2(sch_1):h_cpu0_fast_wake_n" )
			)
			( signal "H_CPU0_MEMABC_MEMHOT_G_N"
				( objectStatus "@baseboard_fab2_lib.baseboard_fab2(sch_1):h_cpu0_memabc_memhot_g_n" )
			)
			( signal "H_CPU0_MEMDEF_MEMHOT_G_N"
				( objectStatus "@baseboard_fab2_lib.baseboard_fab2(sch_1):h_cpu0_memdef_memhot_g_n" )
			)
			( signal "H_CPU0_MSMI_G_N"
				( objectStatus "@baseboard_fab2_lib.baseboard_fab2(sch_1):h_cpu0_msmi_g_n" )
			)
			( signal "H_CPU0_PROCHOT_G_N"
				( objectStatus "@baseboard_fab2_lib.baseboard_fab2(sch_1):h_cpu0_prochot_g_n" )
			)
			( signal "H_CPU0_THERMTRIP_G_N"
				( objectStatus "@baseboard_fab2_lib.baseboard_fab2(sch_1):h_cpu0_thermtrip_g_n" )
			)
			( signal "H_PM_SYNC_GTL"
				( objectStatus "@baseboard_fab2_lib.baseboard_fab2(sch_1):h_pm_sync_gtl" )
			)
			( signal "H_PM_SYNC_GTL_R1"
				( objectStatus "@baseboard_fab2_lib.baseboard_fab2(sch_1):h_pm_sync_gtl_r1" )
			)
			( signal "H_PMSYNC_CLK_24M"
				( objectStatus "@baseboard_fab2_lib.baseboard_fab2(sch_1):h_pmsync_clk_24m" )
			)
			( signal "H_PMSYNC_CLK_24M_CPU0"
				( objectStatus "@baseboard_fab2_lib.baseboard_fab2(sch_1):h_pmsync_clk_24m_cpu0" )
			)
			( signal "M_A_CPU_VREF"
				( objectStatus "@baseboard_fab2_lib.baseboard_fab2(sch_1):m_a_cpu_vref" )
			)
			( signal "M_ABC_RST_N"
				( objectStatus "@baseboard_fab2_lib.baseboard_fab2(sch_1):m_abc_rst_n" )
			)
			( signal "M_B_CPU_VREF"
				( objectStatus "@baseboard_fab2_lib.baseboard_fab2(sch_1):m_b_cpu_vref" )
			)
			( signal "M_C_CPU_VREF"
				( objectStatus "@baseboard_fab2_lib.baseboard_fab2(sch_1):m_c_cpu_vref" )
			)
			( signal "M_D_CPU_VREF"
				( objectStatus "@baseboard_fab2_lib.baseboard_fab2(sch_1):m_d_cpu_vref" )
			)
			( signal "M_DEF_RST_N"
				( objectStatus "@baseboard_fab2_lib.baseboard_fab2(sch_1):m_def_rst_n" )
			)
			( signal "M_E_CPU_VREF"
				( objectStatus "@baseboard_fab2_lib.baseboard_fab2(sch_1):m_e_cpu_vref" )
			)
			( signal "M_F_CPU_VREF"
				( objectStatus "@baseboard_fab2_lib.baseboard_fab2(sch_1):m_f_cpu_vref" )
			)
			( signal "P3V3_STBY"
				( attribute "VOLTAGE" "3.3V"
					( Units "uVoltage" "V" 1.000000)
					( Status sAliasFlattened )
					( Status sAliasConflict )
					( Origin gFrontEnd )
				)
				( objectStatus "@baseboard_fab2_lib.baseboard_fab2(sch_1):p3v3_stby" )
			)
			( signal "RMII_BMC_OCP_TXD1_R"
				( objectStatus "@baseboard_fab2_lib.baseboard_fab2(sch_1):rmii_bmc_ocp_txd1_r" )
			)
			( signal "PD_CPU0_BIST_ENABLE"
				( objectStatus "@baseboard_fab2_lib.baseboard_fab2(sch_1):pd_cpu0_bist_enable" )
			)
			( signal "PD_CPU0_KSFC_DIS"
				( objectStatus "@baseboard_fab2_lib.baseboard_fab2(sch_1):pd_cpu0_ksfc_dis" )
			)
			( signal "PD_CPU0_TEST12"
				( objectStatus "@baseboard_fab2_lib.baseboard_fab2(sch_1):pd_cpu0_test12" )
			)
			( signal "PD_CPU0_TEST13"
				( objectStatus "@baseboard_fab2_lib.baseboard_fab2(sch_1):pd_cpu0_test13" )
			)
			( signal "PD_CPU0_TEST14"
				( objectStatus "@baseboard_fab2_lib.baseboard_fab2(sch_1):pd_cpu0_test14" )
			)
			( signal "PD_CPU0_TXT_PLTEN"
				( objectStatus "@baseboard_fab2_lib.baseboard_fab2(sch_1):pd_cpu0_txt_plten" )
			)
			( signal "PD_PIROM_CPU0_ADDR0"
				( objectStatus "@baseboard_fab2_lib.baseboard_fab2(sch_1):pd_pirom_cpu0_addr0" )
			)
			( signal "PD_PIROM_CPU0_ADDR1"
				( objectStatus "@baseboard_fab2_lib.baseboard_fab2(sch_1):pd_pirom_cpu0_addr1" )
			)
			( signal "PD_PIROM_CPU0_ADDR2"
				( objectStatus "@baseboard_fab2_lib.baseboard_fab2(sch_1):pd_pirom_cpu0_addr2" )
			)
			( signal "PECI_CPU_G"
				( objectStatus "@baseboard_fab2_lib.baseboard_fab2(sch_1):peci_cpu_g" )
			)
			( signal "PU_CPU0_FRMAGENT"
				( objectStatus "@baseboard_fab2_lib.baseboard_fab2(sch_1):pu_cpu0_frmagent" )
			)
			( signal "PU_CPU0_LEGACY_SKT"
				( objectStatus "@baseboard_fab2_lib.baseboard_fab2(sch_1):pu_cpu0_legacy_skt" )
			)
			( signal "PU_CPU0_SAFE_MODE_BOOT"
				( objectStatus "@baseboard_fab2_lib.baseboard_fab2(sch_1):pu_cpu0_safe_mode_boot" )
			)
			( signal "PU_CPU0_SOCKET_ID_0"
				( objectStatus "@baseboard_fab2_lib.baseboard_fab2(sch_1):pu_cpu0_socket_id_0" )
			)
			( signal "PU_CPU0_SOCKET_ID_1"
				( objectStatus "@baseboard_fab2_lib.baseboard_fab2(sch_1):pu_cpu0_socket_id_1" )
			)
			( signal "PU_CPU0_TSC_SYNC"
				( objectStatus "@baseboard_fab2_lib.baseboard_fab2(sch_1):pu_cpu0_tsc_sync" )
			)
			( signal "PU_CPU0_TXT_AGENT"
				( objectStatus "@baseboard_fab2_lib.baseboard_fab2(sch_1):pu_cpu0_txt_agent" )
			)
			( signal "PVCCIO_CPU0"
				( attribute "VOLTAGE" "1.1V"
					( Units "uVoltage" "V" 1.000000)
					( Status sAliasFlattened )
					( Origin gFrontEnd )
				)
				( objectStatus "@baseboard_fab2_lib.baseboard_fab2(sch_1):pvccio_cpu0" )
			)
			( signal "P1V15_AUX_BMC"
				( attribute "VOLTAGE" "1.5"
					( Units "uVoltage" "V" 1.000000)
					( Status sAliasFlattened )
					( Origin gFrontEnd )
				)
				( objectStatus "@baseboard_fab2_lib.baseboard_fab2(sch_1):p1v15_aux_bmc" )
			)
			( signal "PWRGD_CPU0_DRAMPWROK_ABC_G"
				( objectStatus "@baseboard_fab2_lib.baseboard_fab2(sch_1):pwrgd_cpu0_drampwrok_abc_g" )
			)
			( signal "PWRGD_CPU0_DRAMPWROK_DEF_G"
				( objectStatus "@baseboard_fab2_lib.baseboard_fab2(sch_1):pwrgd_cpu0_drampwrok_def_g" )
			)
			( signal "PWRGD_CPU0_G"
				( objectStatus "@baseboard_fab2_lib.baseboard_fab2(sch_1):pwrgd_cpu0_g" )
			)
			( signal "RST_CPU0_G_N"
				( objectStatus "@baseboard_fab2_lib.baseboard_fab2(sch_1):rst_cpu0_g_n" )
			)
			( signal "SMB_DDR_ABC_SCL_G_R"
				( objectStatus "@baseboard_fab2_lib.baseboard_fab2(sch_1):smb_ddr_abc_scl_g_r" )
			)
			( signal "SMB_DDR_ABC_SDA_G_R"
				( objectStatus "@baseboard_fab2_lib.baseboard_fab2(sch_1):smb_ddr_abc_sda_g_r" )
			)
			( signal "SMB_DDR_DEF_SCL_G_R"
				( objectStatus "@baseboard_fab2_lib.baseboard_fab2(sch_1):smb_ddr_def_scl_g_r" )
			)
			( signal "SMB_DDR_DEF_SDA_G_R"
				( objectStatus "@baseboard_fab2_lib.baseboard_fab2(sch_1):smb_ddr_def_sda_g_r" )
			)
			( signal "SMB_PIROM_CPU0_SCL"
				( objectStatus "@baseboard_fab2_lib.baseboard_fab2(sch_1):smb_pirom_cpu0_scl" )
			)
			( signal "SMB_PIROM_CPU0_SDA"
				( objectStatus "@baseboard_fab2_lib.baseboard_fab2(sch_1):smb_pirom_cpu0_sda" )
			)
			( signal "SVID_ALERT0_CPU0_N"
				( objectStatus "@baseboard_fab2_lib.baseboard_fab2(sch_1):svid_alert0_cpu0_n" )
			)
			( signal "SVID_ALERT0_CPU0_R_N"
				( objectStatus "@baseboard_fab2_lib.baseboard_fab2(sch_1):svid_alert0_cpu0_r_n" )
			)
			( signal "SVID_ALERT1_CPU0_N"
				( objectStatus "@baseboard_fab2_lib.baseboard_fab2(sch_1):svid_alert1_cpu0_n" )
			)
			( signal "SVID_ALERT1_CPU0_R_N"
				( objectStatus "@baseboard_fab2_lib.baseboard_fab2(sch_1):svid_alert1_cpu0_r_n" )
			)
			( signal "SVID_CLK0_CPU0"
				( objectStatus "@baseboard_fab2_lib.baseboard_fab2(sch_1):svid_clk0_cpu0" )
			)
			( signal "SVID_CLK0_CPU0_R"
				( objectStatus "@baseboard_fab2_lib.baseboard_fab2(sch_1):svid_clk0_cpu0_r" )
			)
			( signal "SVID_CLK1_CPU0"
				( objectStatus "@baseboard_fab2_lib.baseboard_fab2(sch_1):svid_clk1_cpu0" )
			)
			( signal "SVID_CLK1_CPU0_R"
				( objectStatus "@baseboard_fab2_lib.baseboard_fab2(sch_1):svid_clk1_cpu0_r" )
			)
			( signal "SVID_DIO0_CPU0"
				( objectStatus "@baseboard_fab2_lib.baseboard_fab2(sch_1):svid_dio0_cpu0" )
			)
			( signal "SVID_DIO0_CPU0_R"
				( objectStatus "@baseboard_fab2_lib.baseboard_fab2(sch_1):svid_dio0_cpu0_r" )
			)
			( signal "SVID_DIO1_CPU0"
				( objectStatus "@baseboard_fab2_lib.baseboard_fab2(sch_1):svid_dio1_cpu0" )
			)
			( signal "SVID_DIO1_CPU0_R"
				( objectStatus "@baseboard_fab2_lib.baseboard_fab2(sch_1):svid_dio1_cpu0_r" )
			)
			( signal "TP_CPU0_PROCDIS_G_N"
				( objectStatus "@baseboard_fab2_lib.baseboard_fab2(sch_1):tp_cpu0_procdis_g_n" )
			)
			( signal "TP_CPU0_SOCKET_ID_2"
				( objectStatus "@baseboard_fab2_lib.baseboard_fab2(sch_1):tp_cpu0_socket_id_2" )
			)
			( signal "TP_NMI_CPU0"
				( objectStatus "@baseboard_fab2_lib.baseboard_fab2(sch_1):tp_nmi_cpu0" )
			)
			( signal "TP_XDP_CPU0_OBSDATA_A0_MBP2_N"
				( objectStatus "@baseboard_fab2_lib.baseboard_fab2(sch_1):tp_xdp_cpu0_obsdata_a0_mbp2_n" )
			)
			( signal "TP_XDP_CPU0_OBSDATA_A1_MBP3_N"
				( objectStatus "@baseboard_fab2_lib.baseboard_fab2(sch_1):tp_xdp_cpu0_obsdata_a1_mbp3_n" )
			)
			( signal "TP_XDP_CPU0_OBSDATA_A2_MBP4_N"
				( objectStatus "@baseboard_fab2_lib.baseboard_fab2(sch_1):tp_xdp_cpu0_obsdata_a2_mbp4_n" )
			)
			( signal "TP_XDP_CPU0_OBSDATA_A3_MBP5_N"
				( objectStatus "@baseboard_fab2_lib.baseboard_fab2(sch_1):tp_xdp_cpu0_obsdata_a3_mbp5_n" )
			)
			( signal "XDP_CPU0_TDO"
				( objectStatus "@baseboard_fab2_lib.baseboard_fab2(sch_1):xdp_cpu0_tdo" )
			)
			( signal "XDP_CPU_MBP0_N"
				( objectStatus "@baseboard_fab2_lib.baseboard_fab2(sch_1):xdp_cpu_mbp0_n" )
			)
			( signal "XDP_CPU_MBP1_N"
				( objectStatus "@baseboard_fab2_lib.baseboard_fab2(sch_1):xdp_cpu_mbp1_n" )
			)
			( signal "XDP_CPU_OBSFN_B0_MBP6_N"
				( objectStatus "@baseboard_fab2_lib.baseboard_fab2(sch_1):xdp_cpu_obsfn_b0_mbp6_n" )
			)
			( signal "XDP_CPU_OBSFN_B1_MBP7_N"
				( objectStatus "@baseboard_fab2_lib.baseboard_fab2(sch_1):xdp_cpu_obsfn_b1_mbp7_n" )
			)
			( signal "XDP_CPU_PRDY_N"
				( objectStatus "@baseboard_fab2_lib.baseboard_fab2(sch_1):xdp_cpu_prdy_n" )
			)
			( signal "XDP_CPU_PREQ_N"
				( objectStatus "@baseboard_fab2_lib.baseboard_fab2(sch_1):xdp_cpu_preq_n" )
			)
			( signal "XDP_CPU_TCK0"
				( objectStatus "@baseboard_fab2_lib.baseboard_fab2(sch_1):xdp_cpu_tck0" )
			)
			( signal "XDP_CPU_TDI"
				( objectStatus "@baseboard_fab2_lib.baseboard_fab2(sch_1):xdp_cpu_tdi" )
			)
			( signal "XDP_CPU_TMS"
				( objectStatus "@baseboard_fab2_lib.baseboard_fab2(sch_1):xdp_cpu_tms" )
			)
			( signal "XDP_CPU_TRST_N"
				( objectStatus "@baseboard_fab2_lib.baseboard_fab2(sch_1):xdp_cpu_trst_n" )
			)
			( signal "CLK_100M_CPU0_RC_REFCLK0_DN"
				( objectStatus "@baseboard_fab2_lib.baseboard_fab2(sch_1):clk_100m_cpu0_rc_refclk0_dn" )
			)
			( signal "CLK_100M_CPU0_RC_REFCLK0_DP"
				( objectStatus "@baseboard_fab2_lib.baseboard_fab2(sch_1):clk_100m_cpu0_rc_refclk0_dp" )
			)
			( signal "CLK_322M_OSC_CPU0_RC_DN"
				( objectStatus "@baseboard_fab2_lib.baseboard_fab2(sch_1):clk_322m_osc_cpu0_rc_dn" )
			)
			( signal "CLK_322M_OSC_CPU0_RC_DP"
				( objectStatus "@baseboard_fab2_lib.baseboard_fab2(sch_1):clk_322m_osc_cpu0_rc_dp" )
			)
			( signal "FM_CPU0_RC_ERROR_N"
				( objectStatus "@baseboard_fab2_lib.baseboard_fab2(sch_1):fm_cpu0_rc_error_n" )
			)
			( signal "H_CPU0_FIVR_FAULT_G"
				( objectStatus "@baseboard_fab2_lib.baseboard_fab2(sch_1):h_cpu0_fivr_fault_g" )
			)
			( signal "P1V8_MCP_CPU0"
				( attribute "VOLTAGE" "+1.8V"
					( Units "uVoltage" "V" 1.000000)
					( Status sAliasFlattened )
					( Origin gFrontEnd )
				)
				( objectStatus "@baseboard_fab2_lib.baseboard_fab2(sch_1):p1v8_mcp_cpu0" )
			)
			( signal "PD_CPU0_DMIMODE_OVERRIDE"
				( objectStatus "@baseboard_fab2_lib.baseboard_fab2(sch_1):pd_cpu0_dmimode_override" )
			)
			( signal "PD_CPU0_RSVD_TEST_1"
				( objectStatus "@baseboard_fab2_lib.baseboard_fab2(sch_1):pd_cpu0_rsvd_test_1" )
			)
			( signal "PD_CPU0_RSVD_TEST_2"
				( objectStatus "@baseboard_fab2_lib.baseboard_fab2(sch_1):pd_cpu0_rsvd_test_2" )
			)
			( signal "PVCCMCP_CPU0"
				( attribute "VOLTAGE" "1.2V"
					( Units "uVoltage" "V" 1.000000)
					( Status sAliasFlattened )
					( Origin gFrontEnd )
				)
				( objectStatus "@baseboard_fab2_lib.baseboard_fab2(sch_1):pvccmcp_cpu0" )
			)
			( signal "TP_CPU0_RSVD_194"
				( objectStatus "@baseboard_fab2_lib.baseboard_fab2(sch_1):tp_cpu0_rsvd_194" )
			)
			( signal "TP_CPU0_RSVD_198"
				( objectStatus "@baseboard_fab2_lib.baseboard_fab2(sch_1):tp_cpu0_rsvd_198" )
			)
			( signal "TP_CPU0_RSVD_199"
				( objectStatus "@baseboard_fab2_lib.baseboard_fab2(sch_1):tp_cpu0_rsvd_199" )
			)
			( signal "TP_CPU0_RSVD_204"
				( objectStatus "@baseboard_fab2_lib.baseboard_fab2(sch_1):tp_cpu0_rsvd_204" )
			)
			( signal "TP_CPU0_RSVD_205"
				( objectStatus "@baseboard_fab2_lib.baseboard_fab2(sch_1):tp_cpu0_rsvd_205" )
			)
			( signal "TP_CPU0_RSVD_208"
				( objectStatus "@baseboard_fab2_lib.baseboard_fab2(sch_1):tp_cpu0_rsvd_208" )
			)
			( signal "TP_CPU0_RSVD_210"
				( objectStatus "@baseboard_fab2_lib.baseboard_fab2(sch_1):tp_cpu0_rsvd_210" )
			)
			( signal "TP_CPU0_RSVD_211"
				( objectStatus "@baseboard_fab2_lib.baseboard_fab2(sch_1):tp_cpu0_rsvd_211" )
			)
			( signal "TP_CPU0_RSVD_212"
				( objectStatus "@baseboard_fab2_lib.baseboard_fab2(sch_1):tp_cpu0_rsvd_212" )
			)
			( signal "TP_CPU0_RSVD_214"
				( objectStatus "@baseboard_fab2_lib.baseboard_fab2(sch_1):tp_cpu0_rsvd_214" )
			)
			( signal "TP_CPU0_RSVD_216"
				( objectStatus "@baseboard_fab2_lib.baseboard_fab2(sch_1):tp_cpu0_rsvd_216" )
			)
			( signal "TP_CPU0_RSVD_217"
				( objectStatus "@baseboard_fab2_lib.baseboard_fab2(sch_1):tp_cpu0_rsvd_217" )
			)
			( signal "TP_CPU0_RSVD_218"
				( objectStatus "@baseboard_fab2_lib.baseboard_fab2(sch_1):tp_cpu0_rsvd_218" )
			)
			( signal "TP_CPU0_RSVD_219"
				( objectStatus "@baseboard_fab2_lib.baseboard_fab2(sch_1):tp_cpu0_rsvd_219" )
			)
			( signal "TP_CPU0_RSVD_222"
				( objectStatus "@baseboard_fab2_lib.baseboard_fab2(sch_1):tp_cpu0_rsvd_222" )
			)
			( signal "TP_CPU0_RSVD_223"
				( objectStatus "@baseboard_fab2_lib.baseboard_fab2(sch_1):tp_cpu0_rsvd_223" )
			)
			( signal "TP_CPU0_RSVD_224"
				( objectStatus "@baseboard_fab2_lib.baseboard_fab2(sch_1):tp_cpu0_rsvd_224" )
			)
			( signal "TP_CPU0_RSVD_225"
				( objectStatus "@baseboard_fab2_lib.baseboard_fab2(sch_1):tp_cpu0_rsvd_225" )
			)
			( signal "TP_CPU0_RSVD_226"
				( objectStatus "@baseboard_fab2_lib.baseboard_fab2(sch_1):tp_cpu0_rsvd_226" )
			)
			( signal "TP_CPU0_RSVD_227"
				( objectStatus "@baseboard_fab2_lib.baseboard_fab2(sch_1):tp_cpu0_rsvd_227" )
			)
			( signal "TP_CPU0_RSVD_228"
				( objectStatus "@baseboard_fab2_lib.baseboard_fab2(sch_1):tp_cpu0_rsvd_228" )
			)
			( signal "TP_CPU0_RSVD_229"
				( objectStatus "@baseboard_fab2_lib.baseboard_fab2(sch_1):tp_cpu0_rsvd_229" )
			)
			( signal "TP_CPU0_RSVD_230"
				( objectStatus "@baseboard_fab2_lib.baseboard_fab2(sch_1):tp_cpu0_rsvd_230" )
			)
			( signal "TP_CPU0_RSVD_231"
				( objectStatus "@baseboard_fab2_lib.baseboard_fab2(sch_1):tp_cpu0_rsvd_231" )
			)
			( signal "TP_CPU0_RSVD_232"
				( objectStatus "@baseboard_fab2_lib.baseboard_fab2(sch_1):tp_cpu0_rsvd_232" )
			)
			( signal "TP_CPU0_RSVD_233"
				( objectStatus "@baseboard_fab2_lib.baseboard_fab2(sch_1):tp_cpu0_rsvd_233" )
			)
			( signal "TP_CPU0_RSVD_234"
				( objectStatus "@baseboard_fab2_lib.baseboard_fab2(sch_1):tp_cpu0_rsvd_234" )
			)
			( signal "TP_CPU0_RSVD_235"
				( objectStatus "@baseboard_fab2_lib.baseboard_fab2(sch_1):tp_cpu0_rsvd_235" )
			)
			( signal "TP_CPU0_RSVD_236"
				( objectStatus "@baseboard_fab2_lib.baseboard_fab2(sch_1):tp_cpu0_rsvd_236" )
			)
			( signal "TP_CPU0_RSVD_237"
				( objectStatus "@baseboard_fab2_lib.baseboard_fab2(sch_1):tp_cpu0_rsvd_237" )
			)
			( signal "TP_CPU0_RSVD_238"
				( objectStatus "@baseboard_fab2_lib.baseboard_fab2(sch_1):tp_cpu0_rsvd_238" )
			)
			( signal "TP_CPU0_RSVD_239"
				( objectStatus "@baseboard_fab2_lib.baseboard_fab2(sch_1):tp_cpu0_rsvd_239" )
			)
			( signal "TP_CPU0_RSVD_240"
				( objectStatus "@baseboard_fab2_lib.baseboard_fab2(sch_1):tp_cpu0_rsvd_240" )
			)
			( signal "TP_CPU0_RSVD_241"
				( objectStatus "@baseboard_fab2_lib.baseboard_fab2(sch_1):tp_cpu0_rsvd_241" )
			)
			( signal "TP_CPU0_RSVD_242"
				( objectStatus "@baseboard_fab2_lib.baseboard_fab2(sch_1):tp_cpu0_rsvd_242" )
			)
			( signal "TP_CPU0_RSVD_243"
				( objectStatus "@baseboard_fab2_lib.baseboard_fab2(sch_1):tp_cpu0_rsvd_243" )
			)
			( signal "TP_CPU0_RSVD_244"
				( objectStatus "@baseboard_fab2_lib.baseboard_fab2(sch_1):tp_cpu0_rsvd_244" )
			)
			( signal "TP_CPU0_RSVD_245"
				( objectStatus "@baseboard_fab2_lib.baseboard_fab2(sch_1):tp_cpu0_rsvd_245" )
			)
			( signal "TP_CPU0_RSVD_246"
				( objectStatus "@baseboard_fab2_lib.baseboard_fab2(sch_1):tp_cpu0_rsvd_246" )
			)
			( signal "TP_CPU0_RSVD_247"
				( objectStatus "@baseboard_fab2_lib.baseboard_fab2(sch_1):tp_cpu0_rsvd_247" )
			)
			( signal "TP_CPU0_RSVD_248"
				( objectStatus "@baseboard_fab2_lib.baseboard_fab2(sch_1):tp_cpu0_rsvd_248" )
			)
			( signal "TP_CPU0_RSVD_249"
				( objectStatus "@baseboard_fab2_lib.baseboard_fab2(sch_1):tp_cpu0_rsvd_249" )
			)
			( signal "TP_CPU0_RSVD_250"
				( objectStatus "@baseboard_fab2_lib.baseboard_fab2(sch_1):tp_cpu0_rsvd_250" )
			)
			( signal "TP_CPU0_RSVD_251"
				( objectStatus "@baseboard_fab2_lib.baseboard_fab2(sch_1):tp_cpu0_rsvd_251" )
			)
			( signal "TP_CPU0_RSVD_252"
				( objectStatus "@baseboard_fab2_lib.baseboard_fab2(sch_1):tp_cpu0_rsvd_252" )
			)
			( signal "TP_CPU0_RSVD_253"
				( objectStatus "@baseboard_fab2_lib.baseboard_fab2(sch_1):tp_cpu0_rsvd_253" )
			)
			( signal "TP_CPU0_RSVD_254"
				( objectStatus "@baseboard_fab2_lib.baseboard_fab2(sch_1):tp_cpu0_rsvd_254" )
			)
			( signal "TP_CPU0_RSVD_256"
				( objectStatus "@baseboard_fab2_lib.baseboard_fab2(sch_1):tp_cpu0_rsvd_256" )
			)
			( signal "TP_CPU0_RSVD_258"
				( objectStatus "@baseboard_fab2_lib.baseboard_fab2(sch_1):tp_cpu0_rsvd_258" )
			)
			( signal "TP_CPU0_RSVD_259"
				( objectStatus "@baseboard_fab2_lib.baseboard_fab2(sch_1):tp_cpu0_rsvd_259" )
			)
			( signal "TP_CPU0_RSVD_260"
				( objectStatus "@baseboard_fab2_lib.baseboard_fab2(sch_1):tp_cpu0_rsvd_260" )
			)
			( signal "TP_CPU0_RSVD_261"
				( objectStatus "@baseboard_fab2_lib.baseboard_fab2(sch_1):tp_cpu0_rsvd_261" )
			)
			( signal "TP_CPU0_RSVD_262"
				( objectStatus "@baseboard_fab2_lib.baseboard_fab2(sch_1):tp_cpu0_rsvd_262" )
			)
			( signal "TP_CPU0_RSVD_263"
				( objectStatus "@baseboard_fab2_lib.baseboard_fab2(sch_1):tp_cpu0_rsvd_263" )
			)
			( signal "TP_CPU0_RSVD_264"
				( objectStatus "@baseboard_fab2_lib.baseboard_fab2(sch_1):tp_cpu0_rsvd_264" )
			)
			( signal "TP_CPU0_RSVD_265"
				( objectStatus "@baseboard_fab2_lib.baseboard_fab2(sch_1):tp_cpu0_rsvd_265" )
			)
			( signal "TP_CPU0_RSVD_266"
				( objectStatus "@baseboard_fab2_lib.baseboard_fab2(sch_1):tp_cpu0_rsvd_266" )
			)
			( signal "TP_CPU0_RSVD_267"
				( objectStatus "@baseboard_fab2_lib.baseboard_fab2(sch_1):tp_cpu0_rsvd_267" )
			)
			( signal "TP_CPU0_RSVD_268"
				( objectStatus "@baseboard_fab2_lib.baseboard_fab2(sch_1):tp_cpu0_rsvd_268" )
			)
			( signal "TP_CPU0_RSVD_269"
				( objectStatus "@baseboard_fab2_lib.baseboard_fab2(sch_1):tp_cpu0_rsvd_269" )
			)
			( signal "TP_CPU0_RSVD_270"
				( objectStatus "@baseboard_fab2_lib.baseboard_fab2(sch_1):tp_cpu0_rsvd_270" )
			)
			( signal "TP_CPU0_RSVD_271"
				( objectStatus "@baseboard_fab2_lib.baseboard_fab2(sch_1):tp_cpu0_rsvd_271" )
			)
			( signal "TP_CPU0_RSVD_272"
				( objectStatus "@baseboard_fab2_lib.baseboard_fab2(sch_1):tp_cpu0_rsvd_272" )
			)
			( signal "TP_CPU0_RSVD_273"
				( objectStatus "@baseboard_fab2_lib.baseboard_fab2(sch_1):tp_cpu0_rsvd_273" )
			)
			( signal "TP_CPU0_RSVD_274"
				( objectStatus "@baseboard_fab2_lib.baseboard_fab2(sch_1):tp_cpu0_rsvd_274" )
			)
			( signal "TP_CPU0_RSVD_275"
				( objectStatus "@baseboard_fab2_lib.baseboard_fab2(sch_1):tp_cpu0_rsvd_275" )
			)
			( signal "TP_CPU0_RSVD_276"
				( objectStatus "@baseboard_fab2_lib.baseboard_fab2(sch_1):tp_cpu0_rsvd_276" )
			)
			( signal "TP_CPU0_RSVD_277"
				( objectStatus "@baseboard_fab2_lib.baseboard_fab2(sch_1):tp_cpu0_rsvd_277" )
			)
			( signal "TP_CPU0_RSVD_278"
				( objectStatus "@baseboard_fab2_lib.baseboard_fab2(sch_1):tp_cpu0_rsvd_278" )
			)
			( signal "TP_CPU0_RSVD_279"
				( objectStatus "@baseboard_fab2_lib.baseboard_fab2(sch_1):tp_cpu0_rsvd_279" )
			)
			( signal "TP_CPU0_RSVD_280"
				( objectStatus "@baseboard_fab2_lib.baseboard_fab2(sch_1):tp_cpu0_rsvd_280" )
			)
			( signal "TP_CPU0_RSVD_281"
				( objectStatus "@baseboard_fab2_lib.baseboard_fab2(sch_1):tp_cpu0_rsvd_281" )
			)
			( signal "TP_CPU0_RSVD_282"
				( objectStatus "@baseboard_fab2_lib.baseboard_fab2(sch_1):tp_cpu0_rsvd_282" )
			)
			( signal "TP_CPU0_RSVD_283"
				( objectStatus "@baseboard_fab2_lib.baseboard_fab2(sch_1):tp_cpu0_rsvd_283" )
			)
			( signal "TP_CPU0_RSVD_284"
				( objectStatus "@baseboard_fab2_lib.baseboard_fab2(sch_1):tp_cpu0_rsvd_284" )
			)
			( signal "TP_CPU0_RSVD_285"
				( objectStatus "@baseboard_fab2_lib.baseboard_fab2(sch_1):tp_cpu0_rsvd_285" )
			)
			( signal "TP_CPU0_RSVD_286"
				( objectStatus "@baseboard_fab2_lib.baseboard_fab2(sch_1):tp_cpu0_rsvd_286" )
			)
			( signal "TP_CPU0_RSVD_287"
				( objectStatus "@baseboard_fab2_lib.baseboard_fab2(sch_1):tp_cpu0_rsvd_287" )
			)
			( signal "TP_CPU0_RSVD_288"
				( objectStatus "@baseboard_fab2_lib.baseboard_fab2(sch_1):tp_cpu0_rsvd_288" )
			)
			( signal "TP_CPU0_RSVD_289"
				( objectStatus "@baseboard_fab2_lib.baseboard_fab2(sch_1):tp_cpu0_rsvd_289" )
			)
			( signal "TP_CPU0_RSVD_290"
				( objectStatus "@baseboard_fab2_lib.baseboard_fab2(sch_1):tp_cpu0_rsvd_290" )
			)
			( signal "TP_CPU0_RSVD_291"
				( objectStatus "@baseboard_fab2_lib.baseboard_fab2(sch_1):tp_cpu0_rsvd_291" )
			)
			( signal "TP_CPU0_RSVD_292"
				( objectStatus "@baseboard_fab2_lib.baseboard_fab2(sch_1):tp_cpu0_rsvd_292" )
			)
			( signal "TP_CPU0_RSVD_293"
				( objectStatus "@baseboard_fab2_lib.baseboard_fab2(sch_1):tp_cpu0_rsvd_293" )
			)
			( signal "TP_CPU0_RSVD_298"
				( objectStatus "@baseboard_fab2_lib.baseboard_fab2(sch_1):tp_cpu0_rsvd_298" )
			)
			( signal "TP_CPU0_RSVD_299"
				( objectStatus "@baseboard_fab2_lib.baseboard_fab2(sch_1):tp_cpu0_rsvd_299" )
			)
			( signal "TP_CPU0_RSVD_300"
				( objectStatus "@baseboard_fab2_lib.baseboard_fab2(sch_1):tp_cpu0_rsvd_300" )
			)
			( signal "TP_CPU0_RSVD_303"
				( objectStatus "@baseboard_fab2_lib.baseboard_fab2(sch_1):tp_cpu0_rsvd_303" )
			)
			( signal "TP_CPU0_RSVD_304"
				( objectStatus "@baseboard_fab2_lib.baseboard_fab2(sch_1):tp_cpu0_rsvd_304" )
			)
			( signal "TP_CPU0_RSVD_TEST_11"
				( objectStatus "@baseboard_fab2_lib.baseboard_fab2(sch_1):tp_cpu0_rsvd_test_11" )
			)
			( signal "TP_CPU0_RSVD_TEST_3"
				( objectStatus "@baseboard_fab2_lib.baseboard_fab2(sch_1):tp_cpu0_rsvd_test_3" )
			)
			( signal "TP_CPU0_RSVD_TEST_4"
				( objectStatus "@baseboard_fab2_lib.baseboard_fab2(sch_1):tp_cpu0_rsvd_test_4" )
			)
			( signal "TP_CPU0_RSVD_TEST_5"
				( objectStatus "@baseboard_fab2_lib.baseboard_fab2(sch_1):tp_cpu0_rsvd_test_5" )
			)
			( signal "VSENSE_P1V8MCP_CPU0_SKT_VRTN"
				( objectStatus "@baseboard_fab2_lib.baseboard_fab2(sch_1):vsense_p1v8mcp_cpu0_skt_vrtn" )
			)
			( signal "VSENSE_P1V8MCP_CPU0_SKT_VSEN"
				( objectStatus "@baseboard_fab2_lib.baseboard_fab2(sch_1):vsense_p1v8mcp_cpu0_skt_vsen" )
			)
			( signal "XDP_CPU_PWR_DEBUG_N"
				( objectStatus "@baseboard_fab2_lib.baseboard_fab2(sch_1):xdp_cpu_pwr_debug_n" )
			)
			( signal "XDP_PRESENT_N"
				( objectStatus "@baseboard_fab2_lib.baseboard_fab2(sch_1):xdp_present_n" )
			)
			( signal "M_A_ACT_N"
				( objectStatus "@baseboard_fab2_lib.baseboard_fab2(sch_1):m_a_act_n" )
			)
			( signal "M_A_ALERT_N"
				( objectStatus "@baseboard_fab2_lib.baseboard_fab2(sch_1):m_a_alert_n" )
			)
			( signal "M_A_BA<0>"
				( objectStatus "@baseboard_fab2_lib.baseboard_fab2(sch_1):m_a_ba(0)" )
			)
			( signal "M_A_BA<1>"
				( objectStatus "@baseboard_fab2_lib.baseboard_fab2(sch_1):m_a_ba(1)" )
			)
			( signal "M_A_BG<0>"
				( objectStatus "@baseboard_fab2_lib.baseboard_fab2(sch_1):m_a_bg(0)" )
			)
			( signal "M_A_BG<1>"
				( objectStatus "@baseboard_fab2_lib.baseboard_fab2(sch_1):m_a_bg(1)" )
			)
			( signal "M_A_C<2>"
				( objectStatus "@baseboard_fab2_lib.baseboard_fab2(sch_1):m_a_c(2)" )
			)
			( signal "M_A_CKE<0>"
				( objectStatus "@baseboard_fab2_lib.baseboard_fab2(sch_1):m_a_cke(0)" )
			)
			( signal "M_A_CKE<1>"
				( objectStatus "@baseboard_fab2_lib.baseboard_fab2(sch_1):m_a_cke(1)" )
			)
			( signal "M_A_CKE<2>"
				( objectStatus "@baseboard_fab2_lib.baseboard_fab2(sch_1):m_a_cke(2)" )
			)
			( signal "M_A_CKE<3>"
				( objectStatus "@baseboard_fab2_lib.baseboard_fab2(sch_1):m_a_cke(3)" )
			)
			( signal "M_A_CLK_DN<0>"
				( objectStatus "@baseboard_fab2_lib.baseboard_fab2(sch_1):m_a_clk_dn(0)" )
			)
			( signal "M_A_CLK_DN<1>"
				( objectStatus "@baseboard_fab2_lib.baseboard_fab2(sch_1):m_a_clk_dn(1)" )
			)
			( signal "M_A_CLK_DN<2>"
				( objectStatus "@baseboard_fab2_lib.baseboard_fab2(sch_1):m_a_clk_dn(2)" )
			)
			( signal "M_A_CLK_DN<3>"
				( objectStatus "@baseboard_fab2_lib.baseboard_fab2(sch_1):m_a_clk_dn(3)" )
			)
			( signal "M_A_CLK_DP<0>"
				( objectStatus "@baseboard_fab2_lib.baseboard_fab2(sch_1):m_a_clk_dp(0)" )
			)
			( signal "M_A_CLK_DP<1>"
				( objectStatus "@baseboard_fab2_lib.baseboard_fab2(sch_1):m_a_clk_dp(1)" )
			)
			( signal "M_A_CLK_DP<2>"
				( objectStatus "@baseboard_fab2_lib.baseboard_fab2(sch_1):m_a_clk_dp(2)" )
			)
			( signal "M_A_CLK_DP<3>"
				( objectStatus "@baseboard_fab2_lib.baseboard_fab2(sch_1):m_a_clk_dp(3)" )
			)
			( signal "M_A_CS_N<0>"
				( objectStatus "@baseboard_fab2_lib.baseboard_fab2(sch_1):m_a_cs_n(0)" )
			)
			( signal "M_A_CS_N<1>"
				( objectStatus "@baseboard_fab2_lib.baseboard_fab2(sch_1):m_a_cs_n(1)" )
			)
			( signal "M_A_CS_N<2>"
				( objectStatus "@baseboard_fab2_lib.baseboard_fab2(sch_1):m_a_cs_n(2)" )
			)
			( signal "M_A_CS_N<3>"
				( objectStatus "@baseboard_fab2_lib.baseboard_fab2(sch_1):m_a_cs_n(3)" )
			)
			( signal "M_A_CS_N<4>"
				( objectStatus "@baseboard_fab2_lib.baseboard_fab2(sch_1):m_a_cs_n(4)" )
			)
			( signal "M_A_CS_N<5>"
				( objectStatus "@baseboard_fab2_lib.baseboard_fab2(sch_1):m_a_cs_n(5)" )
			)
			( signal "M_A_CS_N<6>"
				( objectStatus "@baseboard_fab2_lib.baseboard_fab2(sch_1):m_a_cs_n(6)" )
			)
			( signal "M_A_CS_N<7>"
				( objectStatus "@baseboard_fab2_lib.baseboard_fab2(sch_1):m_a_cs_n(7)" )
			)
			( signal "M_A_DQ<0>"
				( objectStatus "@baseboard_fab2_lib.baseboard_fab2(sch_1):m_a_dq(0)" )
			)
			( signal "M_A_DQ<1>"
				( objectStatus "@baseboard_fab2_lib.baseboard_fab2(sch_1):m_a_dq(1)" )
			)
			( signal "M_A_DQ<2>"
				( objectStatus "@baseboard_fab2_lib.baseboard_fab2(sch_1):m_a_dq(2)" )
			)
			( signal "M_A_DQ<3>"
				( objectStatus "@baseboard_fab2_lib.baseboard_fab2(sch_1):m_a_dq(3)" )
			)
			( signal "M_A_DQ<4>"
				( objectStatus "@baseboard_fab2_lib.baseboard_fab2(sch_1):m_a_dq(4)" )
			)
			( signal "M_A_DQ<5>"
				( objectStatus "@baseboard_fab2_lib.baseboard_fab2(sch_1):m_a_dq(5)" )
			)
			( signal "M_A_DQ<6>"
				( objectStatus "@baseboard_fab2_lib.baseboard_fab2(sch_1):m_a_dq(6)" )
			)
			( signal "M_A_DQ<7>"
				( objectStatus "@baseboard_fab2_lib.baseboard_fab2(sch_1):m_a_dq(7)" )
			)
			( signal "M_A_DQ<8>"
				( objectStatus "@baseboard_fab2_lib.baseboard_fab2(sch_1):m_a_dq(8)" )
			)
			( signal "M_A_DQ<9>"
				( objectStatus "@baseboard_fab2_lib.baseboard_fab2(sch_1):m_a_dq(9)" )
			)
			( signal "M_A_DQ<10>"
				( objectStatus "@baseboard_fab2_lib.baseboard_fab2(sch_1):m_a_dq(10)" )
			)
			( signal "M_A_DQ<11>"
				( objectStatus "@baseboard_fab2_lib.baseboard_fab2(sch_1):m_a_dq(11)" )
			)
			( signal "M_A_DQ<12>"
				( objectStatus "@baseboard_fab2_lib.baseboard_fab2(sch_1):m_a_dq(12)" )
			)
			( signal "M_A_DQ<13>"
				( objectStatus "@baseboard_fab2_lib.baseboard_fab2(sch_1):m_a_dq(13)" )
			)
			( signal "M_A_DQ<14>"
				( objectStatus "@baseboard_fab2_lib.baseboard_fab2(sch_1):m_a_dq(14)" )
			)
			( signal "M_A_DQ<15>"
				( objectStatus "@baseboard_fab2_lib.baseboard_fab2(sch_1):m_a_dq(15)" )
			)
			( signal "M_A_DQ<16>"
				( objectStatus "@baseboard_fab2_lib.baseboard_fab2(sch_1):m_a_dq(16)" )
			)
			( signal "M_A_DQ<17>"
				( objectStatus "@baseboard_fab2_lib.baseboard_fab2(sch_1):m_a_dq(17)" )
			)
			( signal "M_A_DQ<18>"
				( objectStatus "@baseboard_fab2_lib.baseboard_fab2(sch_1):m_a_dq(18)" )
			)
			( signal "M_A_DQ<19>"
				( objectStatus "@baseboard_fab2_lib.baseboard_fab2(sch_1):m_a_dq(19)" )
			)
			( signal "M_A_DQ<20>"
				( objectStatus "@baseboard_fab2_lib.baseboard_fab2(sch_1):m_a_dq(20)" )
			)
			( signal "M_A_DQ<21>"
				( objectStatus "@baseboard_fab2_lib.baseboard_fab2(sch_1):m_a_dq(21)" )
			)
			( signal "M_A_DQ<22>"
				( objectStatus "@baseboard_fab2_lib.baseboard_fab2(sch_1):m_a_dq(22)" )
			)
			( signal "M_A_DQ<23>"
				( objectStatus "@baseboard_fab2_lib.baseboard_fab2(sch_1):m_a_dq(23)" )
			)
			( signal "M_A_DQ<24>"
				( objectStatus "@baseboard_fab2_lib.baseboard_fab2(sch_1):m_a_dq(24)" )
			)
			( signal "M_A_DQ<25>"
				( objectStatus "@baseboard_fab2_lib.baseboard_fab2(sch_1):m_a_dq(25)" )
			)
			( signal "M_A_DQ<26>"
				( objectStatus "@baseboard_fab2_lib.baseboard_fab2(sch_1):m_a_dq(26)" )
			)
			( signal "M_A_DQ<27>"
				( objectStatus "@baseboard_fab2_lib.baseboard_fab2(sch_1):m_a_dq(27)" )
			)
			( signal "M_A_DQ<28>"
				( objectStatus "@baseboard_fab2_lib.baseboard_fab2(sch_1):m_a_dq(28)" )
			)
			( signal "M_A_DQ<29>"
				( objectStatus "@baseboard_fab2_lib.baseboard_fab2(sch_1):m_a_dq(29)" )
			)
			( signal "M_A_DQ<30>"
				( objectStatus "@baseboard_fab2_lib.baseboard_fab2(sch_1):m_a_dq(30)" )
			)
			( signal "M_A_DQ<31>"
				( objectStatus "@baseboard_fab2_lib.baseboard_fab2(sch_1):m_a_dq(31)" )
			)
			( signal "M_A_DQ<32>"
				( objectStatus "@baseboard_fab2_lib.baseboard_fab2(sch_1):m_a_dq(32)" )
			)
			( signal "M_A_DQ<33>"
				( objectStatus "@baseboard_fab2_lib.baseboard_fab2(sch_1):m_a_dq(33)" )
			)
			( signal "M_A_DQ<34>"
				( objectStatus "@baseboard_fab2_lib.baseboard_fab2(sch_1):m_a_dq(34)" )
			)
			( signal "M_A_DQ<35>"
				( objectStatus "@baseboard_fab2_lib.baseboard_fab2(sch_1):m_a_dq(35)" )
			)
			( signal "M_A_DQ<36>"
				( objectStatus "@baseboard_fab2_lib.baseboard_fab2(sch_1):m_a_dq(36)" )
			)
			( signal "M_A_DQ<37>"
				( objectStatus "@baseboard_fab2_lib.baseboard_fab2(sch_1):m_a_dq(37)" )
			)
			( signal "M_A_DQ<38>"
				( objectStatus "@baseboard_fab2_lib.baseboard_fab2(sch_1):m_a_dq(38)" )
			)
			( signal "M_A_DQ<39>"
				( objectStatus "@baseboard_fab2_lib.baseboard_fab2(sch_1):m_a_dq(39)" )
			)
			( signal "M_A_DQ<40>"
				( objectStatus "@baseboard_fab2_lib.baseboard_fab2(sch_1):m_a_dq(40)" )
			)
			( signal "M_A_DQ<41>"
				( objectStatus "@baseboard_fab2_lib.baseboard_fab2(sch_1):m_a_dq(41)" )
			)
			( signal "M_A_DQ<42>"
				( objectStatus "@baseboard_fab2_lib.baseboard_fab2(sch_1):m_a_dq(42)" )
			)
			( signal "M_A_DQ<43>"
				( objectStatus "@baseboard_fab2_lib.baseboard_fab2(sch_1):m_a_dq(43)" )
			)
			( signal "M_A_DQ<44>"
				( objectStatus "@baseboard_fab2_lib.baseboard_fab2(sch_1):m_a_dq(44)" )
			)
			( signal "M_A_DQ<45>"
				( objectStatus "@baseboard_fab2_lib.baseboard_fab2(sch_1):m_a_dq(45)" )
			)
			( signal "M_A_DQ<46>"
				( objectStatus "@baseboard_fab2_lib.baseboard_fab2(sch_1):m_a_dq(46)" )
			)
			( signal "M_A_DQ<47>"
				( objectStatus "@baseboard_fab2_lib.baseboard_fab2(sch_1):m_a_dq(47)" )
			)
			( signal "M_A_DQ<48>"
				( objectStatus "@baseboard_fab2_lib.baseboard_fab2(sch_1):m_a_dq(48)" )
			)
			( signal "M_A_DQ<49>"
				( objectStatus "@baseboard_fab2_lib.baseboard_fab2(sch_1):m_a_dq(49)" )
			)
			( signal "M_A_DQ<50>"
				( objectStatus "@baseboard_fab2_lib.baseboard_fab2(sch_1):m_a_dq(50)" )
			)
			( signal "M_A_DQ<51>"
				( objectStatus "@baseboard_fab2_lib.baseboard_fab2(sch_1):m_a_dq(51)" )
			)
			( signal "M_A_DQ<52>"
				( objectStatus "@baseboard_fab2_lib.baseboard_fab2(sch_1):m_a_dq(52)" )
			)
			( signal "M_A_DQ<53>"
				( objectStatus "@baseboard_fab2_lib.baseboard_fab2(sch_1):m_a_dq(53)" )
			)
			( signal "M_A_DQ<54>"
				( objectStatus "@baseboard_fab2_lib.baseboard_fab2(sch_1):m_a_dq(54)" )
			)
			( signal "M_A_DQ<55>"
				( objectStatus "@baseboard_fab2_lib.baseboard_fab2(sch_1):m_a_dq(55)" )
			)
			( signal "M_A_DQ<56>"
				( objectStatus "@baseboard_fab2_lib.baseboard_fab2(sch_1):m_a_dq(56)" )
			)
			( signal "M_A_DQ<57>"
				( objectStatus "@baseboard_fab2_lib.baseboard_fab2(sch_1):m_a_dq(57)" )
			)
			( signal "M_A_DQ<58>"
				( objectStatus "@baseboard_fab2_lib.baseboard_fab2(sch_1):m_a_dq(58)" )
			)
			( signal "M_A_DQ<59>"
				( objectStatus "@baseboard_fab2_lib.baseboard_fab2(sch_1):m_a_dq(59)" )
			)
			( signal "M_A_DQ<60>"
				( objectStatus "@baseboard_fab2_lib.baseboard_fab2(sch_1):m_a_dq(60)" )
			)
			( signal "M_A_DQ<61>"
				( objectStatus "@baseboard_fab2_lib.baseboard_fab2(sch_1):m_a_dq(61)" )
			)
			( signal "M_A_DQ<62>"
				( objectStatus "@baseboard_fab2_lib.baseboard_fab2(sch_1):m_a_dq(62)" )
			)
			( signal "M_A_DQ<63>"
				( objectStatus "@baseboard_fab2_lib.baseboard_fab2(sch_1):m_a_dq(63)" )
			)
			( signal "M_A_DQS_DN<0>"
				( objectStatus "@baseboard_fab2_lib.baseboard_fab2(sch_1):m_a_dqs_dn(0)" )
			)
			( signal "M_A_DQS_DN<1>"
				( objectStatus "@baseboard_fab2_lib.baseboard_fab2(sch_1):m_a_dqs_dn(1)" )
			)
			( signal "M_A_DQS_DN<2>"
				( objectStatus "@baseboard_fab2_lib.baseboard_fab2(sch_1):m_a_dqs_dn(2)" )
			)
			( signal "M_A_DQS_DN<3>"
				( objectStatus "@baseboard_fab2_lib.baseboard_fab2(sch_1):m_a_dqs_dn(3)" )
			)
			( signal "M_A_DQS_DN<4>"
				( objectStatus "@baseboard_fab2_lib.baseboard_fab2(sch_1):m_a_dqs_dn(4)" )
			)
			( signal "M_A_DQS_DN<5>"
				( objectStatus "@baseboard_fab2_lib.baseboard_fab2(sch_1):m_a_dqs_dn(5)" )
			)
			( signal "M_A_DQS_DN<6>"
				( objectStatus "@baseboard_fab2_lib.baseboard_fab2(sch_1):m_a_dqs_dn(6)" )
			)
			( signal "M_A_DQS_DN<7>"
				( objectStatus "@baseboard_fab2_lib.baseboard_fab2(sch_1):m_a_dqs_dn(7)" )
			)
			( signal "M_A_DQS_DN<8>"
				( objectStatus "@baseboard_fab2_lib.baseboard_fab2(sch_1):m_a_dqs_dn(8)" )
			)
			( signal "M_A_DQS_DN<9>"
				( objectStatus "@baseboard_fab2_lib.baseboard_fab2(sch_1):m_a_dqs_dn(9)" )
			)
			( signal "M_A_DQS_DN<10>"
				( objectStatus "@baseboard_fab2_lib.baseboard_fab2(sch_1):m_a_dqs_dn(10)" )
			)
			( signal "M_A_DQS_DN<11>"
				( objectStatus "@baseboard_fab2_lib.baseboard_fab2(sch_1):m_a_dqs_dn(11)" )
			)
			( signal "M_A_DQS_DN<12>"
				( objectStatus "@baseboard_fab2_lib.baseboard_fab2(sch_1):m_a_dqs_dn(12)" )
			)
			( signal "M_A_DQS_DN<13>"
				( objectStatus "@baseboard_fab2_lib.baseboard_fab2(sch_1):m_a_dqs_dn(13)" )
			)
			( signal "M_A_DQS_DN<14>"
				( objectStatus "@baseboard_fab2_lib.baseboard_fab2(sch_1):m_a_dqs_dn(14)" )
			)
			( signal "M_A_DQS_DN<15>"
				( objectStatus "@baseboard_fab2_lib.baseboard_fab2(sch_1):m_a_dqs_dn(15)" )
			)
			( signal "M_A_DQS_DN<16>"
				( objectStatus "@baseboard_fab2_lib.baseboard_fab2(sch_1):m_a_dqs_dn(16)" )
			)
			( signal "M_A_DQS_DN<17>"
				( objectStatus "@baseboard_fab2_lib.baseboard_fab2(sch_1):m_a_dqs_dn(17)" )
			)
			( signal "M_A_DQS_DP<0>"
				( objectStatus "@baseboard_fab2_lib.baseboard_fab2(sch_1):m_a_dqs_dp(0)" )
			)
			( signal "M_A_DQS_DP<1>"
				( objectStatus "@baseboard_fab2_lib.baseboard_fab2(sch_1):m_a_dqs_dp(1)" )
			)
			( signal "M_A_DQS_DP<2>"
				( objectStatus "@baseboard_fab2_lib.baseboard_fab2(sch_1):m_a_dqs_dp(2)" )
			)
			( signal "M_A_DQS_DP<3>"
				( objectStatus "@baseboard_fab2_lib.baseboard_fab2(sch_1):m_a_dqs_dp(3)" )
			)
			( signal "M_A_DQS_DP<4>"
				( objectStatus "@baseboard_fab2_lib.baseboard_fab2(sch_1):m_a_dqs_dp(4)" )
			)
			( signal "M_A_DQS_DP<5>"
				( objectStatus "@baseboard_fab2_lib.baseboard_fab2(sch_1):m_a_dqs_dp(5)" )
			)
			( signal "M_A_DQS_DP<6>"
				( objectStatus "@baseboard_fab2_lib.baseboard_fab2(sch_1):m_a_dqs_dp(6)" )
			)
			( signal "M_A_DQS_DP<7>"
				( objectStatus "@baseboard_fab2_lib.baseboard_fab2(sch_1):m_a_dqs_dp(7)" )
			)
			( signal "M_A_DQS_DP<8>"
				( objectStatus "@baseboard_fab2_lib.baseboard_fab2(sch_1):m_a_dqs_dp(8)" )
			)
			( signal "M_A_DQS_DP<9>"
				( objectStatus "@baseboard_fab2_lib.baseboard_fab2(sch_1):m_a_dqs_dp(9)" )
			)
			( signal "M_A_DQS_DP<10>"
				( objectStatus "@baseboard_fab2_lib.baseboard_fab2(sch_1):m_a_dqs_dp(10)" )
			)
			( signal "M_A_DQS_DP<11>"
				( objectStatus "@baseboard_fab2_lib.baseboard_fab2(sch_1):m_a_dqs_dp(11)" )
			)
			( signal "M_A_DQS_DP<12>"
				( objectStatus "@baseboard_fab2_lib.baseboard_fab2(sch_1):m_a_dqs_dp(12)" )
			)
			( signal "M_A_DQS_DP<13>"
				( objectStatus "@baseboard_fab2_lib.baseboard_fab2(sch_1):m_a_dqs_dp(13)" )
			)
			( signal "M_A_DQS_DP<14>"
				( objectStatus "@baseboard_fab2_lib.baseboard_fab2(sch_1):m_a_dqs_dp(14)" )
			)
			( signal "M_A_DQS_DP<15>"
				( objectStatus "@baseboard_fab2_lib.baseboard_fab2(sch_1):m_a_dqs_dp(15)" )
			)
			( signal "M_A_DQS_DP<16>"
				( objectStatus "@baseboard_fab2_lib.baseboard_fab2(sch_1):m_a_dqs_dp(16)" )
			)
			( signal "M_A_DQS_DP<17>"
				( objectStatus "@baseboard_fab2_lib.baseboard_fab2(sch_1):m_a_dqs_dp(17)" )
			)
			( signal "M_A_ECC<0>"
				( objectStatus "@baseboard_fab2_lib.baseboard_fab2(sch_1):m_a_ecc(0)" )
			)
			( signal "M_A_ECC<1>"
				( objectStatus "@baseboard_fab2_lib.baseboard_fab2(sch_1):m_a_ecc(1)" )
			)
			( signal "M_A_ECC<2>"
				( objectStatus "@baseboard_fab2_lib.baseboard_fab2(sch_1):m_a_ecc(2)" )
			)
			( signal "M_A_ECC<3>"
				( objectStatus "@baseboard_fab2_lib.baseboard_fab2(sch_1):m_a_ecc(3)" )
			)
			( signal "M_A_ECC<4>"
				( objectStatus "@baseboard_fab2_lib.baseboard_fab2(sch_1):m_a_ecc(4)" )
			)
			( signal "M_A_ECC<5>"
				( objectStatus "@baseboard_fab2_lib.baseboard_fab2(sch_1):m_a_ecc(5)" )
			)
			( signal "M_A_ECC<6>"
				( objectStatus "@baseboard_fab2_lib.baseboard_fab2(sch_1):m_a_ecc(6)" )
			)
			( signal "M_A_ECC<7>"
				( objectStatus "@baseboard_fab2_lib.baseboard_fab2(sch_1):m_a_ecc(7)" )
			)
			( signal "M_A_MA<0>"
				( objectStatus "@baseboard_fab2_lib.baseboard_fab2(sch_1):m_a_ma(0)" )
			)
			( signal "M_A_MA<1>"
				( objectStatus "@baseboard_fab2_lib.baseboard_fab2(sch_1):m_a_ma(1)" )
			)
			( signal "M_A_MA<2>"
				( objectStatus "@baseboard_fab2_lib.baseboard_fab2(sch_1):m_a_ma(2)" )
			)
			( signal "M_A_MA<3>"
				( objectStatus "@baseboard_fab2_lib.baseboard_fab2(sch_1):m_a_ma(3)" )
			)
			( signal "M_A_MA<4>"
				( objectStatus "@baseboard_fab2_lib.baseboard_fab2(sch_1):m_a_ma(4)" )
			)
			( signal "M_A_MA<5>"
				( objectStatus "@baseboard_fab2_lib.baseboard_fab2(sch_1):m_a_ma(5)" )
			)
			( signal "M_A_MA<6>"
				( objectStatus "@baseboard_fab2_lib.baseboard_fab2(sch_1):m_a_ma(6)" )
			)
			( signal "M_A_MA<7>"
				( objectStatus "@baseboard_fab2_lib.baseboard_fab2(sch_1):m_a_ma(7)" )
			)
			( signal "M_A_MA<8>"
				( objectStatus "@baseboard_fab2_lib.baseboard_fab2(sch_1):m_a_ma(8)" )
			)
			( signal "M_A_MA<9>"
				( objectStatus "@baseboard_fab2_lib.baseboard_fab2(sch_1):m_a_ma(9)" )
			)
			( signal "M_A_MA<10>"
				( objectStatus "@baseboard_fab2_lib.baseboard_fab2(sch_1):m_a_ma(10)" )
			)
			( signal "M_A_MA<11>"
				( objectStatus "@baseboard_fab2_lib.baseboard_fab2(sch_1):m_a_ma(11)" )
			)
			( signal "M_A_MA<12>"
				( objectStatus "@baseboard_fab2_lib.baseboard_fab2(sch_1):m_a_ma(12)" )
			)
			( signal "M_A_MA<13>"
				( objectStatus "@baseboard_fab2_lib.baseboard_fab2(sch_1):m_a_ma(13)" )
			)
			( signal "M_A_MA<14>"
				( objectStatus "@baseboard_fab2_lib.baseboard_fab2(sch_1):m_a_ma(14)" )
			)
			( signal "M_A_MA<15>"
				( objectStatus "@baseboard_fab2_lib.baseboard_fab2(sch_1):m_a_ma(15)" )
			)
			( signal "M_A_MA<16>"
				( objectStatus "@baseboard_fab2_lib.baseboard_fab2(sch_1):m_a_ma(16)" )
			)
			( signal "M_A_MA<17>"
				( objectStatus "@baseboard_fab2_lib.baseboard_fab2(sch_1):m_a_ma(17)" )
			)
			( signal "M_A_ODT<0>"
				( objectStatus "@baseboard_fab2_lib.baseboard_fab2(sch_1):m_a_odt(0)" )
			)
			( signal "M_A_ODT<1>"
				( objectStatus "@baseboard_fab2_lib.baseboard_fab2(sch_1):m_a_odt(1)" )
			)
			( signal "M_A_ODT<2>"
				( objectStatus "@baseboard_fab2_lib.baseboard_fab2(sch_1):m_a_odt(2)" )
			)
			( signal "M_A_ODT<3>"
				( objectStatus "@baseboard_fab2_lib.baseboard_fab2(sch_1):m_a_odt(3)" )
			)
			( signal "M_A_PAR"
				( objectStatus "@baseboard_fab2_lib.baseboard_fab2(sch_1):m_a_par" )
			)
			( signal "M_B_ACT_N"
				( objectStatus "@baseboard_fab2_lib.baseboard_fab2(sch_1):m_b_act_n" )
			)
			( signal "M_B_ALERT_N"
				( objectStatus "@baseboard_fab2_lib.baseboard_fab2(sch_1):m_b_alert_n" )
			)
			( signal "M_B_BA<0>"
				( objectStatus "@baseboard_fab2_lib.baseboard_fab2(sch_1):m_b_ba(0)" )
			)
			( signal "M_B_BA<1>"
				( objectStatus "@baseboard_fab2_lib.baseboard_fab2(sch_1):m_b_ba(1)" )
			)
			( signal "M_B_BG<0>"
				( objectStatus "@baseboard_fab2_lib.baseboard_fab2(sch_1):m_b_bg(0)" )
			)
			( signal "M_B_BG<1>"
				( objectStatus "@baseboard_fab2_lib.baseboard_fab2(sch_1):m_b_bg(1)" )
			)
			( signal "M_B_C<2>"
				( objectStatus "@baseboard_fab2_lib.baseboard_fab2(sch_1):m_b_c(2)" )
			)
			( signal "M_B_CKE<0>"
				( objectStatus "@baseboard_fab2_lib.baseboard_fab2(sch_1):m_b_cke(0)" )
			)
			( signal "M_B_CKE<1>"
				( objectStatus "@baseboard_fab2_lib.baseboard_fab2(sch_1):m_b_cke(1)" )
			)
			( signal "M_B_CKE<2>"
				( objectStatus "@baseboard_fab2_lib.baseboard_fab2(sch_1):m_b_cke(2)" )
			)
			( signal "M_B_CKE<3>"
				( objectStatus "@baseboard_fab2_lib.baseboard_fab2(sch_1):m_b_cke(3)" )
			)
			( signal "M_B_CLK_DN<0>"
				( objectStatus "@baseboard_fab2_lib.baseboard_fab2(sch_1):m_b_clk_dn(0)" )
			)
			( signal "M_B_CLK_DN<1>"
				( objectStatus "@baseboard_fab2_lib.baseboard_fab2(sch_1):m_b_clk_dn(1)" )
			)
			( signal "M_B_CLK_DN<2>"
				( objectStatus "@baseboard_fab2_lib.baseboard_fab2(sch_1):m_b_clk_dn(2)" )
			)
			( signal "M_B_CLK_DN<3>"
				( objectStatus "@baseboard_fab2_lib.baseboard_fab2(sch_1):m_b_clk_dn(3)" )
			)
			( signal "M_B_CLK_DP<0>"
				( objectStatus "@baseboard_fab2_lib.baseboard_fab2(sch_1):m_b_clk_dp(0)" )
			)
			( signal "M_B_CLK_DP<1>"
				( objectStatus "@baseboard_fab2_lib.baseboard_fab2(sch_1):m_b_clk_dp(1)" )
			)
			( signal "M_B_CLK_DP<2>"
				( objectStatus "@baseboard_fab2_lib.baseboard_fab2(sch_1):m_b_clk_dp(2)" )
			)
			( signal "M_B_CLK_DP<3>"
				( objectStatus "@baseboard_fab2_lib.baseboard_fab2(sch_1):m_b_clk_dp(3)" )
			)
			( signal "M_B_CS_N<0>"
				( objectStatus "@baseboard_fab2_lib.baseboard_fab2(sch_1):m_b_cs_n(0)" )
			)
			( signal "M_B_CS_N<1>"
				( objectStatus "@baseboard_fab2_lib.baseboard_fab2(sch_1):m_b_cs_n(1)" )
			)
			( signal "M_B_CS_N<2>"
				( objectStatus "@baseboard_fab2_lib.baseboard_fab2(sch_1):m_b_cs_n(2)" )
			)
			( signal "M_B_CS_N<3>"
				( objectStatus "@baseboard_fab2_lib.baseboard_fab2(sch_1):m_b_cs_n(3)" )
			)
			( signal "M_B_CS_N<4>"
				( objectStatus "@baseboard_fab2_lib.baseboard_fab2(sch_1):m_b_cs_n(4)" )
			)
			( signal "M_B_CS_N<5>"
				( objectStatus "@baseboard_fab2_lib.baseboard_fab2(sch_1):m_b_cs_n(5)" )
			)
			( signal "M_B_CS_N<6>"
				( objectStatus "@baseboard_fab2_lib.baseboard_fab2(sch_1):m_b_cs_n(6)" )
			)
			( signal "M_B_CS_N<7>"
				( objectStatus "@baseboard_fab2_lib.baseboard_fab2(sch_1):m_b_cs_n(7)" )
			)
			( signal "M_B_DQ<0>"
				( objectStatus "@baseboard_fab2_lib.baseboard_fab2(sch_1):m_b_dq(0)" )
			)
			( signal "M_B_DQ<1>"
				( objectStatus "@baseboard_fab2_lib.baseboard_fab2(sch_1):m_b_dq(1)" )
			)
			( signal "M_B_DQ<2>"
				( objectStatus "@baseboard_fab2_lib.baseboard_fab2(sch_1):m_b_dq(2)" )
			)
			( signal "M_B_DQ<3>"
				( objectStatus "@baseboard_fab2_lib.baseboard_fab2(sch_1):m_b_dq(3)" )
			)
			( signal "M_B_DQ<4>"
				( objectStatus "@baseboard_fab2_lib.baseboard_fab2(sch_1):m_b_dq(4)" )
			)
			( signal "M_B_DQ<5>"
				( objectStatus "@baseboard_fab2_lib.baseboard_fab2(sch_1):m_b_dq(5)" )
			)
			( signal "M_B_DQ<6>"
				( objectStatus "@baseboard_fab2_lib.baseboard_fab2(sch_1):m_b_dq(6)" )
			)
			( signal "M_B_DQ<7>"
				( objectStatus "@baseboard_fab2_lib.baseboard_fab2(sch_1):m_b_dq(7)" )
			)
			( signal "M_B_DQ<8>"
				( objectStatus "@baseboard_fab2_lib.baseboard_fab2(sch_1):m_b_dq(8)" )
			)
			( signal "M_B_DQ<9>"
				( objectStatus "@baseboard_fab2_lib.baseboard_fab2(sch_1):m_b_dq(9)" )
			)
			( signal "M_B_DQ<10>"
				( objectStatus "@baseboard_fab2_lib.baseboard_fab2(sch_1):m_b_dq(10)" )
			)
			( signal "M_B_DQ<11>"
				( objectStatus "@baseboard_fab2_lib.baseboard_fab2(sch_1):m_b_dq(11)" )
			)
			( signal "M_B_DQ<12>"
				( objectStatus "@baseboard_fab2_lib.baseboard_fab2(sch_1):m_b_dq(12)" )
			)
			( signal "M_B_DQ<13>"
				( objectStatus "@baseboard_fab2_lib.baseboard_fab2(sch_1):m_b_dq(13)" )
			)
			( signal "M_B_DQ<14>"
				( objectStatus "@baseboard_fab2_lib.baseboard_fab2(sch_1):m_b_dq(14)" )
			)
			( signal "M_B_DQ<15>"
				( objectStatus "@baseboard_fab2_lib.baseboard_fab2(sch_1):m_b_dq(15)" )
			)
			( signal "M_B_DQ<16>"
				( objectStatus "@baseboard_fab2_lib.baseboard_fab2(sch_1):m_b_dq(16)" )
			)
			( signal "M_B_DQ<17>"
				( objectStatus "@baseboard_fab2_lib.baseboard_fab2(sch_1):m_b_dq(17)" )
			)
			( signal "M_B_DQ<18>"
				( objectStatus "@baseboard_fab2_lib.baseboard_fab2(sch_1):m_b_dq(18)" )
			)
			( signal "M_B_DQ<19>"
				( objectStatus "@baseboard_fab2_lib.baseboard_fab2(sch_1):m_b_dq(19)" )
			)
			( signal "M_B_DQ<20>"
				( objectStatus "@baseboard_fab2_lib.baseboard_fab2(sch_1):m_b_dq(20)" )
			)
			( signal "M_B_DQ<21>"
				( objectStatus "@baseboard_fab2_lib.baseboard_fab2(sch_1):m_b_dq(21)" )
			)
			( signal "M_B_DQ<22>"
				( objectStatus "@baseboard_fab2_lib.baseboard_fab2(sch_1):m_b_dq(22)" )
			)
			( signal "M_B_DQ<23>"
				( objectStatus "@baseboard_fab2_lib.baseboard_fab2(sch_1):m_b_dq(23)" )
			)
			( signal "M_B_DQ<24>"
				( objectStatus "@baseboard_fab2_lib.baseboard_fab2(sch_1):m_b_dq(24)" )
			)
			( signal "M_B_DQ<25>"
				( objectStatus "@baseboard_fab2_lib.baseboard_fab2(sch_1):m_b_dq(25)" )
			)
			( signal "M_B_DQ<26>"
				( objectStatus "@baseboard_fab2_lib.baseboard_fab2(sch_1):m_b_dq(26)" )
			)
			( signal "M_B_DQ<27>"
				( objectStatus "@baseboard_fab2_lib.baseboard_fab2(sch_1):m_b_dq(27)" )
			)
			( signal "M_B_DQ<28>"
				( objectStatus "@baseboard_fab2_lib.baseboard_fab2(sch_1):m_b_dq(28)" )
			)
			( signal "M_B_DQ<29>"
				( objectStatus "@baseboard_fab2_lib.baseboard_fab2(sch_1):m_b_dq(29)" )
			)
			( signal "M_B_DQ<30>"
				( objectStatus "@baseboard_fab2_lib.baseboard_fab2(sch_1):m_b_dq(30)" )
			)
			( signal "M_B_DQ<31>"
				( objectStatus "@baseboard_fab2_lib.baseboard_fab2(sch_1):m_b_dq(31)" )
			)
			( signal "M_B_DQ<32>"
				( objectStatus "@baseboard_fab2_lib.baseboard_fab2(sch_1):m_b_dq(32)" )
			)
			( signal "M_B_DQ<33>"
				( objectStatus "@baseboard_fab2_lib.baseboard_fab2(sch_1):m_b_dq(33)" )
			)
			( signal "M_B_DQ<34>"
				( objectStatus "@baseboard_fab2_lib.baseboard_fab2(sch_1):m_b_dq(34)" )
			)
			( signal "M_B_DQ<35>"
				( objectStatus "@baseboard_fab2_lib.baseboard_fab2(sch_1):m_b_dq(35)" )
			)
			( signal "M_B_DQ<36>"
				( objectStatus "@baseboard_fab2_lib.baseboard_fab2(sch_1):m_b_dq(36)" )
			)
			( signal "M_B_DQ<37>"
				( objectStatus "@baseboard_fab2_lib.baseboard_fab2(sch_1):m_b_dq(37)" )
			)
			( signal "M_B_DQ<38>"
				( objectStatus "@baseboard_fab2_lib.baseboard_fab2(sch_1):m_b_dq(38)" )
			)
			( signal "M_B_DQ<39>"
				( objectStatus "@baseboard_fab2_lib.baseboard_fab2(sch_1):m_b_dq(39)" )
			)
			( signal "M_B_DQ<40>"
				( objectStatus "@baseboard_fab2_lib.baseboard_fab2(sch_1):m_b_dq(40)" )
			)
			( signal "M_B_DQ<41>"
				( objectStatus "@baseboard_fab2_lib.baseboard_fab2(sch_1):m_b_dq(41)" )
			)
			( signal "M_B_DQ<42>"
				( objectStatus "@baseboard_fab2_lib.baseboard_fab2(sch_1):m_b_dq(42)" )
			)
			( signal "M_B_DQ<43>"
				( objectStatus "@baseboard_fab2_lib.baseboard_fab2(sch_1):m_b_dq(43)" )
			)
			( signal "M_B_DQ<44>"
				( objectStatus "@baseboard_fab2_lib.baseboard_fab2(sch_1):m_b_dq(44)" )
			)
			( signal "M_B_DQ<45>"
				( objectStatus "@baseboard_fab2_lib.baseboard_fab2(sch_1):m_b_dq(45)" )
			)
			( signal "M_B_DQ<46>"
				( objectStatus "@baseboard_fab2_lib.baseboard_fab2(sch_1):m_b_dq(46)" )
			)
			( signal "M_B_DQ<47>"
				( objectStatus "@baseboard_fab2_lib.baseboard_fab2(sch_1):m_b_dq(47)" )
			)
			( signal "M_B_DQ<48>"
				( objectStatus "@baseboard_fab2_lib.baseboard_fab2(sch_1):m_b_dq(48)" )
			)
			( signal "M_B_DQ<49>"
				( objectStatus "@baseboard_fab2_lib.baseboard_fab2(sch_1):m_b_dq(49)" )
			)
			( signal "M_B_DQ<50>"
				( objectStatus "@baseboard_fab2_lib.baseboard_fab2(sch_1):m_b_dq(50)" )
			)
			( signal "M_B_DQ<51>"
				( objectStatus "@baseboard_fab2_lib.baseboard_fab2(sch_1):m_b_dq(51)" )
			)
			( signal "M_B_DQ<52>"
				( objectStatus "@baseboard_fab2_lib.baseboard_fab2(sch_1):m_b_dq(52)" )
			)
			( signal "M_B_DQ<53>"
				( objectStatus "@baseboard_fab2_lib.baseboard_fab2(sch_1):m_b_dq(53)" )
			)
			( signal "M_B_DQ<54>"
				( objectStatus "@baseboard_fab2_lib.baseboard_fab2(sch_1):m_b_dq(54)" )
			)
			( signal "M_B_DQ<55>"
				( objectStatus "@baseboard_fab2_lib.baseboard_fab2(sch_1):m_b_dq(55)" )
			)
			( signal "M_B_DQ<56>"
				( objectStatus "@baseboard_fab2_lib.baseboard_fab2(sch_1):m_b_dq(56)" )
			)
			( signal "M_B_DQ<57>"
				( objectStatus "@baseboard_fab2_lib.baseboard_fab2(sch_1):m_b_dq(57)" )
			)
			( signal "M_B_DQ<58>"
				( objectStatus "@baseboard_fab2_lib.baseboard_fab2(sch_1):m_b_dq(58)" )
			)
			( signal "M_B_DQ<59>"
				( objectStatus "@baseboard_fab2_lib.baseboard_fab2(sch_1):m_b_dq(59)" )
			)
			( signal "M_B_DQ<60>"
				( objectStatus "@baseboard_fab2_lib.baseboard_fab2(sch_1):m_b_dq(60)" )
			)
			( signal "M_B_DQ<61>"
				( objectStatus "@baseboard_fab2_lib.baseboard_fab2(sch_1):m_b_dq(61)" )
			)
			( signal "M_B_DQ<62>"
				( objectStatus "@baseboard_fab2_lib.baseboard_fab2(sch_1):m_b_dq(62)" )
			)
			( signal "M_B_DQ<63>"
				( objectStatus "@baseboard_fab2_lib.baseboard_fab2(sch_1):m_b_dq(63)" )
			)
			( signal "M_B_DQS_DN<0>"
				( objectStatus "@baseboard_fab2_lib.baseboard_fab2(sch_1):m_b_dqs_dn(0)" )
			)
			( signal "M_B_DQS_DN<1>"
				( objectStatus "@baseboard_fab2_lib.baseboard_fab2(sch_1):m_b_dqs_dn(1)" )
			)
			( signal "M_B_DQS_DN<2>"
				( objectStatus "@baseboard_fab2_lib.baseboard_fab2(sch_1):m_b_dqs_dn(2)" )
			)
			( signal "M_B_DQS_DN<3>"
				( objectStatus "@baseboard_fab2_lib.baseboard_fab2(sch_1):m_b_dqs_dn(3)" )
			)
			( signal "M_B_DQS_DN<4>"
				( objectStatus "@baseboard_fab2_lib.baseboard_fab2(sch_1):m_b_dqs_dn(4)" )
			)
			( signal "M_B_DQS_DN<5>"
				( objectStatus "@baseboard_fab2_lib.baseboard_fab2(sch_1):m_b_dqs_dn(5)" )
			)
			( signal "M_B_DQS_DN<6>"
				( objectStatus "@baseboard_fab2_lib.baseboard_fab2(sch_1):m_b_dqs_dn(6)" )
			)
			( signal "M_B_DQS_DN<7>"
				( objectStatus "@baseboard_fab2_lib.baseboard_fab2(sch_1):m_b_dqs_dn(7)" )
			)
			( signal "M_B_DQS_DN<8>"
				( objectStatus "@baseboard_fab2_lib.baseboard_fab2(sch_1):m_b_dqs_dn(8)" )
			)
			( signal "M_B_DQS_DN<9>"
				( objectStatus "@baseboard_fab2_lib.baseboard_fab2(sch_1):m_b_dqs_dn(9)" )
			)
			( signal "M_B_DQS_DN<10>"
				( objectStatus "@baseboard_fab2_lib.baseboard_fab2(sch_1):m_b_dqs_dn(10)" )
			)
			( signal "M_B_DQS_DN<11>"
				( objectStatus "@baseboard_fab2_lib.baseboard_fab2(sch_1):m_b_dqs_dn(11)" )
			)
			( signal "M_B_DQS_DN<12>"
				( objectStatus "@baseboard_fab2_lib.baseboard_fab2(sch_1):m_b_dqs_dn(12)" )
			)
			( signal "M_B_DQS_DN<13>"
				( objectStatus "@baseboard_fab2_lib.baseboard_fab2(sch_1):m_b_dqs_dn(13)" )
			)
			( signal "M_B_DQS_DN<14>"
				( objectStatus "@baseboard_fab2_lib.baseboard_fab2(sch_1):m_b_dqs_dn(14)" )
			)
			( signal "M_B_DQS_DN<15>"
				( objectStatus "@baseboard_fab2_lib.baseboard_fab2(sch_1):m_b_dqs_dn(15)" )
			)
			( signal "M_B_DQS_DN<16>"
				( objectStatus "@baseboard_fab2_lib.baseboard_fab2(sch_1):m_b_dqs_dn(16)" )
			)
			( signal "M_B_DQS_DN<17>"
				( objectStatus "@baseboard_fab2_lib.baseboard_fab2(sch_1):m_b_dqs_dn(17)" )
			)
			( signal "M_B_DQS_DP<0>"
				( objectStatus "@baseboard_fab2_lib.baseboard_fab2(sch_1):m_b_dqs_dp(0)" )
			)
			( signal "M_B_DQS_DP<1>"
				( objectStatus "@baseboard_fab2_lib.baseboard_fab2(sch_1):m_b_dqs_dp(1)" )
			)
			( signal "M_B_DQS_DP<2>"
				( objectStatus "@baseboard_fab2_lib.baseboard_fab2(sch_1):m_b_dqs_dp(2)" )
			)
			( signal "M_B_DQS_DP<3>"
				( objectStatus "@baseboard_fab2_lib.baseboard_fab2(sch_1):m_b_dqs_dp(3)" )
			)
			( signal "M_B_DQS_DP<4>"
				( objectStatus "@baseboard_fab2_lib.baseboard_fab2(sch_1):m_b_dqs_dp(4)" )
			)
			( signal "M_B_DQS_DP<5>"
				( objectStatus "@baseboard_fab2_lib.baseboard_fab2(sch_1):m_b_dqs_dp(5)" )
			)
			( signal "M_B_DQS_DP<6>"
				( objectStatus "@baseboard_fab2_lib.baseboard_fab2(sch_1):m_b_dqs_dp(6)" )
			)
			( signal "M_B_DQS_DP<7>"
				( objectStatus "@baseboard_fab2_lib.baseboard_fab2(sch_1):m_b_dqs_dp(7)" )
			)
			( signal "M_B_DQS_DP<8>"
				( objectStatus "@baseboard_fab2_lib.baseboard_fab2(sch_1):m_b_dqs_dp(8)" )
			)
			( signal "M_B_DQS_DP<9>"
				( objectStatus "@baseboard_fab2_lib.baseboard_fab2(sch_1):m_b_dqs_dp(9)" )
			)
			( signal "M_B_DQS_DP<10>"
				( objectStatus "@baseboard_fab2_lib.baseboard_fab2(sch_1):m_b_dqs_dp(10)" )
			)
			( signal "M_B_DQS_DP<11>"
				( objectStatus "@baseboard_fab2_lib.baseboard_fab2(sch_1):m_b_dqs_dp(11)" )
			)
			( signal "M_B_DQS_DP<12>"
				( objectStatus "@baseboard_fab2_lib.baseboard_fab2(sch_1):m_b_dqs_dp(12)" )
			)
			( signal "M_B_DQS_DP<13>"
				( objectStatus "@baseboard_fab2_lib.baseboard_fab2(sch_1):m_b_dqs_dp(13)" )
			)
			( signal "M_B_DQS_DP<14>"
				( objectStatus "@baseboard_fab2_lib.baseboard_fab2(sch_1):m_b_dqs_dp(14)" )
			)
			( signal "M_B_DQS_DP<15>"
				( objectStatus "@baseboard_fab2_lib.baseboard_fab2(sch_1):m_b_dqs_dp(15)" )
			)
			( signal "M_B_DQS_DP<16>"
				( objectStatus "@baseboard_fab2_lib.baseboard_fab2(sch_1):m_b_dqs_dp(16)" )
			)
			( signal "M_B_DQS_DP<17>"
				( objectStatus "@baseboard_fab2_lib.baseboard_fab2(sch_1):m_b_dqs_dp(17)" )
			)
			( signal "M_B_ECC<0>"
				( objectStatus "@baseboard_fab2_lib.baseboard_fab2(sch_1):m_b_ecc(0)" )
			)
			( signal "M_B_ECC<1>"
				( objectStatus "@baseboard_fab2_lib.baseboard_fab2(sch_1):m_b_ecc(1)" )
			)
			( signal "M_B_ECC<2>"
				( objectStatus "@baseboard_fab2_lib.baseboard_fab2(sch_1):m_b_ecc(2)" )
			)
			( signal "M_B_ECC<3>"
				( objectStatus "@baseboard_fab2_lib.baseboard_fab2(sch_1):m_b_ecc(3)" )
			)
			( signal "M_B_ECC<4>"
				( objectStatus "@baseboard_fab2_lib.baseboard_fab2(sch_1):m_b_ecc(4)" )
			)
			( signal "M_B_ECC<5>"
				( objectStatus "@baseboard_fab2_lib.baseboard_fab2(sch_1):m_b_ecc(5)" )
			)
			( signal "M_B_ECC<6>"
				( objectStatus "@baseboard_fab2_lib.baseboard_fab2(sch_1):m_b_ecc(6)" )
			)
			( signal "M_B_ECC<7>"
				( objectStatus "@baseboard_fab2_lib.baseboard_fab2(sch_1):m_b_ecc(7)" )
			)
			( signal "M_B_MA<0>"
				( objectStatus "@baseboard_fab2_lib.baseboard_fab2(sch_1):m_b_ma(0)" )
			)
			( signal "M_B_MA<1>"
				( objectStatus "@baseboard_fab2_lib.baseboard_fab2(sch_1):m_b_ma(1)" )
			)
			( signal "M_B_MA<2>"
				( objectStatus "@baseboard_fab2_lib.baseboard_fab2(sch_1):m_b_ma(2)" )
			)
			( signal "M_B_MA<3>"
				( objectStatus "@baseboard_fab2_lib.baseboard_fab2(sch_1):m_b_ma(3)" )
			)
			( signal "M_B_MA<4>"
				( objectStatus "@baseboard_fab2_lib.baseboard_fab2(sch_1):m_b_ma(4)" )
			)
			( signal "M_B_MA<5>"
				( objectStatus "@baseboard_fab2_lib.baseboard_fab2(sch_1):m_b_ma(5)" )
			)
			( signal "M_B_MA<6>"
				( objectStatus "@baseboard_fab2_lib.baseboard_fab2(sch_1):m_b_ma(6)" )
			)
			( signal "M_B_MA<7>"
				( objectStatus "@baseboard_fab2_lib.baseboard_fab2(sch_1):m_b_ma(7)" )
			)
			( signal "M_B_MA<8>"
				( objectStatus "@baseboard_fab2_lib.baseboard_fab2(sch_1):m_b_ma(8)" )
			)
			( signal "M_B_MA<9>"
				( objectStatus "@baseboard_fab2_lib.baseboard_fab2(sch_1):m_b_ma(9)" )
			)
			( signal "M_B_MA<10>"
				( objectStatus "@baseboard_fab2_lib.baseboard_fab2(sch_1):m_b_ma(10)" )
			)
			( signal "M_B_MA<11>"
				( objectStatus "@baseboard_fab2_lib.baseboard_fab2(sch_1):m_b_ma(11)" )
			)
			( signal "M_B_MA<12>"
				( objectStatus "@baseboard_fab2_lib.baseboard_fab2(sch_1):m_b_ma(12)" )
			)
			( signal "M_B_MA<13>"
				( objectStatus "@baseboard_fab2_lib.baseboard_fab2(sch_1):m_b_ma(13)" )
			)
			( signal "M_B_MA<14>"
				( objectStatus "@baseboard_fab2_lib.baseboard_fab2(sch_1):m_b_ma(14)" )
			)
			( signal "M_B_MA<15>"
				( objectStatus "@baseboard_fab2_lib.baseboard_fab2(sch_1):m_b_ma(15)" )
			)
			( signal "M_B_MA<16>"
				( objectStatus "@baseboard_fab2_lib.baseboard_fab2(sch_1):m_b_ma(16)" )
			)
			( signal "M_B_MA<17>"
				( objectStatus "@baseboard_fab2_lib.baseboard_fab2(sch_1):m_b_ma(17)" )
			)
			( signal "M_B_ODT<0>"
				( objectStatus "@baseboard_fab2_lib.baseboard_fab2(sch_1):m_b_odt(0)" )
			)
			( signal "M_B_ODT<1>"
				( objectStatus "@baseboard_fab2_lib.baseboard_fab2(sch_1):m_b_odt(1)" )
			)
			( signal "M_B_ODT<2>"
				( objectStatus "@baseboard_fab2_lib.baseboard_fab2(sch_1):m_b_odt(2)" )
			)
			( signal "M_B_ODT<3>"
				( objectStatus "@baseboard_fab2_lib.baseboard_fab2(sch_1):m_b_odt(3)" )
			)
			( signal "M_B_PAR"
				( objectStatus "@baseboard_fab2_lib.baseboard_fab2(sch_1):m_b_par" )
			)
			( signal "M_C_ACT_N"
				( objectStatus "@baseboard_fab2_lib.baseboard_fab2(sch_1):m_c_act_n" )
			)
			( signal "M_C_ALERT_N"
				( objectStatus "@baseboard_fab2_lib.baseboard_fab2(sch_1):m_c_alert_n" )
			)
			( signal "M_C_BA<0>"
				( objectStatus "@baseboard_fab2_lib.baseboard_fab2(sch_1):m_c_ba(0)" )
			)
			( signal "M_C_BA<1>"
				( objectStatus "@baseboard_fab2_lib.baseboard_fab2(sch_1):m_c_ba(1)" )
			)
			( signal "M_C_BG<0>"
				( objectStatus "@baseboard_fab2_lib.baseboard_fab2(sch_1):m_c_bg(0)" )
			)
			( signal "M_C_BG<1>"
				( objectStatus "@baseboard_fab2_lib.baseboard_fab2(sch_1):m_c_bg(1)" )
			)
			( signal "M_C_C<2>"
				( objectStatus "@baseboard_fab2_lib.baseboard_fab2(sch_1):m_c_c(2)" )
			)
			( signal "M_C_CKE<0>"
				( objectStatus "@baseboard_fab2_lib.baseboard_fab2(sch_1):m_c_cke(0)" )
			)
			( signal "M_C_CKE<1>"
				( objectStatus "@baseboard_fab2_lib.baseboard_fab2(sch_1):m_c_cke(1)" )
			)
			( signal "M_C_CKE<2>"
				( objectStatus "@baseboard_fab2_lib.baseboard_fab2(sch_1):m_c_cke(2)" )
			)
			( signal "M_C_CKE<3>"
				( objectStatus "@baseboard_fab2_lib.baseboard_fab2(sch_1):m_c_cke(3)" )
			)
			( signal "M_C_CLK_DN<0>"
				( objectStatus "@baseboard_fab2_lib.baseboard_fab2(sch_1):m_c_clk_dn(0)" )
			)
			( signal "M_C_CLK_DN<1>"
				( objectStatus "@baseboard_fab2_lib.baseboard_fab2(sch_1):m_c_clk_dn(1)" )
			)
			( signal "M_C_CLK_DN<2>"
				( objectStatus "@baseboard_fab2_lib.baseboard_fab2(sch_1):m_c_clk_dn(2)" )
			)
			( signal "M_C_CLK_DN<3>"
				( objectStatus "@baseboard_fab2_lib.baseboard_fab2(sch_1):m_c_clk_dn(3)" )
			)
			( signal "M_C_CLK_DP<0>"
				( objectStatus "@baseboard_fab2_lib.baseboard_fab2(sch_1):m_c_clk_dp(0)" )
			)
			( signal "M_C_CLK_DP<1>"
				( objectStatus "@baseboard_fab2_lib.baseboard_fab2(sch_1):m_c_clk_dp(1)" )
			)
			( signal "M_C_CLK_DP<2>"
				( objectStatus "@baseboard_fab2_lib.baseboard_fab2(sch_1):m_c_clk_dp(2)" )
			)
			( signal "M_C_CLK_DP<3>"
				( objectStatus "@baseboard_fab2_lib.baseboard_fab2(sch_1):m_c_clk_dp(3)" )
			)
			( signal "M_C_CS_N<0>"
				( objectStatus "@baseboard_fab2_lib.baseboard_fab2(sch_1):m_c_cs_n(0)" )
			)
			( signal "M_C_CS_N<1>"
				( objectStatus "@baseboard_fab2_lib.baseboard_fab2(sch_1):m_c_cs_n(1)" )
			)
			( signal "M_C_CS_N<2>"
				( objectStatus "@baseboard_fab2_lib.baseboard_fab2(sch_1):m_c_cs_n(2)" )
			)
			( signal "M_C_CS_N<3>"
				( objectStatus "@baseboard_fab2_lib.baseboard_fab2(sch_1):m_c_cs_n(3)" )
			)
			( signal "M_C_CS_N<4>"
				( objectStatus "@baseboard_fab2_lib.baseboard_fab2(sch_1):m_c_cs_n(4)" )
			)
			( signal "M_C_CS_N<5>"
				( objectStatus "@baseboard_fab2_lib.baseboard_fab2(sch_1):m_c_cs_n(5)" )
			)
			( signal "M_C_CS_N<6>"
				( objectStatus "@baseboard_fab2_lib.baseboard_fab2(sch_1):m_c_cs_n(6)" )
			)
			( signal "M_C_CS_N<7>"
				( objectStatus "@baseboard_fab2_lib.baseboard_fab2(sch_1):m_c_cs_n(7)" )
			)
			( signal "M_C_DQ<0>"
				( objectStatus "@baseboard_fab2_lib.baseboard_fab2(sch_1):m_c_dq(0)" )
			)
			( signal "M_C_DQ<1>"
				( objectStatus "@baseboard_fab2_lib.baseboard_fab2(sch_1):m_c_dq(1)" )
			)
			( signal "M_C_DQ<2>"
				( objectStatus "@baseboard_fab2_lib.baseboard_fab2(sch_1):m_c_dq(2)" )
			)
			( signal "M_C_DQ<3>"
				( objectStatus "@baseboard_fab2_lib.baseboard_fab2(sch_1):m_c_dq(3)" )
			)
			( signal "M_C_DQ<4>"
				( objectStatus "@baseboard_fab2_lib.baseboard_fab2(sch_1):m_c_dq(4)" )
			)
			( signal "M_C_DQ<5>"
				( objectStatus "@baseboard_fab2_lib.baseboard_fab2(sch_1):m_c_dq(5)" )
			)
			( signal "M_C_DQ<6>"
				( objectStatus "@baseboard_fab2_lib.baseboard_fab2(sch_1):m_c_dq(6)" )
			)
			( signal "M_C_DQ<7>"
				( objectStatus "@baseboard_fab2_lib.baseboard_fab2(sch_1):m_c_dq(7)" )
			)
			( signal "M_C_DQ<8>"
				( objectStatus "@baseboard_fab2_lib.baseboard_fab2(sch_1):m_c_dq(8)" )
			)
			( signal "M_C_DQ<9>"
				( objectStatus "@baseboard_fab2_lib.baseboard_fab2(sch_1):m_c_dq(9)" )
			)
			( signal "M_C_DQ<10>"
				( objectStatus "@baseboard_fab2_lib.baseboard_fab2(sch_1):m_c_dq(10)" )
			)
			( signal "M_C_DQ<11>"
				( objectStatus "@baseboard_fab2_lib.baseboard_fab2(sch_1):m_c_dq(11)" )
			)
			( signal "M_C_DQ<12>"
				( objectStatus "@baseboard_fab2_lib.baseboard_fab2(sch_1):m_c_dq(12)" )
			)
			( signal "M_C_DQ<13>"
				( objectStatus "@baseboard_fab2_lib.baseboard_fab2(sch_1):m_c_dq(13)" )
			)
			( signal "M_C_DQ<14>"
				( objectStatus "@baseboard_fab2_lib.baseboard_fab2(sch_1):m_c_dq(14)" )
			)
			( signal "M_C_DQ<15>"
				( objectStatus "@baseboard_fab2_lib.baseboard_fab2(sch_1):m_c_dq(15)" )
			)
			( signal "M_C_DQ<16>"
				( objectStatus "@baseboard_fab2_lib.baseboard_fab2(sch_1):m_c_dq(16)" )
			)
			( signal "M_C_DQ<17>"
				( objectStatus "@baseboard_fab2_lib.baseboard_fab2(sch_1):m_c_dq(17)" )
			)
			( signal "M_C_DQ<18>"
				( objectStatus "@baseboard_fab2_lib.baseboard_fab2(sch_1):m_c_dq(18)" )
			)
			( signal "M_C_DQ<19>"
				( objectStatus "@baseboard_fab2_lib.baseboard_fab2(sch_1):m_c_dq(19)" )
			)
			( signal "M_C_DQ<20>"
				( objectStatus "@baseboard_fab2_lib.baseboard_fab2(sch_1):m_c_dq(20)" )
			)
			( signal "M_C_DQ<21>"
				( objectStatus "@baseboard_fab2_lib.baseboard_fab2(sch_1):m_c_dq(21)" )
			)
			( signal "M_C_DQ<22>"
				( objectStatus "@baseboard_fab2_lib.baseboard_fab2(sch_1):m_c_dq(22)" )
			)
			( signal "M_C_DQ<23>"
				( objectStatus "@baseboard_fab2_lib.baseboard_fab2(sch_1):m_c_dq(23)" )
			)
			( signal "M_C_DQ<24>"
				( objectStatus "@baseboard_fab2_lib.baseboard_fab2(sch_1):m_c_dq(24)" )
			)
			( signal "M_C_DQ<25>"
				( objectStatus "@baseboard_fab2_lib.baseboard_fab2(sch_1):m_c_dq(25)" )
			)
			( signal "M_C_DQ<26>"
				( objectStatus "@baseboard_fab2_lib.baseboard_fab2(sch_1):m_c_dq(26)" )
			)
			( signal "M_C_DQ<27>"
				( objectStatus "@baseboard_fab2_lib.baseboard_fab2(sch_1):m_c_dq(27)" )
			)
			( signal "M_C_DQ<28>"
				( objectStatus "@baseboard_fab2_lib.baseboard_fab2(sch_1):m_c_dq(28)" )
			)
			( signal "M_C_DQ<29>"
				( objectStatus "@baseboard_fab2_lib.baseboard_fab2(sch_1):m_c_dq(29)" )
			)
			( signal "M_C_DQ<30>"
				( objectStatus "@baseboard_fab2_lib.baseboard_fab2(sch_1):m_c_dq(30)" )
			)
			( signal "M_C_DQ<31>"
				( objectStatus "@baseboard_fab2_lib.baseboard_fab2(sch_1):m_c_dq(31)" )
			)
			( signal "M_C_DQ<32>"
				( objectStatus "@baseboard_fab2_lib.baseboard_fab2(sch_1):m_c_dq(32)" )
			)
			( signal "M_C_DQ<33>"
				( objectStatus "@baseboard_fab2_lib.baseboard_fab2(sch_1):m_c_dq(33)" )
			)
			( signal "M_C_DQ<34>"
				( objectStatus "@baseboard_fab2_lib.baseboard_fab2(sch_1):m_c_dq(34)" )
			)
			( signal "M_C_DQ<35>"
				( objectStatus "@baseboard_fab2_lib.baseboard_fab2(sch_1):m_c_dq(35)" )
			)
			( signal "M_C_DQ<36>"
				( objectStatus "@baseboard_fab2_lib.baseboard_fab2(sch_1):m_c_dq(36)" )
			)
			( signal "M_C_DQ<37>"
				( objectStatus "@baseboard_fab2_lib.baseboard_fab2(sch_1):m_c_dq(37)" )
			)
			( signal "M_C_DQ<38>"
				( objectStatus "@baseboard_fab2_lib.baseboard_fab2(sch_1):m_c_dq(38)" )
			)
			( signal "M_C_DQ<39>"
				( objectStatus "@baseboard_fab2_lib.baseboard_fab2(sch_1):m_c_dq(39)" )
			)
			( signal "M_C_DQ<40>"
				( objectStatus "@baseboard_fab2_lib.baseboard_fab2(sch_1):m_c_dq(40)" )
			)
			( signal "M_C_DQ<41>"
				( objectStatus "@baseboard_fab2_lib.baseboard_fab2(sch_1):m_c_dq(41)" )
			)
			( signal "M_C_DQ<42>"
				( objectStatus "@baseboard_fab2_lib.baseboard_fab2(sch_1):m_c_dq(42)" )
			)
			( signal "M_C_DQ<43>"
				( objectStatus "@baseboard_fab2_lib.baseboard_fab2(sch_1):m_c_dq(43)" )
			)
			( signal "M_C_DQ<44>"
				( objectStatus "@baseboard_fab2_lib.baseboard_fab2(sch_1):m_c_dq(44)" )
			)
			( signal "M_C_DQ<45>"
				( objectStatus "@baseboard_fab2_lib.baseboard_fab2(sch_1):m_c_dq(45)" )
			)
			( signal "M_C_DQ<46>"
				( objectStatus "@baseboard_fab2_lib.baseboard_fab2(sch_1):m_c_dq(46)" )
			)
			( signal "M_C_DQ<47>"
				( objectStatus "@baseboard_fab2_lib.baseboard_fab2(sch_1):m_c_dq(47)" )
			)
			( signal "M_C_DQ<48>"
				( objectStatus "@baseboard_fab2_lib.baseboard_fab2(sch_1):m_c_dq(48)" )
			)
			( signal "M_C_DQ<49>"
				( objectStatus "@baseboard_fab2_lib.baseboard_fab2(sch_1):m_c_dq(49)" )
			)
			( signal "M_C_DQ<50>"
				( objectStatus "@baseboard_fab2_lib.baseboard_fab2(sch_1):m_c_dq(50)" )
			)
			( signal "M_C_DQ<51>"
				( objectStatus "@baseboard_fab2_lib.baseboard_fab2(sch_1):m_c_dq(51)" )
			)
			( signal "M_C_DQ<52>"
				( objectStatus "@baseboard_fab2_lib.baseboard_fab2(sch_1):m_c_dq(52)" )
			)
			( signal "M_C_DQ<53>"
				( objectStatus "@baseboard_fab2_lib.baseboard_fab2(sch_1):m_c_dq(53)" )
			)
			( signal "M_C_DQ<54>"
				( objectStatus "@baseboard_fab2_lib.baseboard_fab2(sch_1):m_c_dq(54)" )
			)
			( signal "M_C_DQ<55>"
				( objectStatus "@baseboard_fab2_lib.baseboard_fab2(sch_1):m_c_dq(55)" )
			)
			( signal "M_C_DQ<56>"
				( objectStatus "@baseboard_fab2_lib.baseboard_fab2(sch_1):m_c_dq(56)" )
			)
			( signal "M_C_DQ<57>"
				( objectStatus "@baseboard_fab2_lib.baseboard_fab2(sch_1):m_c_dq(57)" )
			)
			( signal "M_C_DQ<58>"
				( objectStatus "@baseboard_fab2_lib.baseboard_fab2(sch_1):m_c_dq(58)" )
			)
			( signal "M_C_DQ<59>"
				( objectStatus "@baseboard_fab2_lib.baseboard_fab2(sch_1):m_c_dq(59)" )
			)
			( signal "M_C_DQ<60>"
				( objectStatus "@baseboard_fab2_lib.baseboard_fab2(sch_1):m_c_dq(60)" )
			)
			( signal "M_C_DQ<61>"
				( objectStatus "@baseboard_fab2_lib.baseboard_fab2(sch_1):m_c_dq(61)" )
			)
			( signal "M_C_DQ<62>"
				( objectStatus "@baseboard_fab2_lib.baseboard_fab2(sch_1):m_c_dq(62)" )
			)
			( signal "M_C_DQ<63>"
				( objectStatus "@baseboard_fab2_lib.baseboard_fab2(sch_1):m_c_dq(63)" )
			)
			( signal "M_C_DQS_DN<0>"
				( objectStatus "@baseboard_fab2_lib.baseboard_fab2(sch_1):m_c_dqs_dn(0)" )
			)
			( signal "M_C_DQS_DN<1>"
				( objectStatus "@baseboard_fab2_lib.baseboard_fab2(sch_1):m_c_dqs_dn(1)" )
			)
			( signal "M_C_DQS_DN<2>"
				( objectStatus "@baseboard_fab2_lib.baseboard_fab2(sch_1):m_c_dqs_dn(2)" )
			)
			( signal "M_C_DQS_DN<3>"
				( objectStatus "@baseboard_fab2_lib.baseboard_fab2(sch_1):m_c_dqs_dn(3)" )
			)
			( signal "M_C_DQS_DN<4>"
				( objectStatus "@baseboard_fab2_lib.baseboard_fab2(sch_1):m_c_dqs_dn(4)" )
			)
			( signal "M_C_DQS_DN<5>"
				( objectStatus "@baseboard_fab2_lib.baseboard_fab2(sch_1):m_c_dqs_dn(5)" )
			)
			( signal "M_C_DQS_DN<6>"
				( objectStatus "@baseboard_fab2_lib.baseboard_fab2(sch_1):m_c_dqs_dn(6)" )
			)
			( signal "M_C_DQS_DN<7>"
				( objectStatus "@baseboard_fab2_lib.baseboard_fab2(sch_1):m_c_dqs_dn(7)" )
			)
			( signal "M_C_DQS_DN<8>"
				( objectStatus "@baseboard_fab2_lib.baseboard_fab2(sch_1):m_c_dqs_dn(8)" )
			)
			( signal "M_C_DQS_DN<9>"
				( objectStatus "@baseboard_fab2_lib.baseboard_fab2(sch_1):m_c_dqs_dn(9)" )
			)
			( signal "M_C_DQS_DN<10>"
				( objectStatus "@baseboard_fab2_lib.baseboard_fab2(sch_1):m_c_dqs_dn(10)" )
			)
			( signal "M_C_DQS_DN<11>"
				( objectStatus "@baseboard_fab2_lib.baseboard_fab2(sch_1):m_c_dqs_dn(11)" )
			)
			( signal "M_C_DQS_DN<12>"
				( objectStatus "@baseboard_fab2_lib.baseboard_fab2(sch_1):m_c_dqs_dn(12)" )
			)
			( signal "M_C_DQS_DN<13>"
				( objectStatus "@baseboard_fab2_lib.baseboard_fab2(sch_1):m_c_dqs_dn(13)" )
			)
			( signal "M_C_DQS_DN<14>"
				( objectStatus "@baseboard_fab2_lib.baseboard_fab2(sch_1):m_c_dqs_dn(14)" )
			)
			( signal "M_C_DQS_DN<15>"
				( objectStatus "@baseboard_fab2_lib.baseboard_fab2(sch_1):m_c_dqs_dn(15)" )
			)
			( signal "M_C_DQS_DN<16>"
				( objectStatus "@baseboard_fab2_lib.baseboard_fab2(sch_1):m_c_dqs_dn(16)" )
			)
			( signal "M_C_DQS_DN<17>"
				( objectStatus "@baseboard_fab2_lib.baseboard_fab2(sch_1):m_c_dqs_dn(17)" )
			)
			( signal "M_C_DQS_DP<0>"
				( objectStatus "@baseboard_fab2_lib.baseboard_fab2(sch_1):m_c_dqs_dp(0)" )
			)
			( signal "M_C_DQS_DP<1>"
				( objectStatus "@baseboard_fab2_lib.baseboard_fab2(sch_1):m_c_dqs_dp(1)" )
			)
			( signal "M_C_DQS_DP<2>"
				( objectStatus "@baseboard_fab2_lib.baseboard_fab2(sch_1):m_c_dqs_dp(2)" )
			)
			( signal "M_C_DQS_DP<3>"
				( objectStatus "@baseboard_fab2_lib.baseboard_fab2(sch_1):m_c_dqs_dp(3)" )
			)
			( signal "M_C_DQS_DP<4>"
				( objectStatus "@baseboard_fab2_lib.baseboard_fab2(sch_1):m_c_dqs_dp(4)" )
			)
			( signal "M_C_DQS_DP<5>"
				( objectStatus "@baseboard_fab2_lib.baseboard_fab2(sch_1):m_c_dqs_dp(5)" )
			)
			( signal "M_C_DQS_DP<6>"
				( objectStatus "@baseboard_fab2_lib.baseboard_fab2(sch_1):m_c_dqs_dp(6)" )
			)
			( signal "M_C_DQS_DP<7>"
				( objectStatus "@baseboard_fab2_lib.baseboard_fab2(sch_1):m_c_dqs_dp(7)" )
			)
			( signal "M_C_DQS_DP<8>"
				( objectStatus "@baseboard_fab2_lib.baseboard_fab2(sch_1):m_c_dqs_dp(8)" )
			)
			( signal "M_C_DQS_DP<9>"
				( objectStatus "@baseboard_fab2_lib.baseboard_fab2(sch_1):m_c_dqs_dp(9)" )
			)
			( signal "M_C_DQS_DP<10>"
				( objectStatus "@baseboard_fab2_lib.baseboard_fab2(sch_1):m_c_dqs_dp(10)" )
			)
			( signal "M_C_DQS_DP<11>"
				( objectStatus "@baseboard_fab2_lib.baseboard_fab2(sch_1):m_c_dqs_dp(11)" )
			)
			( signal "M_C_DQS_DP<12>"
				( objectStatus "@baseboard_fab2_lib.baseboard_fab2(sch_1):m_c_dqs_dp(12)" )
			)
			( signal "M_C_DQS_DP<13>"
				( objectStatus "@baseboard_fab2_lib.baseboard_fab2(sch_1):m_c_dqs_dp(13)" )
			)
			( signal "M_C_DQS_DP<14>"
				( objectStatus "@baseboard_fab2_lib.baseboard_fab2(sch_1):m_c_dqs_dp(14)" )
			)
			( signal "M_C_DQS_DP<15>"
				( objectStatus "@baseboard_fab2_lib.baseboard_fab2(sch_1):m_c_dqs_dp(15)" )
			)
			( signal "M_C_DQS_DP<16>"
				( objectStatus "@baseboard_fab2_lib.baseboard_fab2(sch_1):m_c_dqs_dp(16)" )
			)
			( signal "M_C_DQS_DP<17>"
				( objectStatus "@baseboard_fab2_lib.baseboard_fab2(sch_1):m_c_dqs_dp(17)" )
			)
			( signal "M_C_ECC<0>"
				( objectStatus "@baseboard_fab2_lib.baseboard_fab2(sch_1):m_c_ecc(0)" )
			)
			( signal "M_C_ECC<1>"
				( objectStatus "@baseboard_fab2_lib.baseboard_fab2(sch_1):m_c_ecc(1)" )
			)
			( signal "M_C_ECC<2>"
				( objectStatus "@baseboard_fab2_lib.baseboard_fab2(sch_1):m_c_ecc(2)" )
			)
			( signal "M_C_ECC<3>"
				( objectStatus "@baseboard_fab2_lib.baseboard_fab2(sch_1):m_c_ecc(3)" )
			)
			( signal "M_C_ECC<4>"
				( objectStatus "@baseboard_fab2_lib.baseboard_fab2(sch_1):m_c_ecc(4)" )
			)
			( signal "M_C_ECC<5>"
				( objectStatus "@baseboard_fab2_lib.baseboard_fab2(sch_1):m_c_ecc(5)" )
			)
			( signal "M_C_ECC<6>"
				( objectStatus "@baseboard_fab2_lib.baseboard_fab2(sch_1):m_c_ecc(6)" )
			)
			( signal "M_C_ECC<7>"
				( objectStatus "@baseboard_fab2_lib.baseboard_fab2(sch_1):m_c_ecc(7)" )
			)
			( signal "M_C_MA<0>"
				( objectStatus "@baseboard_fab2_lib.baseboard_fab2(sch_1):m_c_ma(0)" )
			)
			( signal "M_C_MA<1>"
				( objectStatus "@baseboard_fab2_lib.baseboard_fab2(sch_1):m_c_ma(1)" )
			)
			( signal "M_C_MA<2>"
				( objectStatus "@baseboard_fab2_lib.baseboard_fab2(sch_1):m_c_ma(2)" )
			)
			( signal "M_C_MA<3>"
				( objectStatus "@baseboard_fab2_lib.baseboard_fab2(sch_1):m_c_ma(3)" )
			)
			( signal "M_C_MA<4>"
				( objectStatus "@baseboard_fab2_lib.baseboard_fab2(sch_1):m_c_ma(4)" )
			)
			( signal "M_C_MA<5>"
				( objectStatus "@baseboard_fab2_lib.baseboard_fab2(sch_1):m_c_ma(5)" )
			)
			( signal "M_C_MA<6>"
				( objectStatus "@baseboard_fab2_lib.baseboard_fab2(sch_1):m_c_ma(6)" )
			)
			( signal "M_C_MA<7>"
				( objectStatus "@baseboard_fab2_lib.baseboard_fab2(sch_1):m_c_ma(7)" )
			)
			( signal "M_C_MA<8>"
				( objectStatus "@baseboard_fab2_lib.baseboard_fab2(sch_1):m_c_ma(8)" )
			)
			( signal "M_C_MA<9>"
				( objectStatus "@baseboard_fab2_lib.baseboard_fab2(sch_1):m_c_ma(9)" )
			)
			( signal "M_C_MA<10>"
				( objectStatus "@baseboard_fab2_lib.baseboard_fab2(sch_1):m_c_ma(10)" )
			)
			( signal "M_C_MA<11>"
				( objectStatus "@baseboard_fab2_lib.baseboard_fab2(sch_1):m_c_ma(11)" )
			)
			( signal "M_C_MA<12>"
				( objectStatus "@baseboard_fab2_lib.baseboard_fab2(sch_1):m_c_ma(12)" )
			)
			( signal "M_C_MA<13>"
				( objectStatus "@baseboard_fab2_lib.baseboard_fab2(sch_1):m_c_ma(13)" )
			)
			( signal "M_C_MA<14>"
				( objectStatus "@baseboard_fab2_lib.baseboard_fab2(sch_1):m_c_ma(14)" )
			)
			( signal "M_C_MA<15>"
				( objectStatus "@baseboard_fab2_lib.baseboard_fab2(sch_1):m_c_ma(15)" )
			)
			( signal "M_C_MA<16>"
				( objectStatus "@baseboard_fab2_lib.baseboard_fab2(sch_1):m_c_ma(16)" )
			)
			( signal "M_C_MA<17>"
				( objectStatus "@baseboard_fab2_lib.baseboard_fab2(sch_1):m_c_ma(17)" )
			)
			( signal "M_C_ODT<0>"
				( objectStatus "@baseboard_fab2_lib.baseboard_fab2(sch_1):m_c_odt(0)" )
			)
			( signal "M_C_ODT<1>"
				( objectStatus "@baseboard_fab2_lib.baseboard_fab2(sch_1):m_c_odt(1)" )
			)
			( signal "M_C_ODT<2>"
				( objectStatus "@baseboard_fab2_lib.baseboard_fab2(sch_1):m_c_odt(2)" )
			)
			( signal "M_C_ODT<3>"
				( objectStatus "@baseboard_fab2_lib.baseboard_fab2(sch_1):m_c_odt(3)" )
			)
			( signal "M_C_PAR"
				( objectStatus "@baseboard_fab2_lib.baseboard_fab2(sch_1):m_c_par" )
			)
			( signal "M_D_ACT_N"
				( objectStatus "@baseboard_fab2_lib.baseboard_fab2(sch_1):m_d_act_n" )
			)
			( signal "M_D_ALERT_N"
				( objectStatus "@baseboard_fab2_lib.baseboard_fab2(sch_1):m_d_alert_n" )
			)
			( signal "M_D_BA<0>"
				( objectStatus "@baseboard_fab2_lib.baseboard_fab2(sch_1):m_d_ba(0)" )
			)
			( signal "M_D_BA<1>"
				( objectStatus "@baseboard_fab2_lib.baseboard_fab2(sch_1):m_d_ba(1)" )
			)
			( signal "M_D_BG<0>"
				( objectStatus "@baseboard_fab2_lib.baseboard_fab2(sch_1):m_d_bg(0)" )
			)
			( signal "M_D_BG<1>"
				( objectStatus "@baseboard_fab2_lib.baseboard_fab2(sch_1):m_d_bg(1)" )
			)
			( signal "M_D_C<2>"
				( objectStatus "@baseboard_fab2_lib.baseboard_fab2(sch_1):m_d_c(2)" )
			)
			( signal "M_D_CKE<0>"
				( objectStatus "@baseboard_fab2_lib.baseboard_fab2(sch_1):m_d_cke(0)" )
			)
			( signal "M_D_CKE<1>"
				( objectStatus "@baseboard_fab2_lib.baseboard_fab2(sch_1):m_d_cke(1)" )
			)
			( signal "M_D_CKE<2>"
				( objectStatus "@baseboard_fab2_lib.baseboard_fab2(sch_1):m_d_cke(2)" )
			)
			( signal "M_D_CKE<3>"
				( objectStatus "@baseboard_fab2_lib.baseboard_fab2(sch_1):m_d_cke(3)" )
			)
			( signal "M_D_CLK_DN<0>"
				( objectStatus "@baseboard_fab2_lib.baseboard_fab2(sch_1):m_d_clk_dn(0)" )
			)
			( signal "M_D_CLK_DN<1>"
				( objectStatus "@baseboard_fab2_lib.baseboard_fab2(sch_1):m_d_clk_dn(1)" )
			)
			( signal "M_D_CLK_DN<2>"
				( objectStatus "@baseboard_fab2_lib.baseboard_fab2(sch_1):m_d_clk_dn(2)" )
			)
			( signal "M_D_CLK_DN<3>"
				( objectStatus "@baseboard_fab2_lib.baseboard_fab2(sch_1):m_d_clk_dn(3)" )
			)
			( signal "M_D_CLK_DP<0>"
				( objectStatus "@baseboard_fab2_lib.baseboard_fab2(sch_1):m_d_clk_dp(0)" )
			)
			( signal "M_D_CLK_DP<1>"
				( objectStatus "@baseboard_fab2_lib.baseboard_fab2(sch_1):m_d_clk_dp(1)" )
			)
			( signal "M_D_CLK_DP<2>"
				( objectStatus "@baseboard_fab2_lib.baseboard_fab2(sch_1):m_d_clk_dp(2)" )
			)
			( signal "M_D_CLK_DP<3>"
				( objectStatus "@baseboard_fab2_lib.baseboard_fab2(sch_1):m_d_clk_dp(3)" )
			)
			( signal "M_D_CS_N<0>"
				( objectStatus "@baseboard_fab2_lib.baseboard_fab2(sch_1):m_d_cs_n(0)" )
			)
			( signal "M_D_CS_N<1>"
				( objectStatus "@baseboard_fab2_lib.baseboard_fab2(sch_1):m_d_cs_n(1)" )
			)
			( signal "M_D_CS_N<2>"
				( objectStatus "@baseboard_fab2_lib.baseboard_fab2(sch_1):m_d_cs_n(2)" )
			)
			( signal "M_D_CS_N<3>"
				( objectStatus "@baseboard_fab2_lib.baseboard_fab2(sch_1):m_d_cs_n(3)" )
			)
			( signal "M_D_CS_N<4>"
				( objectStatus "@baseboard_fab2_lib.baseboard_fab2(sch_1):m_d_cs_n(4)" )
			)
			( signal "M_D_CS_N<5>"
				( objectStatus "@baseboard_fab2_lib.baseboard_fab2(sch_1):m_d_cs_n(5)" )
			)
			( signal "M_D_CS_N<6>"
				( objectStatus "@baseboard_fab2_lib.baseboard_fab2(sch_1):m_d_cs_n(6)" )
			)
			( signal "M_D_CS_N<7>"
				( objectStatus "@baseboard_fab2_lib.baseboard_fab2(sch_1):m_d_cs_n(7)" )
			)
			( signal "M_D_DQ<0>"
				( objectStatus "@baseboard_fab2_lib.baseboard_fab2(sch_1):m_d_dq(0)" )
			)
			( signal "M_D_DQ<1>"
				( objectStatus "@baseboard_fab2_lib.baseboard_fab2(sch_1):m_d_dq(1)" )
			)
			( signal "M_D_DQ<2>"
				( objectStatus "@baseboard_fab2_lib.baseboard_fab2(sch_1):m_d_dq(2)" )
			)
			( signal "M_D_DQ<3>"
				( objectStatus "@baseboard_fab2_lib.baseboard_fab2(sch_1):m_d_dq(3)" )
			)
			( signal "M_D_DQ<4>"
				( objectStatus "@baseboard_fab2_lib.baseboard_fab2(sch_1):m_d_dq(4)" )
			)
			( signal "M_D_DQ<5>"
				( objectStatus "@baseboard_fab2_lib.baseboard_fab2(sch_1):m_d_dq(5)" )
			)
			( signal "M_D_DQ<6>"
				( objectStatus "@baseboard_fab2_lib.baseboard_fab2(sch_1):m_d_dq(6)" )
			)
			( signal "M_D_DQ<7>"
				( objectStatus "@baseboard_fab2_lib.baseboard_fab2(sch_1):m_d_dq(7)" )
			)
			( signal "M_D_DQ<8>"
				( objectStatus "@baseboard_fab2_lib.baseboard_fab2(sch_1):m_d_dq(8)" )
			)
			( signal "M_D_DQ<9>"
				( objectStatus "@baseboard_fab2_lib.baseboard_fab2(sch_1):m_d_dq(9)" )
			)
			( signal "M_D_DQ<10>"
				( objectStatus "@baseboard_fab2_lib.baseboard_fab2(sch_1):m_d_dq(10)" )
			)
			( signal "M_D_DQ<11>"
				( objectStatus "@baseboard_fab2_lib.baseboard_fab2(sch_1):m_d_dq(11)" )
			)
			( signal "M_D_DQ<12>"
				( objectStatus "@baseboard_fab2_lib.baseboard_fab2(sch_1):m_d_dq(12)" )
			)
			( signal "M_D_DQ<13>"
				( objectStatus "@baseboard_fab2_lib.baseboard_fab2(sch_1):m_d_dq(13)" )
			)
			( signal "M_D_DQ<14>"
				( objectStatus "@baseboard_fab2_lib.baseboard_fab2(sch_1):m_d_dq(14)" )
			)
			( signal "M_D_DQ<15>"
				( objectStatus "@baseboard_fab2_lib.baseboard_fab2(sch_1):m_d_dq(15)" )
			)
			( signal "M_D_DQ<16>"
				( objectStatus "@baseboard_fab2_lib.baseboard_fab2(sch_1):m_d_dq(16)" )
			)
			( signal "M_D_DQ<17>"
				( objectStatus "@baseboard_fab2_lib.baseboard_fab2(sch_1):m_d_dq(17)" )
			)
			( signal "M_D_DQ<18>"
				( objectStatus "@baseboard_fab2_lib.baseboard_fab2(sch_1):m_d_dq(18)" )
			)
			( signal "M_D_DQ<19>"
				( objectStatus "@baseboard_fab2_lib.baseboard_fab2(sch_1):m_d_dq(19)" )
			)
			( signal "M_D_DQ<20>"
				( objectStatus "@baseboard_fab2_lib.baseboard_fab2(sch_1):m_d_dq(20)" )
			)
			( signal "M_D_DQ<21>"
				( objectStatus "@baseboard_fab2_lib.baseboard_fab2(sch_1):m_d_dq(21)" )
			)
			( signal "M_D_DQ<22>"
				( objectStatus "@baseboard_fab2_lib.baseboard_fab2(sch_1):m_d_dq(22)" )
			)
			( signal "M_D_DQ<23>"
				( objectStatus "@baseboard_fab2_lib.baseboard_fab2(sch_1):m_d_dq(23)" )
			)
			( signal "M_D_DQ<24>"
				( objectStatus "@baseboard_fab2_lib.baseboard_fab2(sch_1):m_d_dq(24)" )
			)
			( signal "M_D_DQ<25>"
				( objectStatus "@baseboard_fab2_lib.baseboard_fab2(sch_1):m_d_dq(25)" )
			)
			( signal "M_D_DQ<26>"
				( objectStatus "@baseboard_fab2_lib.baseboard_fab2(sch_1):m_d_dq(26)" )
			)
			( signal "M_D_DQ<27>"
				( objectStatus "@baseboard_fab2_lib.baseboard_fab2(sch_1):m_d_dq(27)" )
			)
			( signal "M_D_DQ<28>"
				( objectStatus "@baseboard_fab2_lib.baseboard_fab2(sch_1):m_d_dq(28)" )
			)
			( signal "M_D_DQ<29>"
				( objectStatus "@baseboard_fab2_lib.baseboard_fab2(sch_1):m_d_dq(29)" )
			)
			( signal "M_D_DQ<30>"
				( objectStatus "@baseboard_fab2_lib.baseboard_fab2(sch_1):m_d_dq(30)" )
			)
			( signal "M_D_DQ<31>"
				( objectStatus "@baseboard_fab2_lib.baseboard_fab2(sch_1):m_d_dq(31)" )
			)
			( signal "M_D_DQ<32>"
				( objectStatus "@baseboard_fab2_lib.baseboard_fab2(sch_1):m_d_dq(32)" )
			)
			( signal "M_D_DQ<33>"
				( objectStatus "@baseboard_fab2_lib.baseboard_fab2(sch_1):m_d_dq(33)" )
			)
			( signal "M_D_DQ<34>"
				( objectStatus "@baseboard_fab2_lib.baseboard_fab2(sch_1):m_d_dq(34)" )
			)
			( signal "M_D_DQ<35>"
				( objectStatus "@baseboard_fab2_lib.baseboard_fab2(sch_1):m_d_dq(35)" )
			)
			( signal "M_D_DQ<36>"
				( objectStatus "@baseboard_fab2_lib.baseboard_fab2(sch_1):m_d_dq(36)" )
			)
			( signal "M_D_DQ<37>"
				( objectStatus "@baseboard_fab2_lib.baseboard_fab2(sch_1):m_d_dq(37)" )
			)
			( signal "M_D_DQ<38>"
				( objectStatus "@baseboard_fab2_lib.baseboard_fab2(sch_1):m_d_dq(38)" )
			)
			( signal "M_D_DQ<39>"
				( objectStatus "@baseboard_fab2_lib.baseboard_fab2(sch_1):m_d_dq(39)" )
			)
			( signal "M_D_DQ<40>"
				( objectStatus "@baseboard_fab2_lib.baseboard_fab2(sch_1):m_d_dq(40)" )
			)
			( signal "M_D_DQ<41>"
				( objectStatus "@baseboard_fab2_lib.baseboard_fab2(sch_1):m_d_dq(41)" )
			)
			( signal "M_D_DQ<42>"
				( objectStatus "@baseboard_fab2_lib.baseboard_fab2(sch_1):m_d_dq(42)" )
			)
			( signal "M_D_DQ<43>"
				( objectStatus "@baseboard_fab2_lib.baseboard_fab2(sch_1):m_d_dq(43)" )
			)
			( signal "M_D_DQ<44>"
				( objectStatus "@baseboard_fab2_lib.baseboard_fab2(sch_1):m_d_dq(44)" )
			)
			( signal "M_D_DQ<45>"
				( objectStatus "@baseboard_fab2_lib.baseboard_fab2(sch_1):m_d_dq(45)" )
			)
			( signal "M_D_DQ<46>"
				( objectStatus "@baseboard_fab2_lib.baseboard_fab2(sch_1):m_d_dq(46)" )
			)
			( signal "M_D_DQ<47>"
				( objectStatus "@baseboard_fab2_lib.baseboard_fab2(sch_1):m_d_dq(47)" )
			)
			( signal "M_D_DQ<48>"
				( objectStatus "@baseboard_fab2_lib.baseboard_fab2(sch_1):m_d_dq(48)" )
			)
			( signal "M_D_DQ<49>"
				( objectStatus "@baseboard_fab2_lib.baseboard_fab2(sch_1):m_d_dq(49)" )
			)
			( signal "M_D_DQ<50>"
				( objectStatus "@baseboard_fab2_lib.baseboard_fab2(sch_1):m_d_dq(50)" )
			)
			( signal "M_D_DQ<51>"
				( objectStatus "@baseboard_fab2_lib.baseboard_fab2(sch_1):m_d_dq(51)" )
			)
			( signal "M_D_DQ<52>"
				( objectStatus "@baseboard_fab2_lib.baseboard_fab2(sch_1):m_d_dq(52)" )
			)
			( signal "M_D_DQ<53>"
				( objectStatus "@baseboard_fab2_lib.baseboard_fab2(sch_1):m_d_dq(53)" )
			)
			( signal "M_D_DQ<54>"
				( objectStatus "@baseboard_fab2_lib.baseboard_fab2(sch_1):m_d_dq(54)" )
			)
			( signal "M_D_DQ<55>"
				( objectStatus "@baseboard_fab2_lib.baseboard_fab2(sch_1):m_d_dq(55)" )
			)
			( signal "M_D_DQ<56>"
				( objectStatus "@baseboard_fab2_lib.baseboard_fab2(sch_1):m_d_dq(56)" )
			)
			( signal "M_D_DQ<57>"
				( objectStatus "@baseboard_fab2_lib.baseboard_fab2(sch_1):m_d_dq(57)" )
			)
			( signal "M_D_DQ<58>"
				( objectStatus "@baseboard_fab2_lib.baseboard_fab2(sch_1):m_d_dq(58)" )
			)
			( signal "M_D_DQ<59>"
				( objectStatus "@baseboard_fab2_lib.baseboard_fab2(sch_1):m_d_dq(59)" )
			)
			( signal "M_D_DQ<60>"
				( objectStatus "@baseboard_fab2_lib.baseboard_fab2(sch_1):m_d_dq(60)" )
			)
			( signal "M_D_DQ<61>"
				( objectStatus "@baseboard_fab2_lib.baseboard_fab2(sch_1):m_d_dq(61)" )
			)
			( signal "M_D_DQ<62>"
				( objectStatus "@baseboard_fab2_lib.baseboard_fab2(sch_1):m_d_dq(62)" )
			)
			( signal "M_D_DQ<63>"
				( objectStatus "@baseboard_fab2_lib.baseboard_fab2(sch_1):m_d_dq(63)" )
			)
			( signal "M_D_DQS_DN<0>"
				( objectStatus "@baseboard_fab2_lib.baseboard_fab2(sch_1):m_d_dqs_dn(0)" )
			)
			( signal "M_D_DQS_DN<1>"
				( objectStatus "@baseboard_fab2_lib.baseboard_fab2(sch_1):m_d_dqs_dn(1)" )
			)
			( signal "M_D_DQS_DN<2>"
				( objectStatus "@baseboard_fab2_lib.baseboard_fab2(sch_1):m_d_dqs_dn(2)" )
			)
			( signal "M_D_DQS_DN<3>"
				( objectStatus "@baseboard_fab2_lib.baseboard_fab2(sch_1):m_d_dqs_dn(3)" )
			)
			( signal "M_D_DQS_DN<4>"
				( objectStatus "@baseboard_fab2_lib.baseboard_fab2(sch_1):m_d_dqs_dn(4)" )
			)
			( signal "M_D_DQS_DN<5>"
				( objectStatus "@baseboard_fab2_lib.baseboard_fab2(sch_1):m_d_dqs_dn(5)" )
			)
			( signal "M_D_DQS_DN<6>"
				( objectStatus "@baseboard_fab2_lib.baseboard_fab2(sch_1):m_d_dqs_dn(6)" )
			)
			( signal "M_D_DQS_DN<7>"
				( objectStatus "@baseboard_fab2_lib.baseboard_fab2(sch_1):m_d_dqs_dn(7)" )
			)
			( signal "M_D_DQS_DN<8>"
				( objectStatus "@baseboard_fab2_lib.baseboard_fab2(sch_1):m_d_dqs_dn(8)" )
			)
			( signal "M_D_DQS_DN<9>"
				( objectStatus "@baseboard_fab2_lib.baseboard_fab2(sch_1):m_d_dqs_dn(9)" )
			)
			( signal "M_D_DQS_DN<10>"
				( objectStatus "@baseboard_fab2_lib.baseboard_fab2(sch_1):m_d_dqs_dn(10)" )
			)
			( signal "M_D_DQS_DN<11>"
				( objectStatus "@baseboard_fab2_lib.baseboard_fab2(sch_1):m_d_dqs_dn(11)" )
			)
			( signal "M_D_DQS_DN<12>"
				( objectStatus "@baseboard_fab2_lib.baseboard_fab2(sch_1):m_d_dqs_dn(12)" )
			)
			( signal "M_D_DQS_DN<13>"
				( objectStatus "@baseboard_fab2_lib.baseboard_fab2(sch_1):m_d_dqs_dn(13)" )
			)
			( signal "M_D_DQS_DN<14>"
				( objectStatus "@baseboard_fab2_lib.baseboard_fab2(sch_1):m_d_dqs_dn(14)" )
			)
			( signal "M_D_DQS_DN<15>"
				( objectStatus "@baseboard_fab2_lib.baseboard_fab2(sch_1):m_d_dqs_dn(15)" )
			)
			( signal "M_D_DQS_DN<16>"
				( objectStatus "@baseboard_fab2_lib.baseboard_fab2(sch_1):m_d_dqs_dn(16)" )
			)
			( signal "M_D_DQS_DN<17>"
				( objectStatus "@baseboard_fab2_lib.baseboard_fab2(sch_1):m_d_dqs_dn(17)" )
			)
			( signal "M_D_DQS_DP<0>"
				( objectStatus "@baseboard_fab2_lib.baseboard_fab2(sch_1):m_d_dqs_dp(0)" )
			)
			( signal "M_D_DQS_DP<1>"
				( objectStatus "@baseboard_fab2_lib.baseboard_fab2(sch_1):m_d_dqs_dp(1)" )
			)
			( signal "M_D_DQS_DP<2>"
				( objectStatus "@baseboard_fab2_lib.baseboard_fab2(sch_1):m_d_dqs_dp(2)" )
			)
			( signal "M_D_DQS_DP<3>"
				( objectStatus "@baseboard_fab2_lib.baseboard_fab2(sch_1):m_d_dqs_dp(3)" )
			)
			( signal "M_D_DQS_DP<4>"
				( objectStatus "@baseboard_fab2_lib.baseboard_fab2(sch_1):m_d_dqs_dp(4)" )
			)
			( signal "M_D_DQS_DP<5>"
				( objectStatus "@baseboard_fab2_lib.baseboard_fab2(sch_1):m_d_dqs_dp(5)" )
			)
			( signal "M_D_DQS_DP<6>"
				( objectStatus "@baseboard_fab2_lib.baseboard_fab2(sch_1):m_d_dqs_dp(6)" )
			)
			( signal "M_D_DQS_DP<7>"
				( objectStatus "@baseboard_fab2_lib.baseboard_fab2(sch_1):m_d_dqs_dp(7)" )
			)
			( signal "M_D_DQS_DP<8>"
				( objectStatus "@baseboard_fab2_lib.baseboard_fab2(sch_1):m_d_dqs_dp(8)" )
			)
			( signal "M_D_DQS_DP<9>"
				( objectStatus "@baseboard_fab2_lib.baseboard_fab2(sch_1):m_d_dqs_dp(9)" )
			)
			( signal "M_D_DQS_DP<10>"
				( objectStatus "@baseboard_fab2_lib.baseboard_fab2(sch_1):m_d_dqs_dp(10)" )
			)
			( signal "M_D_DQS_DP<11>"
				( objectStatus "@baseboard_fab2_lib.baseboard_fab2(sch_1):m_d_dqs_dp(11)" )
			)
			( signal "M_D_DQS_DP<12>"
				( objectStatus "@baseboard_fab2_lib.baseboard_fab2(sch_1):m_d_dqs_dp(12)" )
			)
			( signal "M_D_DQS_DP<13>"
				( objectStatus "@baseboard_fab2_lib.baseboard_fab2(sch_1):m_d_dqs_dp(13)" )
			)
			( signal "M_D_DQS_DP<14>"
				( objectStatus "@baseboard_fab2_lib.baseboard_fab2(sch_1):m_d_dqs_dp(14)" )
			)
			( signal "M_D_DQS_DP<15>"
				( objectStatus "@baseboard_fab2_lib.baseboard_fab2(sch_1):m_d_dqs_dp(15)" )
			)
			( signal "M_D_DQS_DP<16>"
				( objectStatus "@baseboard_fab2_lib.baseboard_fab2(sch_1):m_d_dqs_dp(16)" )
			)
			( signal "M_D_DQS_DP<17>"
				( objectStatus "@baseboard_fab2_lib.baseboard_fab2(sch_1):m_d_dqs_dp(17)" )
			)
			( signal "M_D_ECC<0>"
				( objectStatus "@baseboard_fab2_lib.baseboard_fab2(sch_1):m_d_ecc(0)" )
			)
			( signal "M_D_ECC<1>"
				( objectStatus "@baseboard_fab2_lib.baseboard_fab2(sch_1):m_d_ecc(1)" )
			)
			( signal "M_D_ECC<2>"
				( objectStatus "@baseboard_fab2_lib.baseboard_fab2(sch_1):m_d_ecc(2)" )
			)
			( signal "M_D_ECC<3>"
				( objectStatus "@baseboard_fab2_lib.baseboard_fab2(sch_1):m_d_ecc(3)" )
			)
			( signal "M_D_ECC<4>"
				( objectStatus "@baseboard_fab2_lib.baseboard_fab2(sch_1):m_d_ecc(4)" )
			)
			( signal "M_D_ECC<5>"
				( objectStatus "@baseboard_fab2_lib.baseboard_fab2(sch_1):m_d_ecc(5)" )
			)
			( signal "M_D_ECC<6>"
				( objectStatus "@baseboard_fab2_lib.baseboard_fab2(sch_1):m_d_ecc(6)" )
			)
			( signal "M_D_ECC<7>"
				( objectStatus "@baseboard_fab2_lib.baseboard_fab2(sch_1):m_d_ecc(7)" )
			)
			( signal "M_D_MA<0>"
				( objectStatus "@baseboard_fab2_lib.baseboard_fab2(sch_1):m_d_ma(0)" )
			)
			( signal "M_D_MA<1>"
				( objectStatus "@baseboard_fab2_lib.baseboard_fab2(sch_1):m_d_ma(1)" )
			)
			( signal "M_D_MA<2>"
				( objectStatus "@baseboard_fab2_lib.baseboard_fab2(sch_1):m_d_ma(2)" )
			)
			( signal "M_D_MA<3>"
				( objectStatus "@baseboard_fab2_lib.baseboard_fab2(sch_1):m_d_ma(3)" )
			)
			( signal "M_D_MA<4>"
				( objectStatus "@baseboard_fab2_lib.baseboard_fab2(sch_1):m_d_ma(4)" )
			)
			( signal "M_D_MA<5>"
				( objectStatus "@baseboard_fab2_lib.baseboard_fab2(sch_1):m_d_ma(5)" )
			)
			( signal "M_D_MA<6>"
				( objectStatus "@baseboard_fab2_lib.baseboard_fab2(sch_1):m_d_ma(6)" )
			)
			( signal "M_D_MA<7>"
				( objectStatus "@baseboard_fab2_lib.baseboard_fab2(sch_1):m_d_ma(7)" )
			)
			( signal "M_D_MA<8>"
				( objectStatus "@baseboard_fab2_lib.baseboard_fab2(sch_1):m_d_ma(8)" )
			)
			( signal "M_D_MA<9>"
				( objectStatus "@baseboard_fab2_lib.baseboard_fab2(sch_1):m_d_ma(9)" )
			)
			( signal "M_D_MA<10>"
				( objectStatus "@baseboard_fab2_lib.baseboard_fab2(sch_1):m_d_ma(10)" )
			)
			( signal "M_D_MA<11>"
				( objectStatus "@baseboard_fab2_lib.baseboard_fab2(sch_1):m_d_ma(11)" )
			)
			( signal "M_D_MA<12>"
				( objectStatus "@baseboard_fab2_lib.baseboard_fab2(sch_1):m_d_ma(12)" )
			)
			( signal "M_D_MA<13>"
				( objectStatus "@baseboard_fab2_lib.baseboard_fab2(sch_1):m_d_ma(13)" )
			)
			( signal "M_D_MA<14>"
				( objectStatus "@baseboard_fab2_lib.baseboard_fab2(sch_1):m_d_ma(14)" )
			)
			( signal "M_D_MA<15>"
				( objectStatus "@baseboard_fab2_lib.baseboard_fab2(sch_1):m_d_ma(15)" )
			)
			( signal "M_D_MA<16>"
				( objectStatus "@baseboard_fab2_lib.baseboard_fab2(sch_1):m_d_ma(16)" )
			)
			( signal "M_D_MA<17>"
				( objectStatus "@baseboard_fab2_lib.baseboard_fab2(sch_1):m_d_ma(17)" )
			)
			( signal "M_D_ODT<0>"
				( objectStatus "@baseboard_fab2_lib.baseboard_fab2(sch_1):m_d_odt(0)" )
			)
			( signal "M_D_ODT<1>"
				( objectStatus "@baseboard_fab2_lib.baseboard_fab2(sch_1):m_d_odt(1)" )
			)
			( signal "M_D_ODT<2>"
				( objectStatus "@baseboard_fab2_lib.baseboard_fab2(sch_1):m_d_odt(2)" )
			)
			( signal "M_D_ODT<3>"
				( objectStatus "@baseboard_fab2_lib.baseboard_fab2(sch_1):m_d_odt(3)" )
			)
			( signal "M_D_PAR"
				( objectStatus "@baseboard_fab2_lib.baseboard_fab2(sch_1):m_d_par" )
			)
			( signal "M_E_ACT_N"
				( objectStatus "@baseboard_fab2_lib.baseboard_fab2(sch_1):m_e_act_n" )
			)
			( signal "M_E_ALERT_N"
				( objectStatus "@baseboard_fab2_lib.baseboard_fab2(sch_1):m_e_alert_n" )
			)
			( signal "M_E_BA<0>"
				( objectStatus "@baseboard_fab2_lib.baseboard_fab2(sch_1):m_e_ba(0)" )
			)
			( signal "M_E_BA<1>"
				( objectStatus "@baseboard_fab2_lib.baseboard_fab2(sch_1):m_e_ba(1)" )
			)
			( signal "M_E_BG<0>"
				( objectStatus "@baseboard_fab2_lib.baseboard_fab2(sch_1):m_e_bg(0)" )
			)
			( signal "M_E_BG<1>"
				( objectStatus "@baseboard_fab2_lib.baseboard_fab2(sch_1):m_e_bg(1)" )
			)
			( signal "M_E_C<2>"
				( objectStatus "@baseboard_fab2_lib.baseboard_fab2(sch_1):m_e_c(2)" )
			)
			( signal "M_E_CKE<0>"
				( objectStatus "@baseboard_fab2_lib.baseboard_fab2(sch_1):m_e_cke(0)" )
			)
			( signal "M_E_CKE<1>"
				( objectStatus "@baseboard_fab2_lib.baseboard_fab2(sch_1):m_e_cke(1)" )
			)
			( signal "M_E_CKE<2>"
				( objectStatus "@baseboard_fab2_lib.baseboard_fab2(sch_1):m_e_cke(2)" )
			)
			( signal "M_E_CKE<3>"
				( objectStatus "@baseboard_fab2_lib.baseboard_fab2(sch_1):m_e_cke(3)" )
			)
			( signal "M_E_CLK_DN<0>"
				( objectStatus "@baseboard_fab2_lib.baseboard_fab2(sch_1):m_e_clk_dn(0)" )
			)
			( signal "M_E_CLK_DN<1>"
				( objectStatus "@baseboard_fab2_lib.baseboard_fab2(sch_1):m_e_clk_dn(1)" )
			)
			( signal "M_E_CLK_DN<2>"
				( objectStatus "@baseboard_fab2_lib.baseboard_fab2(sch_1):m_e_clk_dn(2)" )
			)
			( signal "M_E_CLK_DN<3>"
				( objectStatus "@baseboard_fab2_lib.baseboard_fab2(sch_1):m_e_clk_dn(3)" )
			)
			( signal "M_E_CLK_DP<0>"
				( objectStatus "@baseboard_fab2_lib.baseboard_fab2(sch_1):m_e_clk_dp(0)" )
			)
			( signal "M_E_CLK_DP<1>"
				( objectStatus "@baseboard_fab2_lib.baseboard_fab2(sch_1):m_e_clk_dp(1)" )
			)
			( signal "M_E_CLK_DP<2>"
				( objectStatus "@baseboard_fab2_lib.baseboard_fab2(sch_1):m_e_clk_dp(2)" )
			)
			( signal "M_E_CLK_DP<3>"
				( objectStatus "@baseboard_fab2_lib.baseboard_fab2(sch_1):m_e_clk_dp(3)" )
			)
			( signal "M_E_CS_N<0>"
				( objectStatus "@baseboard_fab2_lib.baseboard_fab2(sch_1):m_e_cs_n(0)" )
			)
			( signal "M_E_CS_N<1>"
				( objectStatus "@baseboard_fab2_lib.baseboard_fab2(sch_1):m_e_cs_n(1)" )
			)
			( signal "M_E_CS_N<2>"
				( objectStatus "@baseboard_fab2_lib.baseboard_fab2(sch_1):m_e_cs_n(2)" )
			)
			( signal "M_E_CS_N<3>"
				( objectStatus "@baseboard_fab2_lib.baseboard_fab2(sch_1):m_e_cs_n(3)" )
			)
			( signal "M_E_CS_N<4>"
				( objectStatus "@baseboard_fab2_lib.baseboard_fab2(sch_1):m_e_cs_n(4)" )
			)
			( signal "M_E_CS_N<5>"
				( objectStatus "@baseboard_fab2_lib.baseboard_fab2(sch_1):m_e_cs_n(5)" )
			)
			( signal "M_E_CS_N<6>"
				( objectStatus "@baseboard_fab2_lib.baseboard_fab2(sch_1):m_e_cs_n(6)" )
			)
			( signal "M_E_CS_N<7>"
				( objectStatus "@baseboard_fab2_lib.baseboard_fab2(sch_1):m_e_cs_n(7)" )
			)
			( signal "M_E_DQ<0>"
				( objectStatus "@baseboard_fab2_lib.baseboard_fab2(sch_1):m_e_dq(0)" )
			)
			( signal "M_E_DQ<1>"
				( objectStatus "@baseboard_fab2_lib.baseboard_fab2(sch_1):m_e_dq(1)" )
			)
			( signal "M_E_DQ<2>"
				( objectStatus "@baseboard_fab2_lib.baseboard_fab2(sch_1):m_e_dq(2)" )
			)
			( signal "M_E_DQ<3>"
				( objectStatus "@baseboard_fab2_lib.baseboard_fab2(sch_1):m_e_dq(3)" )
			)
			( signal "M_E_DQ<4>"
				( objectStatus "@baseboard_fab2_lib.baseboard_fab2(sch_1):m_e_dq(4)" )
			)
			( signal "M_E_DQ<5>"
				( objectStatus "@baseboard_fab2_lib.baseboard_fab2(sch_1):m_e_dq(5)" )
			)
			( signal "M_E_DQ<6>"
				( objectStatus "@baseboard_fab2_lib.baseboard_fab2(sch_1):m_e_dq(6)" )
			)
			( signal "M_E_DQ<7>"
				( objectStatus "@baseboard_fab2_lib.baseboard_fab2(sch_1):m_e_dq(7)" )
			)
			( signal "M_E_DQ<8>"
				( objectStatus "@baseboard_fab2_lib.baseboard_fab2(sch_1):m_e_dq(8)" )
			)
			( signal "M_E_DQ<9>"
				( objectStatus "@baseboard_fab2_lib.baseboard_fab2(sch_1):m_e_dq(9)" )
			)
			( signal "M_E_DQ<10>"
				( objectStatus "@baseboard_fab2_lib.baseboard_fab2(sch_1):m_e_dq(10)" )
			)
			( signal "M_E_DQ<11>"
				( objectStatus "@baseboard_fab2_lib.baseboard_fab2(sch_1):m_e_dq(11)" )
			)
			( signal "M_E_DQ<12>"
				( objectStatus "@baseboard_fab2_lib.baseboard_fab2(sch_1):m_e_dq(12)" )
			)
			( signal "M_E_DQ<13>"
				( objectStatus "@baseboard_fab2_lib.baseboard_fab2(sch_1):m_e_dq(13)" )
			)
			( signal "M_E_DQ<14>"
				( objectStatus "@baseboard_fab2_lib.baseboard_fab2(sch_1):m_e_dq(14)" )
			)
			( signal "M_E_DQ<15>"
				( objectStatus "@baseboard_fab2_lib.baseboard_fab2(sch_1):m_e_dq(15)" )
			)
			( signal "M_E_DQ<16>"
				( objectStatus "@baseboard_fab2_lib.baseboard_fab2(sch_1):m_e_dq(16)" )
			)
			( signal "M_E_DQ<17>"
				( objectStatus "@baseboard_fab2_lib.baseboard_fab2(sch_1):m_e_dq(17)" )
			)
			( signal "M_E_DQ<18>"
				( objectStatus "@baseboard_fab2_lib.baseboard_fab2(sch_1):m_e_dq(18)" )
			)
			( signal "M_E_DQ<19>"
				( objectStatus "@baseboard_fab2_lib.baseboard_fab2(sch_1):m_e_dq(19)" )
			)
			( signal "M_E_DQ<20>"
				( objectStatus "@baseboard_fab2_lib.baseboard_fab2(sch_1):m_e_dq(20)" )
			)
			( signal "M_E_DQ<21>"
				( objectStatus "@baseboard_fab2_lib.baseboard_fab2(sch_1):m_e_dq(21)" )
			)
			( signal "M_E_DQ<22>"
				( objectStatus "@baseboard_fab2_lib.baseboard_fab2(sch_1):m_e_dq(22)" )
			)
			( signal "M_E_DQ<23>"
				( objectStatus "@baseboard_fab2_lib.baseboard_fab2(sch_1):m_e_dq(23)" )
			)
			( signal "M_E_DQ<24>"
				( objectStatus "@baseboard_fab2_lib.baseboard_fab2(sch_1):m_e_dq(24)" )
			)
			( signal "M_E_DQ<25>"
				( objectStatus "@baseboard_fab2_lib.baseboard_fab2(sch_1):m_e_dq(25)" )
			)
			( signal "M_E_DQ<26>"
				( objectStatus "@baseboard_fab2_lib.baseboard_fab2(sch_1):m_e_dq(26)" )
			)
			( signal "M_E_DQ<27>"
				( objectStatus "@baseboard_fab2_lib.baseboard_fab2(sch_1):m_e_dq(27)" )
			)
			( signal "M_E_DQ<28>"
				( objectStatus "@baseboard_fab2_lib.baseboard_fab2(sch_1):m_e_dq(28)" )
			)
			( signal "M_E_DQ<29>"
				( objectStatus "@baseboard_fab2_lib.baseboard_fab2(sch_1):m_e_dq(29)" )
			)
			( signal "M_E_DQ<30>"
				( objectStatus "@baseboard_fab2_lib.baseboard_fab2(sch_1):m_e_dq(30)" )
			)
			( signal "M_E_DQ<31>"
				( objectStatus "@baseboard_fab2_lib.baseboard_fab2(sch_1):m_e_dq(31)" )
			)
			( signal "M_E_DQ<32>"
				( objectStatus "@baseboard_fab2_lib.baseboard_fab2(sch_1):m_e_dq(32)" )
			)
			( signal "M_E_DQ<33>"
				( objectStatus "@baseboard_fab2_lib.baseboard_fab2(sch_1):m_e_dq(33)" )
			)
			( signal "M_E_DQ<34>"
				( objectStatus "@baseboard_fab2_lib.baseboard_fab2(sch_1):m_e_dq(34)" )
			)
			( signal "M_E_DQ<35>"
				( objectStatus "@baseboard_fab2_lib.baseboard_fab2(sch_1):m_e_dq(35)" )
			)
			( signal "M_E_DQ<36>"
				( objectStatus "@baseboard_fab2_lib.baseboard_fab2(sch_1):m_e_dq(36)" )
			)
			( signal "M_E_DQ<37>"
				( objectStatus "@baseboard_fab2_lib.baseboard_fab2(sch_1):m_e_dq(37)" )
			)
			( signal "M_E_DQ<38>"
				( objectStatus "@baseboard_fab2_lib.baseboard_fab2(sch_1):m_e_dq(38)" )
			)
			( signal "M_E_DQ<39>"
				( objectStatus "@baseboard_fab2_lib.baseboard_fab2(sch_1):m_e_dq(39)" )
			)
			( signal "M_E_DQ<40>"
				( objectStatus "@baseboard_fab2_lib.baseboard_fab2(sch_1):m_e_dq(40)" )
			)
			( signal "M_E_DQ<41>"
				( objectStatus "@baseboard_fab2_lib.baseboard_fab2(sch_1):m_e_dq(41)" )
			)
			( signal "M_E_DQ<42>"
				( objectStatus "@baseboard_fab2_lib.baseboard_fab2(sch_1):m_e_dq(42)" )
			)
			( signal "M_E_DQ<43>"
				( objectStatus "@baseboard_fab2_lib.baseboard_fab2(sch_1):m_e_dq(43)" )
			)
			( signal "M_E_DQ<44>"
				( objectStatus "@baseboard_fab2_lib.baseboard_fab2(sch_1):m_e_dq(44)" )
			)
			( signal "M_E_DQ<45>"
				( objectStatus "@baseboard_fab2_lib.baseboard_fab2(sch_1):m_e_dq(45)" )
			)
			( signal "M_E_DQ<46>"
				( objectStatus "@baseboard_fab2_lib.baseboard_fab2(sch_1):m_e_dq(46)" )
			)
			( signal "M_E_DQ<47>"
				( objectStatus "@baseboard_fab2_lib.baseboard_fab2(sch_1):m_e_dq(47)" )
			)
			( signal "M_E_DQ<48>"
				( objectStatus "@baseboard_fab2_lib.baseboard_fab2(sch_1):m_e_dq(48)" )
			)
			( signal "M_E_DQ<49>"
				( objectStatus "@baseboard_fab2_lib.baseboard_fab2(sch_1):m_e_dq(49)" )
			)
			( signal "M_E_DQ<50>"
				( objectStatus "@baseboard_fab2_lib.baseboard_fab2(sch_1):m_e_dq(50)" )
			)
			( signal "M_E_DQ<51>"
				( objectStatus "@baseboard_fab2_lib.baseboard_fab2(sch_1):m_e_dq(51)" )
			)
			( signal "M_E_DQ<52>"
				( objectStatus "@baseboard_fab2_lib.baseboard_fab2(sch_1):m_e_dq(52)" )
			)
			( signal "M_E_DQ<53>"
				( objectStatus "@baseboard_fab2_lib.baseboard_fab2(sch_1):m_e_dq(53)" )
			)
			( signal "M_E_DQ<54>"
				( objectStatus "@baseboard_fab2_lib.baseboard_fab2(sch_1):m_e_dq(54)" )
			)
			( signal "M_E_DQ<55>"
				( objectStatus "@baseboard_fab2_lib.baseboard_fab2(sch_1):m_e_dq(55)" )
			)
			( signal "M_E_DQ<56>"
				( objectStatus "@baseboard_fab2_lib.baseboard_fab2(sch_1):m_e_dq(56)" )
			)
			( signal "M_E_DQ<57>"
				( objectStatus "@baseboard_fab2_lib.baseboard_fab2(sch_1):m_e_dq(57)" )
			)
			( signal "M_E_DQ<58>"
				( objectStatus "@baseboard_fab2_lib.baseboard_fab2(sch_1):m_e_dq(58)" )
			)
			( signal "M_E_DQ<59>"
				( objectStatus "@baseboard_fab2_lib.baseboard_fab2(sch_1):m_e_dq(59)" )
			)
			( signal "M_E_DQ<60>"
				( objectStatus "@baseboard_fab2_lib.baseboard_fab2(sch_1):m_e_dq(60)" )
			)
			( signal "M_E_DQ<61>"
				( objectStatus "@baseboard_fab2_lib.baseboard_fab2(sch_1):m_e_dq(61)" )
			)
			( signal "M_E_DQ<62>"
				( objectStatus "@baseboard_fab2_lib.baseboard_fab2(sch_1):m_e_dq(62)" )
			)
			( signal "M_E_DQ<63>"
				( objectStatus "@baseboard_fab2_lib.baseboard_fab2(sch_1):m_e_dq(63)" )
			)
			( signal "M_E_DQS_DN<0>"
				( objectStatus "@baseboard_fab2_lib.baseboard_fab2(sch_1):m_e_dqs_dn(0)" )
			)
			( signal "M_E_DQS_DN<1>"
				( objectStatus "@baseboard_fab2_lib.baseboard_fab2(sch_1):m_e_dqs_dn(1)" )
			)
			( signal "M_E_DQS_DN<2>"
				( objectStatus "@baseboard_fab2_lib.baseboard_fab2(sch_1):m_e_dqs_dn(2)" )
			)
			( signal "M_E_DQS_DN<3>"
				( objectStatus "@baseboard_fab2_lib.baseboard_fab2(sch_1):m_e_dqs_dn(3)" )
			)
			( signal "M_E_DQS_DN<4>"
				( objectStatus "@baseboard_fab2_lib.baseboard_fab2(sch_1):m_e_dqs_dn(4)" )
			)
			( signal "M_E_DQS_DN<5>"
				( objectStatus "@baseboard_fab2_lib.baseboard_fab2(sch_1):m_e_dqs_dn(5)" )
			)
			( signal "M_E_DQS_DN<6>"
				( objectStatus "@baseboard_fab2_lib.baseboard_fab2(sch_1):m_e_dqs_dn(6)" )
			)
			( signal "M_E_DQS_DN<7>"
				( objectStatus "@baseboard_fab2_lib.baseboard_fab2(sch_1):m_e_dqs_dn(7)" )
			)
			( signal "M_E_DQS_DN<8>"
				( objectStatus "@baseboard_fab2_lib.baseboard_fab2(sch_1):m_e_dqs_dn(8)" )
			)
			( signal "M_E_DQS_DN<9>"
				( objectStatus "@baseboard_fab2_lib.baseboard_fab2(sch_1):m_e_dqs_dn(9)" )
			)
			( signal "M_E_DQS_DN<10>"
				( objectStatus "@baseboard_fab2_lib.baseboard_fab2(sch_1):m_e_dqs_dn(10)" )
			)
			( signal "M_E_DQS_DN<11>"
				( objectStatus "@baseboard_fab2_lib.baseboard_fab2(sch_1):m_e_dqs_dn(11)" )
			)
			( signal "M_E_DQS_DN<12>"
				( objectStatus "@baseboard_fab2_lib.baseboard_fab2(sch_1):m_e_dqs_dn(12)" )
			)
			( signal "M_E_DQS_DN<13>"
				( objectStatus "@baseboard_fab2_lib.baseboard_fab2(sch_1):m_e_dqs_dn(13)" )
			)
			( signal "M_E_DQS_DN<14>"
				( objectStatus "@baseboard_fab2_lib.baseboard_fab2(sch_1):m_e_dqs_dn(14)" )
			)
			( signal "M_E_DQS_DN<15>"
				( objectStatus "@baseboard_fab2_lib.baseboard_fab2(sch_1):m_e_dqs_dn(15)" )
			)
			( signal "M_E_DQS_DN<16>"
				( objectStatus "@baseboard_fab2_lib.baseboard_fab2(sch_1):m_e_dqs_dn(16)" )
			)
			( signal "M_E_DQS_DN<17>"
				( objectStatus "@baseboard_fab2_lib.baseboard_fab2(sch_1):m_e_dqs_dn(17)" )
			)
			( signal "M_E_DQS_DP<0>"
				( objectStatus "@baseboard_fab2_lib.baseboard_fab2(sch_1):m_e_dqs_dp(0)" )
			)
			( signal "M_E_DQS_DP<1>"
				( objectStatus "@baseboard_fab2_lib.baseboard_fab2(sch_1):m_e_dqs_dp(1)" )
			)
			( signal "M_E_DQS_DP<2>"
				( objectStatus "@baseboard_fab2_lib.baseboard_fab2(sch_1):m_e_dqs_dp(2)" )
			)
			( signal "M_E_DQS_DP<3>"
				( objectStatus "@baseboard_fab2_lib.baseboard_fab2(sch_1):m_e_dqs_dp(3)" )
			)
			( signal "M_E_DQS_DP<4>"
				( objectStatus "@baseboard_fab2_lib.baseboard_fab2(sch_1):m_e_dqs_dp(4)" )
			)
			( signal "M_E_DQS_DP<5>"
				( objectStatus "@baseboard_fab2_lib.baseboard_fab2(sch_1):m_e_dqs_dp(5)" )
			)
			( signal "M_E_DQS_DP<6>"
				( objectStatus "@baseboard_fab2_lib.baseboard_fab2(sch_1):m_e_dqs_dp(6)" )
			)
			( signal "M_E_DQS_DP<7>"
				( objectStatus "@baseboard_fab2_lib.baseboard_fab2(sch_1):m_e_dqs_dp(7)" )
			)
			( signal "M_E_DQS_DP<8>"
				( objectStatus "@baseboard_fab2_lib.baseboard_fab2(sch_1):m_e_dqs_dp(8)" )
			)
			( signal "M_E_DQS_DP<9>"
				( objectStatus "@baseboard_fab2_lib.baseboard_fab2(sch_1):m_e_dqs_dp(9)" )
			)
			( signal "M_E_DQS_DP<10>"
				( objectStatus "@baseboard_fab2_lib.baseboard_fab2(sch_1):m_e_dqs_dp(10)" )
			)
			( signal "M_E_DQS_DP<11>"
				( objectStatus "@baseboard_fab2_lib.baseboard_fab2(sch_1):m_e_dqs_dp(11)" )
			)
			( signal "M_E_DQS_DP<12>"
				( objectStatus "@baseboard_fab2_lib.baseboard_fab2(sch_1):m_e_dqs_dp(12)" )
			)
			( signal "M_E_DQS_DP<13>"
				( objectStatus "@baseboard_fab2_lib.baseboard_fab2(sch_1):m_e_dqs_dp(13)" )
			)
			( signal "M_E_DQS_DP<14>"
				( objectStatus "@baseboard_fab2_lib.baseboard_fab2(sch_1):m_e_dqs_dp(14)" )
			)
			( signal "M_E_DQS_DP<15>"
				( objectStatus "@baseboard_fab2_lib.baseboard_fab2(sch_1):m_e_dqs_dp(15)" )
			)
			( signal "M_E_DQS_DP<16>"
				( objectStatus "@baseboard_fab2_lib.baseboard_fab2(sch_1):m_e_dqs_dp(16)" )
			)
			( signal "M_E_DQS_DP<17>"
				( objectStatus "@baseboard_fab2_lib.baseboard_fab2(sch_1):m_e_dqs_dp(17)" )
			)
			( signal "M_E_ECC<0>"
				( objectStatus "@baseboard_fab2_lib.baseboard_fab2(sch_1):m_e_ecc(0)" )
			)
			( signal "M_E_ECC<1>"
				( objectStatus "@baseboard_fab2_lib.baseboard_fab2(sch_1):m_e_ecc(1)" )
			)
			( signal "M_E_ECC<2>"
				( objectStatus "@baseboard_fab2_lib.baseboard_fab2(sch_1):m_e_ecc(2)" )
			)
			( signal "M_E_ECC<3>"
				( objectStatus "@baseboard_fab2_lib.baseboard_fab2(sch_1):m_e_ecc(3)" )
			)
			( signal "M_E_ECC<4>"
				( objectStatus "@baseboard_fab2_lib.baseboard_fab2(sch_1):m_e_ecc(4)" )
			)
			( signal "M_E_ECC<5>"
				( objectStatus "@baseboard_fab2_lib.baseboard_fab2(sch_1):m_e_ecc(5)" )
			)
			( signal "M_E_ECC<6>"
				( objectStatus "@baseboard_fab2_lib.baseboard_fab2(sch_1):m_e_ecc(6)" )
			)
			( signal "M_E_ECC<7>"
				( objectStatus "@baseboard_fab2_lib.baseboard_fab2(sch_1):m_e_ecc(7)" )
			)
			( signal "M_E_MA<0>"
				( objectStatus "@baseboard_fab2_lib.baseboard_fab2(sch_1):m_e_ma(0)" )
			)
			( signal "M_E_MA<1>"
				( objectStatus "@baseboard_fab2_lib.baseboard_fab2(sch_1):m_e_ma(1)" )
			)
			( signal "M_E_MA<2>"
				( objectStatus "@baseboard_fab2_lib.baseboard_fab2(sch_1):m_e_ma(2)" )
			)
			( signal "M_E_MA<3>"
				( objectStatus "@baseboard_fab2_lib.baseboard_fab2(sch_1):m_e_ma(3)" )
			)
			( signal "M_E_MA<4>"
				( objectStatus "@baseboard_fab2_lib.baseboard_fab2(sch_1):m_e_ma(4)" )
			)
			( signal "M_E_MA<5>"
				( objectStatus "@baseboard_fab2_lib.baseboard_fab2(sch_1):m_e_ma(5)" )
			)
			( signal "M_E_MA<6>"
				( objectStatus "@baseboard_fab2_lib.baseboard_fab2(sch_1):m_e_ma(6)" )
			)
			( signal "M_E_MA<7>"
				( objectStatus "@baseboard_fab2_lib.baseboard_fab2(sch_1):m_e_ma(7)" )
			)
			( signal "M_E_MA<8>"
				( objectStatus "@baseboard_fab2_lib.baseboard_fab2(sch_1):m_e_ma(8)" )
			)
			( signal "M_E_MA<9>"
				( objectStatus "@baseboard_fab2_lib.baseboard_fab2(sch_1):m_e_ma(9)" )
			)
			( signal "M_E_MA<10>"
				( objectStatus "@baseboard_fab2_lib.baseboard_fab2(sch_1):m_e_ma(10)" )
			)
			( signal "M_E_MA<11>"
				( objectStatus "@baseboard_fab2_lib.baseboard_fab2(sch_1):m_e_ma(11)" )
			)
			( signal "M_E_MA<12>"
				( objectStatus "@baseboard_fab2_lib.baseboard_fab2(sch_1):m_e_ma(12)" )
			)
			( signal "M_E_MA<13>"
				( objectStatus "@baseboard_fab2_lib.baseboard_fab2(sch_1):m_e_ma(13)" )
			)
			( signal "M_E_MA<14>"
				( objectStatus "@baseboard_fab2_lib.baseboard_fab2(sch_1):m_e_ma(14)" )
			)
			( signal "M_E_MA<15>"
				( objectStatus "@baseboard_fab2_lib.baseboard_fab2(sch_1):m_e_ma(15)" )
			)
			( signal "M_E_MA<16>"
				( objectStatus "@baseboard_fab2_lib.baseboard_fab2(sch_1):m_e_ma(16)" )
			)
			( signal "M_E_MA<17>"
				( objectStatus "@baseboard_fab2_lib.baseboard_fab2(sch_1):m_e_ma(17)" )
			)
			( signal "M_E_ODT<0>"
				( objectStatus "@baseboard_fab2_lib.baseboard_fab2(sch_1):m_e_odt(0)" )
			)
			( signal "M_E_ODT<1>"
				( objectStatus "@baseboard_fab2_lib.baseboard_fab2(sch_1):m_e_odt(1)" )
			)
			( signal "M_E_ODT<2>"
				( objectStatus "@baseboard_fab2_lib.baseboard_fab2(sch_1):m_e_odt(2)" )
			)
			( signal "M_E_ODT<3>"
				( objectStatus "@baseboard_fab2_lib.baseboard_fab2(sch_1):m_e_odt(3)" )
			)
			( signal "M_E_PAR"
				( objectStatus "@baseboard_fab2_lib.baseboard_fab2(sch_1):m_e_par" )
			)
			( signal "M_F_ACT_N"
				( objectStatus "@baseboard_fab2_lib.baseboard_fab2(sch_1):m_f_act_n" )
			)
			( signal "M_F_ALERT_N"
				( objectStatus "@baseboard_fab2_lib.baseboard_fab2(sch_1):m_f_alert_n" )
			)
			( signal "M_F_BA<0>"
				( objectStatus "@baseboard_fab2_lib.baseboard_fab2(sch_1):m_f_ba(0)" )
			)
			( signal "M_F_BA<1>"
				( objectStatus "@baseboard_fab2_lib.baseboard_fab2(sch_1):m_f_ba(1)" )
			)
			( signal "M_F_BG<0>"
				( objectStatus "@baseboard_fab2_lib.baseboard_fab2(sch_1):m_f_bg(0)" )
			)
			( signal "M_F_BG<1>"
				( objectStatus "@baseboard_fab2_lib.baseboard_fab2(sch_1):m_f_bg(1)" )
			)
			( signal "M_F_C<2>"
				( objectStatus "@baseboard_fab2_lib.baseboard_fab2(sch_1):m_f_c(2)" )
			)
			( signal "M_F_CKE<0>"
				( objectStatus "@baseboard_fab2_lib.baseboard_fab2(sch_1):m_f_cke(0)" )
			)
			( signal "M_F_CKE<1>"
				( objectStatus "@baseboard_fab2_lib.baseboard_fab2(sch_1):m_f_cke(1)" )
			)
			( signal "M_F_CKE<2>"
				( objectStatus "@baseboard_fab2_lib.baseboard_fab2(sch_1):m_f_cke(2)" )
			)
			( signal "M_F_CKE<3>"
				( objectStatus "@baseboard_fab2_lib.baseboard_fab2(sch_1):m_f_cke(3)" )
			)
			( signal "M_F_CLK_DN<0>"
				( objectStatus "@baseboard_fab2_lib.baseboard_fab2(sch_1):m_f_clk_dn(0)" )
			)
			( signal "M_F_CLK_DN<1>"
				( objectStatus "@baseboard_fab2_lib.baseboard_fab2(sch_1):m_f_clk_dn(1)" )
			)
			( signal "M_F_CLK_DN<2>"
				( objectStatus "@baseboard_fab2_lib.baseboard_fab2(sch_1):m_f_clk_dn(2)" )
			)
			( signal "M_F_CLK_DN<3>"
				( objectStatus "@baseboard_fab2_lib.baseboard_fab2(sch_1):m_f_clk_dn(3)" )
			)
			( signal "M_F_CLK_DP<0>"
				( objectStatus "@baseboard_fab2_lib.baseboard_fab2(sch_1):m_f_clk_dp(0)" )
			)
			( signal "M_F_CLK_DP<1>"
				( objectStatus "@baseboard_fab2_lib.baseboard_fab2(sch_1):m_f_clk_dp(1)" )
			)
			( signal "M_F_CLK_DP<2>"
				( objectStatus "@baseboard_fab2_lib.baseboard_fab2(sch_1):m_f_clk_dp(2)" )
			)
			( signal "M_F_CLK_DP<3>"
				( objectStatus "@baseboard_fab2_lib.baseboard_fab2(sch_1):m_f_clk_dp(3)" )
			)
			( signal "M_F_CS_N<0>"
				( objectStatus "@baseboard_fab2_lib.baseboard_fab2(sch_1):m_f_cs_n(0)" )
			)
			( signal "M_F_CS_N<1>"
				( objectStatus "@baseboard_fab2_lib.baseboard_fab2(sch_1):m_f_cs_n(1)" )
			)
			( signal "M_F_CS_N<2>"
				( objectStatus "@baseboard_fab2_lib.baseboard_fab2(sch_1):m_f_cs_n(2)" )
			)
			( signal "M_F_CS_N<3>"
				( objectStatus "@baseboard_fab2_lib.baseboard_fab2(sch_1):m_f_cs_n(3)" )
			)
			( signal "M_F_CS_N<4>"
				( objectStatus "@baseboard_fab2_lib.baseboard_fab2(sch_1):m_f_cs_n(4)" )
			)
			( signal "M_F_CS_N<5>"
				( objectStatus "@baseboard_fab2_lib.baseboard_fab2(sch_1):m_f_cs_n(5)" )
			)
			( signal "M_F_CS_N<6>"
				( objectStatus "@baseboard_fab2_lib.baseboard_fab2(sch_1):m_f_cs_n(6)" )
			)
			( signal "M_F_CS_N<7>"
				( objectStatus "@baseboard_fab2_lib.baseboard_fab2(sch_1):m_f_cs_n(7)" )
			)
			( signal "M_F_DQ<0>"
				( objectStatus "@baseboard_fab2_lib.baseboard_fab2(sch_1):m_f_dq(0)" )
			)
			( signal "M_F_DQ<1>"
				( objectStatus "@baseboard_fab2_lib.baseboard_fab2(sch_1):m_f_dq(1)" )
			)
			( signal "M_F_DQ<2>"
				( objectStatus "@baseboard_fab2_lib.baseboard_fab2(sch_1):m_f_dq(2)" )
			)
			( signal "M_F_DQ<3>"
				( objectStatus "@baseboard_fab2_lib.baseboard_fab2(sch_1):m_f_dq(3)" )
			)
			( signal "M_F_DQ<4>"
				( objectStatus "@baseboard_fab2_lib.baseboard_fab2(sch_1):m_f_dq(4)" )
			)
			( signal "M_F_DQ<5>"
				( objectStatus "@baseboard_fab2_lib.baseboard_fab2(sch_1):m_f_dq(5)" )
			)
			( signal "M_F_DQ<6>"
				( objectStatus "@baseboard_fab2_lib.baseboard_fab2(sch_1):m_f_dq(6)" )
			)
			( signal "M_F_DQ<7>"
				( objectStatus "@baseboard_fab2_lib.baseboard_fab2(sch_1):m_f_dq(7)" )
			)
			( signal "M_F_DQ<8>"
				( objectStatus "@baseboard_fab2_lib.baseboard_fab2(sch_1):m_f_dq(8)" )
			)
			( signal "M_F_DQ<9>"
				( objectStatus "@baseboard_fab2_lib.baseboard_fab2(sch_1):m_f_dq(9)" )
			)
			( signal "M_F_DQ<10>"
				( objectStatus "@baseboard_fab2_lib.baseboard_fab2(sch_1):m_f_dq(10)" )
			)
			( signal "M_F_DQ<11>"
				( objectStatus "@baseboard_fab2_lib.baseboard_fab2(sch_1):m_f_dq(11)" )
			)
			( signal "M_F_DQ<12>"
				( objectStatus "@baseboard_fab2_lib.baseboard_fab2(sch_1):m_f_dq(12)" )
			)
			( signal "M_F_DQ<13>"
				( objectStatus "@baseboard_fab2_lib.baseboard_fab2(sch_1):m_f_dq(13)" )
			)
			( signal "M_F_DQ<14>"
				( objectStatus "@baseboard_fab2_lib.baseboard_fab2(sch_1):m_f_dq(14)" )
			)
			( signal "M_F_DQ<15>"
				( objectStatus "@baseboard_fab2_lib.baseboard_fab2(sch_1):m_f_dq(15)" )
			)
			( signal "M_F_DQ<16>"
				( objectStatus "@baseboard_fab2_lib.baseboard_fab2(sch_1):m_f_dq(16)" )
			)
			( signal "M_F_DQ<17>"
				( objectStatus "@baseboard_fab2_lib.baseboard_fab2(sch_1):m_f_dq(17)" )
			)
			( signal "M_F_DQ<18>"
				( objectStatus "@baseboard_fab2_lib.baseboard_fab2(sch_1):m_f_dq(18)" )
			)
			( signal "M_F_DQ<19>"
				( objectStatus "@baseboard_fab2_lib.baseboard_fab2(sch_1):m_f_dq(19)" )
			)
			( signal "M_F_DQ<20>"
				( objectStatus "@baseboard_fab2_lib.baseboard_fab2(sch_1):m_f_dq(20)" )
			)
			( signal "M_F_DQ<21>"
				( objectStatus "@baseboard_fab2_lib.baseboard_fab2(sch_1):m_f_dq(21)" )
			)
			( signal "M_F_DQ<22>"
				( objectStatus "@baseboard_fab2_lib.baseboard_fab2(sch_1):m_f_dq(22)" )
			)
			( signal "M_F_DQ<23>"
				( objectStatus "@baseboard_fab2_lib.baseboard_fab2(sch_1):m_f_dq(23)" )
			)
			( signal "M_F_DQ<24>"
				( objectStatus "@baseboard_fab2_lib.baseboard_fab2(sch_1):m_f_dq(24)" )
			)
			( signal "M_F_DQ<25>"
				( objectStatus "@baseboard_fab2_lib.baseboard_fab2(sch_1):m_f_dq(25)" )
			)
			( signal "M_F_DQ<26>"
				( objectStatus "@baseboard_fab2_lib.baseboard_fab2(sch_1):m_f_dq(26)" )
			)
			( signal "M_F_DQ<27>"
				( objectStatus "@baseboard_fab2_lib.baseboard_fab2(sch_1):m_f_dq(27)" )
			)
			( signal "M_F_DQ<28>"
				( objectStatus "@baseboard_fab2_lib.baseboard_fab2(sch_1):m_f_dq(28)" )
			)
			( signal "M_F_DQ<29>"
				( objectStatus "@baseboard_fab2_lib.baseboard_fab2(sch_1):m_f_dq(29)" )
			)
			( signal "M_F_DQ<30>"
				( objectStatus "@baseboard_fab2_lib.baseboard_fab2(sch_1):m_f_dq(30)" )
			)
			( signal "M_F_DQ<31>"
				( objectStatus "@baseboard_fab2_lib.baseboard_fab2(sch_1):m_f_dq(31)" )
			)
			( signal "M_F_DQ<32>"
				( objectStatus "@baseboard_fab2_lib.baseboard_fab2(sch_1):m_f_dq(32)" )
			)
			( signal "M_F_DQ<33>"
				( objectStatus "@baseboard_fab2_lib.baseboard_fab2(sch_1):m_f_dq(33)" )
			)
			( signal "M_F_DQ<34>"
				( objectStatus "@baseboard_fab2_lib.baseboard_fab2(sch_1):m_f_dq(34)" )
			)
			( signal "M_F_DQ<35>"
				( objectStatus "@baseboard_fab2_lib.baseboard_fab2(sch_1):m_f_dq(35)" )
			)
			( signal "M_F_DQ<36>"
				( objectStatus "@baseboard_fab2_lib.baseboard_fab2(sch_1):m_f_dq(36)" )
			)
			( signal "M_F_DQ<37>"
				( objectStatus "@baseboard_fab2_lib.baseboard_fab2(sch_1):m_f_dq(37)" )
			)
			( signal "M_F_DQ<38>"
				( objectStatus "@baseboard_fab2_lib.baseboard_fab2(sch_1):m_f_dq(38)" )
			)
			( signal "M_F_DQ<39>"
				( objectStatus "@baseboard_fab2_lib.baseboard_fab2(sch_1):m_f_dq(39)" )
			)
			( signal "M_F_DQ<40>"
				( objectStatus "@baseboard_fab2_lib.baseboard_fab2(sch_1):m_f_dq(40)" )
			)
			( signal "M_F_DQ<41>"
				( objectStatus "@baseboard_fab2_lib.baseboard_fab2(sch_1):m_f_dq(41)" )
			)
			( signal "M_F_DQ<42>"
				( objectStatus "@baseboard_fab2_lib.baseboard_fab2(sch_1):m_f_dq(42)" )
			)
			( signal "M_F_DQ<43>"
				( objectStatus "@baseboard_fab2_lib.baseboard_fab2(sch_1):m_f_dq(43)" )
			)
			( signal "M_F_DQ<44>"
				( objectStatus "@baseboard_fab2_lib.baseboard_fab2(sch_1):m_f_dq(44)" )
			)
			( signal "M_F_DQ<45>"
				( objectStatus "@baseboard_fab2_lib.baseboard_fab2(sch_1):m_f_dq(45)" )
			)
			( signal "M_F_DQ<46>"
				( objectStatus "@baseboard_fab2_lib.baseboard_fab2(sch_1):m_f_dq(46)" )
			)
			( signal "M_F_DQ<47>"
				( objectStatus "@baseboard_fab2_lib.baseboard_fab2(sch_1):m_f_dq(47)" )
			)
			( signal "M_F_DQ<48>"
				( objectStatus "@baseboard_fab2_lib.baseboard_fab2(sch_1):m_f_dq(48)" )
			)
			( signal "M_F_DQ<49>"
				( objectStatus "@baseboard_fab2_lib.baseboard_fab2(sch_1):m_f_dq(49)" )
			)
			( signal "M_F_DQ<50>"
				( objectStatus "@baseboard_fab2_lib.baseboard_fab2(sch_1):m_f_dq(50)" )
			)
			( signal "M_F_DQ<51>"
				( objectStatus "@baseboard_fab2_lib.baseboard_fab2(sch_1):m_f_dq(51)" )
			)
			( signal "M_F_DQ<52>"
				( objectStatus "@baseboard_fab2_lib.baseboard_fab2(sch_1):m_f_dq(52)" )
			)
			( signal "M_F_DQ<53>"
				( objectStatus "@baseboard_fab2_lib.baseboard_fab2(sch_1):m_f_dq(53)" )
			)
			( signal "M_F_DQ<54>"
				( objectStatus "@baseboard_fab2_lib.baseboard_fab2(sch_1):m_f_dq(54)" )
			)
			( signal "M_F_DQ<55>"
				( objectStatus "@baseboard_fab2_lib.baseboard_fab2(sch_1):m_f_dq(55)" )
			)
			( signal "M_F_DQ<56>"
				( objectStatus "@baseboard_fab2_lib.baseboard_fab2(sch_1):m_f_dq(56)" )
			)
			( signal "M_F_DQ<57>"
				( objectStatus "@baseboard_fab2_lib.baseboard_fab2(sch_1):m_f_dq(57)" )
			)
			( signal "M_F_DQ<58>"
				( objectStatus "@baseboard_fab2_lib.baseboard_fab2(sch_1):m_f_dq(58)" )
			)
			( signal "M_F_DQ<59>"
				( objectStatus "@baseboard_fab2_lib.baseboard_fab2(sch_1):m_f_dq(59)" )
			)
			( signal "M_F_DQ<60>"
				( objectStatus "@baseboard_fab2_lib.baseboard_fab2(sch_1):m_f_dq(60)" )
			)
			( signal "M_F_DQ<61>"
				( objectStatus "@baseboard_fab2_lib.baseboard_fab2(sch_1):m_f_dq(61)" )
			)
			( signal "M_F_DQ<62>"
				( objectStatus "@baseboard_fab2_lib.baseboard_fab2(sch_1):m_f_dq(62)" )
			)
			( signal "M_F_DQ<63>"
				( objectStatus "@baseboard_fab2_lib.baseboard_fab2(sch_1):m_f_dq(63)" )
			)
			( signal "M_F_DQS_DN<0>"
				( objectStatus "@baseboard_fab2_lib.baseboard_fab2(sch_1):m_f_dqs_dn(0)" )
			)
			( signal "M_F_DQS_DN<1>"
				( objectStatus "@baseboard_fab2_lib.baseboard_fab2(sch_1):m_f_dqs_dn(1)" )
			)
			( signal "M_F_DQS_DN<2>"
				( objectStatus "@baseboard_fab2_lib.baseboard_fab2(sch_1):m_f_dqs_dn(2)" )
			)
			( signal "M_F_DQS_DN<3>"
				( objectStatus "@baseboard_fab2_lib.baseboard_fab2(sch_1):m_f_dqs_dn(3)" )
			)
			( signal "M_F_DQS_DN<4>"
				( objectStatus "@baseboard_fab2_lib.baseboard_fab2(sch_1):m_f_dqs_dn(4)" )
			)
			( signal "M_F_DQS_DN<5>"
				( objectStatus "@baseboard_fab2_lib.baseboard_fab2(sch_1):m_f_dqs_dn(5)" )
			)
			( signal "M_F_DQS_DN<6>"
				( objectStatus "@baseboard_fab2_lib.baseboard_fab2(sch_1):m_f_dqs_dn(6)" )
			)
			( signal "M_F_DQS_DN<7>"
				( objectStatus "@baseboard_fab2_lib.baseboard_fab2(sch_1):m_f_dqs_dn(7)" )
			)
			( signal "M_F_DQS_DN<8>"
				( objectStatus "@baseboard_fab2_lib.baseboard_fab2(sch_1):m_f_dqs_dn(8)" )
			)
			( signal "M_F_DQS_DN<9>"
				( objectStatus "@baseboard_fab2_lib.baseboard_fab2(sch_1):m_f_dqs_dn(9)" )
			)
			( signal "M_F_DQS_DN<10>"
				( objectStatus "@baseboard_fab2_lib.baseboard_fab2(sch_1):m_f_dqs_dn(10)" )
			)
			( signal "M_F_DQS_DN<11>"
				( objectStatus "@baseboard_fab2_lib.baseboard_fab2(sch_1):m_f_dqs_dn(11)" )
			)
			( signal "M_F_DQS_DN<12>"
				( objectStatus "@baseboard_fab2_lib.baseboard_fab2(sch_1):m_f_dqs_dn(12)" )
			)
			( signal "M_F_DQS_DN<13>"
				( objectStatus "@baseboard_fab2_lib.baseboard_fab2(sch_1):m_f_dqs_dn(13)" )
			)
			( signal "M_F_DQS_DN<14>"
				( objectStatus "@baseboard_fab2_lib.baseboard_fab2(sch_1):m_f_dqs_dn(14)" )
			)
			( signal "M_F_DQS_DN<15>"
				( objectStatus "@baseboard_fab2_lib.baseboard_fab2(sch_1):m_f_dqs_dn(15)" )
			)
			( signal "M_F_DQS_DN<16>"
				( objectStatus "@baseboard_fab2_lib.baseboard_fab2(sch_1):m_f_dqs_dn(16)" )
			)
			( signal "M_F_DQS_DN<17>"
				( objectStatus "@baseboard_fab2_lib.baseboard_fab2(sch_1):m_f_dqs_dn(17)" )
			)
			( signal "M_F_DQS_DP<0>"
				( objectStatus "@baseboard_fab2_lib.baseboard_fab2(sch_1):m_f_dqs_dp(0)" )
			)
			( signal "M_F_DQS_DP<1>"
				( objectStatus "@baseboard_fab2_lib.baseboard_fab2(sch_1):m_f_dqs_dp(1)" )
			)
			( signal "M_F_DQS_DP<2>"
				( objectStatus "@baseboard_fab2_lib.baseboard_fab2(sch_1):m_f_dqs_dp(2)" )
			)
			( signal "M_F_DQS_DP<3>"
				( objectStatus "@baseboard_fab2_lib.baseboard_fab2(sch_1):m_f_dqs_dp(3)" )
			)
			( signal "M_F_DQS_DP<4>"
				( objectStatus "@baseboard_fab2_lib.baseboard_fab2(sch_1):m_f_dqs_dp(4)" )
			)
			( signal "M_F_DQS_DP<5>"
				( objectStatus "@baseboard_fab2_lib.baseboard_fab2(sch_1):m_f_dqs_dp(5)" )
			)
			( signal "M_F_DQS_DP<6>"
				( objectStatus "@baseboard_fab2_lib.baseboard_fab2(sch_1):m_f_dqs_dp(6)" )
			)
			( signal "M_F_DQS_DP<7>"
				( objectStatus "@baseboard_fab2_lib.baseboard_fab2(sch_1):m_f_dqs_dp(7)" )
			)
			( signal "M_F_DQS_DP<8>"
				( objectStatus "@baseboard_fab2_lib.baseboard_fab2(sch_1):m_f_dqs_dp(8)" )
			)
			( signal "M_F_DQS_DP<9>"
				( objectStatus "@baseboard_fab2_lib.baseboard_fab2(sch_1):m_f_dqs_dp(9)" )
			)
			( signal "M_F_DQS_DP<10>"
				( objectStatus "@baseboard_fab2_lib.baseboard_fab2(sch_1):m_f_dqs_dp(10)" )
			)
			( signal "M_F_DQS_DP<11>"
				( objectStatus "@baseboard_fab2_lib.baseboard_fab2(sch_1):m_f_dqs_dp(11)" )
			)
			( signal "M_F_DQS_DP<12>"
				( objectStatus "@baseboard_fab2_lib.baseboard_fab2(sch_1):m_f_dqs_dp(12)" )
			)
			( signal "M_F_DQS_DP<13>"
				( objectStatus "@baseboard_fab2_lib.baseboard_fab2(sch_1):m_f_dqs_dp(13)" )
			)
			( signal "M_F_DQS_DP<14>"
				( objectStatus "@baseboard_fab2_lib.baseboard_fab2(sch_1):m_f_dqs_dp(14)" )
			)
			( signal "M_F_DQS_DP<15>"
				( objectStatus "@baseboard_fab2_lib.baseboard_fab2(sch_1):m_f_dqs_dp(15)" )
			)
			( signal "M_F_DQS_DP<16>"
				( objectStatus "@baseboard_fab2_lib.baseboard_fab2(sch_1):m_f_dqs_dp(16)" )
			)
			( signal "M_F_DQS_DP<17>"
				( objectStatus "@baseboard_fab2_lib.baseboard_fab2(sch_1):m_f_dqs_dp(17)" )
			)
			( signal "M_F_ECC<0>"
				( objectStatus "@baseboard_fab2_lib.baseboard_fab2(sch_1):m_f_ecc(0)" )
			)
			( signal "M_F_ECC<1>"
				( objectStatus "@baseboard_fab2_lib.baseboard_fab2(sch_1):m_f_ecc(1)" )
			)
			( signal "M_F_ECC<2>"
				( objectStatus "@baseboard_fab2_lib.baseboard_fab2(sch_1):m_f_ecc(2)" )
			)
			( signal "M_F_ECC<3>"
				( objectStatus "@baseboard_fab2_lib.baseboard_fab2(sch_1):m_f_ecc(3)" )
			)
			( signal "M_F_ECC<4>"
				( objectStatus "@baseboard_fab2_lib.baseboard_fab2(sch_1):m_f_ecc(4)" )
			)
			( signal "M_F_ECC<5>"
				( objectStatus "@baseboard_fab2_lib.baseboard_fab2(sch_1):m_f_ecc(5)" )
			)
			( signal "M_F_ECC<6>"
				( objectStatus "@baseboard_fab2_lib.baseboard_fab2(sch_1):m_f_ecc(6)" )
			)
			( signal "M_F_ECC<7>"
				( objectStatus "@baseboard_fab2_lib.baseboard_fab2(sch_1):m_f_ecc(7)" )
			)
			( signal "M_F_MA<0>"
				( objectStatus "@baseboard_fab2_lib.baseboard_fab2(sch_1):m_f_ma(0)" )
			)
			( signal "M_F_MA<1>"
				( objectStatus "@baseboard_fab2_lib.baseboard_fab2(sch_1):m_f_ma(1)" )
			)
			( signal "M_F_MA<2>"
				( objectStatus "@baseboard_fab2_lib.baseboard_fab2(sch_1):m_f_ma(2)" )
			)
			( signal "M_F_MA<3>"
				( objectStatus "@baseboard_fab2_lib.baseboard_fab2(sch_1):m_f_ma(3)" )
			)
			( signal "M_F_MA<4>"
				( objectStatus "@baseboard_fab2_lib.baseboard_fab2(sch_1):m_f_ma(4)" )
			)
			( signal "M_F_MA<5>"
				( objectStatus "@baseboard_fab2_lib.baseboard_fab2(sch_1):m_f_ma(5)" )
			)
			( signal "M_F_MA<6>"
				( objectStatus "@baseboard_fab2_lib.baseboard_fab2(sch_1):m_f_ma(6)" )
			)
			( signal "M_F_MA<7>"
				( objectStatus "@baseboard_fab2_lib.baseboard_fab2(sch_1):m_f_ma(7)" )
			)
			( signal "M_F_MA<8>"
				( objectStatus "@baseboard_fab2_lib.baseboard_fab2(sch_1):m_f_ma(8)" )
			)
			( signal "M_F_MA<9>"
				( objectStatus "@baseboard_fab2_lib.baseboard_fab2(sch_1):m_f_ma(9)" )
			)
			( signal "M_F_MA<10>"
				( objectStatus "@baseboard_fab2_lib.baseboard_fab2(sch_1):m_f_ma(10)" )
			)
			( signal "M_F_MA<11>"
				( objectStatus "@baseboard_fab2_lib.baseboard_fab2(sch_1):m_f_ma(11)" )
			)
			( signal "M_F_MA<12>"
				( objectStatus "@baseboard_fab2_lib.baseboard_fab2(sch_1):m_f_ma(12)" )
			)
			( signal "M_F_MA<13>"
				( objectStatus "@baseboard_fab2_lib.baseboard_fab2(sch_1):m_f_ma(13)" )
			)
			( signal "M_F_MA<14>"
				( objectStatus "@baseboard_fab2_lib.baseboard_fab2(sch_1):m_f_ma(14)" )
			)
			( signal "M_F_MA<15>"
				( objectStatus "@baseboard_fab2_lib.baseboard_fab2(sch_1):m_f_ma(15)" )
			)
			( signal "M_F_MA<16>"
				( objectStatus "@baseboard_fab2_lib.baseboard_fab2(sch_1):m_f_ma(16)" )
			)
			( signal "M_F_MA<17>"
				( objectStatus "@baseboard_fab2_lib.baseboard_fab2(sch_1):m_f_ma(17)" )
			)
			( signal "M_F_ODT<0>"
				( objectStatus "@baseboard_fab2_lib.baseboard_fab2(sch_1):m_f_odt(0)" )
			)
			( signal "M_F_ODT<1>"
				( objectStatus "@baseboard_fab2_lib.baseboard_fab2(sch_1):m_f_odt(1)" )
			)
			( signal "M_F_ODT<2>"
				( objectStatus "@baseboard_fab2_lib.baseboard_fab2(sch_1):m_f_odt(2)" )
			)
			( signal "M_F_ODT<3>"
				( objectStatus "@baseboard_fab2_lib.baseboard_fab2(sch_1):m_f_odt(3)" )
			)
			( signal "M_F_PAR"
				( objectStatus "@baseboard_fab2_lib.baseboard_fab2(sch_1):m_f_par" )
			)
			( signal "CLK_100M_CPU0_PE_REFCLK_DN"
				( objectStatus "@baseboard_fab2_lib.baseboard_fab2(sch_1):clk_100m_cpu0_pe_refclk_dn" )
			)
			( signal "CLK_100M_CPU0_PE_REFCLK_DP"
				( objectStatus "@baseboard_fab2_lib.baseboard_fab2(sch_1):clk_100m_cpu0_pe_refclk_dp" )
			)
			( signal "CLK_156M_OSC_CPU0_HFI_DN"
				( objectStatus "@baseboard_fab2_lib.baseboard_fab2(sch_1):clk_156m_osc_cpu0_hfi_dn" )
			)
			( signal "CLK_156M_OSC_CPU0_HFI_DP"
				( objectStatus "@baseboard_fab2_lib.baseboard_fab2(sch_1):clk_156m_osc_cpu0_hfi_dp" )
			)
			( signal "DMI_CPU0_PCH_RX_C_DN<0>"
				( objectStatus "@baseboard_fab2_lib.baseboard_fab2(sch_1):dmi_cpu0_pch_rx_c_dn(0)" )
			)
			( signal "DMI_CPU0_PCH_RX_C_DN<1>"
				( objectStatus "@baseboard_fab2_lib.baseboard_fab2(sch_1):dmi_cpu0_pch_rx_c_dn(1)" )
			)
			( signal "DMI_CPU0_PCH_RX_C_DN<2>"
				( objectStatus "@baseboard_fab2_lib.baseboard_fab2(sch_1):dmi_cpu0_pch_rx_c_dn(2)" )
			)
			( signal "DMI_CPU0_PCH_RX_C_DN<3>"
				( objectStatus "@baseboard_fab2_lib.baseboard_fab2(sch_1):dmi_cpu0_pch_rx_c_dn(3)" )
			)
			( signal "DMI_CPU0_PCH_RX_C_DP<0>"
				( objectStatus "@baseboard_fab2_lib.baseboard_fab2(sch_1):dmi_cpu0_pch_rx_c_dp(0)" )
			)
			( signal "DMI_CPU0_PCH_RX_C_DP<1>"
				( objectStatus "@baseboard_fab2_lib.baseboard_fab2(sch_1):dmi_cpu0_pch_rx_c_dp(1)" )
			)
			( signal "DMI_CPU0_PCH_RX_C_DP<2>"
				( objectStatus "@baseboard_fab2_lib.baseboard_fab2(sch_1):dmi_cpu0_pch_rx_c_dp(2)" )
			)
			( signal "DMI_CPU0_PCH_RX_C_DP<3>"
				( objectStatus "@baseboard_fab2_lib.baseboard_fab2(sch_1):dmi_cpu0_pch_rx_c_dp(3)" )
			)
			( signal "DMI_CPU0_PCH_TX_DN<0>"
				( objectStatus "@baseboard_fab2_lib.baseboard_fab2(sch_1):dmi_cpu0_pch_tx_dn(0)" )
			)
			( signal "DMI_CPU0_PCH_TX_DN<1>"
				( objectStatus "@baseboard_fab2_lib.baseboard_fab2(sch_1):dmi_cpu0_pch_tx_dn(1)" )
			)
			( signal "DMI_CPU0_PCH_TX_DN<2>"
				( objectStatus "@baseboard_fab2_lib.baseboard_fab2(sch_1):dmi_cpu0_pch_tx_dn(2)" )
			)
			( signal "DMI_CPU0_PCH_TX_DN<3>"
				( objectStatus "@baseboard_fab2_lib.baseboard_fab2(sch_1):dmi_cpu0_pch_tx_dn(3)" )
			)
			( signal "DMI_CPU0_PCH_TX_DP<0>"
				( objectStatus "@baseboard_fab2_lib.baseboard_fab2(sch_1):dmi_cpu0_pch_tx_dp(0)" )
			)
			( signal "DMI_CPU0_PCH_TX_DP<1>"
				( objectStatus "@baseboard_fab2_lib.baseboard_fab2(sch_1):dmi_cpu0_pch_tx_dp(1)" )
			)
			( signal "DMI_CPU0_PCH_TX_DP<2>"
				( objectStatus "@baseboard_fab2_lib.baseboard_fab2(sch_1):dmi_cpu0_pch_tx_dp(2)" )
			)
			( signal "DMI_CPU0_PCH_TX_DP<3>"
				( objectStatus "@baseboard_fab2_lib.baseboard_fab2(sch_1):dmi_cpu0_pch_tx_dp(3)" )
			)
			( signal "FM_MODPRST_HFI0_CPU0_LVT2_N"
				( objectStatus "@baseboard_fab2_lib.baseboard_fab2(sch_1):fm_modprst_hfi0_cpu0_lvt2_n" )
			)
			( signal "FM_MODPRST_HFI1_CPU0_LVT2_N"
				( objectStatus "@baseboard_fab2_lib.baseboard_fab2(sch_1):fm_modprst_hfi1_cpu0_lvt2_n" )
			)
			( signal "IRQ_HFI0_CPU0_LVT2_N"
				( objectStatus "@baseboard_fab2_lib.baseboard_fab2(sch_1):irq_hfi0_cpu0_lvt2_n" )
			)
			( signal "IRQ_HFI1_CPU0_LVT2_N"
				( objectStatus "@baseboard_fab2_lib.baseboard_fab2(sch_1):irq_hfi1_cpu0_lvt2_n" )
			)
			( signal "JTAG_MCP_CPU0_TDI"
				( objectStatus "@baseboard_fab2_lib.baseboard_fab2(sch_1):jtag_mcp_cpu0_tdi" )
			)
			( signal "JTAG_MCP_CPU0_TDO"
				( objectStatus "@baseboard_fab2_lib.baseboard_fab2(sch_1):jtag_mcp_cpu0_tdo" )
			)
			( signal "JTAG_MCP_TCK"
				( objectStatus "@baseboard_fab2_lib.baseboard_fab2(sch_1):jtag_mcp_tck" )
			)
			( signal "JTAG_MCP_TMS"
				( objectStatus "@baseboard_fab2_lib.baseboard_fab2(sch_1):jtag_mcp_tms" )
			)
			( signal "JTAG_MCP_TRST_N"
				( objectStatus "@baseboard_fab2_lib.baseboard_fab2(sch_1):jtag_mcp_trst_n" )
			)
			( signal "LED_HFI0_CPU0_N"
				( objectStatus "@baseboard_fab2_lib.baseboard_fab2(sch_1):led_hfi0_cpu0_n" )
			)
			( signal "LED_HFI1_CPU0_N"
				( objectStatus "@baseboard_fab2_lib.baseboard_fab2(sch_1):led_hfi1_cpu0_n" )
			)
			( signal "RST_CD_CPU0_POR_N"
				( objectStatus "@baseboard_fab2_lib.baseboard_fab2(sch_1):rst_cd_cpu0_por_n" )
			)
			( signal "RST_HFI0_CPU0_LVT2_N"
				( objectStatus "@baseboard_fab2_lib.baseboard_fab2(sch_1):rst_hfi0_cpu0_lvt2_n" )
			)
			( signal "RST_HFI1_CPU0_LVT2_N"
				( objectStatus "@baseboard_fab2_lib.baseboard_fab2(sch_1):rst_hfi1_cpu0_lvt2_n" )
			)
			( signal "SMB_HFI0_CPU0_LVC2_SCL"
				( objectStatus "@baseboard_fab2_lib.baseboard_fab2(sch_1):smb_hfi0_cpu0_lvc2_scl" )
			)
			( signal "SMB_HFI0_CPU0_LVC2_SDA"
				( objectStatus "@baseboard_fab2_lib.baseboard_fab2(sch_1):smb_hfi0_cpu0_lvc2_sda" )
			)
			( signal "SMB_HFI1_CPU0_LVC2_SCL"
				( objectStatus "@baseboard_fab2_lib.baseboard_fab2(sch_1):smb_hfi1_cpu0_lvc2_scl" )
			)
			( signal "SMB_HFI1_CPU0_LVC2_SDA"
				( objectStatus "@baseboard_fab2_lib.baseboard_fab2(sch_1):smb_hfi1_cpu0_lvc2_sda" )
			)
			( signal "TP_CPU0_RSVD_172"
				( objectStatus "@baseboard_fab2_lib.baseboard_fab2(sch_1):tp_cpu0_rsvd_172" )
			)
			( signal "TP_CPU0_RSVD_173"
				( objectStatus "@baseboard_fab2_lib.baseboard_fab2(sch_1):tp_cpu0_rsvd_173" )
			)
			( signal "TP_CPU0_RSVD_174"
				( objectStatus "@baseboard_fab2_lib.baseboard_fab2(sch_1):tp_cpu0_rsvd_174" )
			)
			( signal "TP_CPU0_RSVD_175"
				( objectStatus "@baseboard_fab2_lib.baseboard_fab2(sch_1):tp_cpu0_rsvd_175" )
			)
			( signal "TP_CPU0_RSVD_176"
				( objectStatus "@baseboard_fab2_lib.baseboard_fab2(sch_1):tp_cpu0_rsvd_176" )
			)
			( signal "TP_CPU0_RSVD_177"
				( objectStatus "@baseboard_fab2_lib.baseboard_fab2(sch_1):tp_cpu0_rsvd_177" )
			)
			( signal "TP_CPU0_RSVD_178"
				( objectStatus "@baseboard_fab2_lib.baseboard_fab2(sch_1):tp_cpu0_rsvd_178" )
			)
			( signal "TP_CPU0_RSVD_179"
				( objectStatus "@baseboard_fab2_lib.baseboard_fab2(sch_1):tp_cpu0_rsvd_179" )
			)
			( signal "TP_CPU0_RSVD_180"
				( objectStatus "@baseboard_fab2_lib.baseboard_fab2(sch_1):tp_cpu0_rsvd_180" )
			)
			( signal "TP_CPU0_RSVD_181"
				( objectStatus "@baseboard_fab2_lib.baseboard_fab2(sch_1):tp_cpu0_rsvd_181" )
			)
			( signal "TP_CPU0_RSVD_182"
				( objectStatus "@baseboard_fab2_lib.baseboard_fab2(sch_1):tp_cpu0_rsvd_182" )
			)
			( signal "TP_CPU0_RSVD_183"
				( objectStatus "@baseboard_fab2_lib.baseboard_fab2(sch_1):tp_cpu0_rsvd_183" )
			)
			( signal "TP_CPU0_RSVD_184"
				( objectStatus "@baseboard_fab2_lib.baseboard_fab2(sch_1):tp_cpu0_rsvd_184" )
			)
			( signal "TP_CPU0_RSVD_186"
				( objectStatus "@baseboard_fab2_lib.baseboard_fab2(sch_1):tp_cpu0_rsvd_186" )
			)
			( signal "TP_CPU0_RSVD_189"
				( objectStatus "@baseboard_fab2_lib.baseboard_fab2(sch_1):tp_cpu0_rsvd_189" )
			)
			( signal "TP_CPU0_RSVD_190"
				( objectStatus "@baseboard_fab2_lib.baseboard_fab2(sch_1):tp_cpu0_rsvd_190" )
			)
			( signal "P3E_CPU0_PE1_PCH_RXN<8>"
				( objectStatus "@baseboard_fab2_lib.baseboard_fab2(sch_1):p3e_cpu0_pe1_pch_rxn(8)" )
			)
			( signal "P3E_CPU0_PE1_PCH_RXN<9>"
				( objectStatus "@baseboard_fab2_lib.baseboard_fab2(sch_1):p3e_cpu0_pe1_pch_rxn(9)" )
			)
			( signal "P3E_CPU0_PE1_PCH_RXN<10>"
				( objectStatus "@baseboard_fab2_lib.baseboard_fab2(sch_1):p3e_cpu0_pe1_pch_rxn(10)" )
			)
			( signal "P3E_CPU0_PE1_PCH_RXN<11>"
				( objectStatus "@baseboard_fab2_lib.baseboard_fab2(sch_1):p3e_cpu0_pe1_pch_rxn(11)" )
			)
			( signal "P3E_CPU0_PE1_PCH_RXN<12>"
				( objectStatus "@baseboard_fab2_lib.baseboard_fab2(sch_1):p3e_cpu0_pe1_pch_rxn(12)" )
			)
			( signal "P3E_CPU0_PE1_PCH_RXN<13>"
				( objectStatus "@baseboard_fab2_lib.baseboard_fab2(sch_1):p3e_cpu0_pe1_pch_rxn(13)" )
			)
			( signal "P3E_CPU0_PE1_PCH_RXN<14>"
				( objectStatus "@baseboard_fab2_lib.baseboard_fab2(sch_1):p3e_cpu0_pe1_pch_rxn(14)" )
			)
			( signal "P3E_CPU0_PE1_PCH_RXN<15>"
				( objectStatus "@baseboard_fab2_lib.baseboard_fab2(sch_1):p3e_cpu0_pe1_pch_rxn(15)" )
			)
			( signal "P3E_CPU0_PE1_PCH_RXP<8>"
				( objectStatus "@baseboard_fab2_lib.baseboard_fab2(sch_1):p3e_cpu0_pe1_pch_rxp(8)" )
			)
			( signal "P3E_CPU0_PE1_PCH_RXP<9>"
				( objectStatus "@baseboard_fab2_lib.baseboard_fab2(sch_1):p3e_cpu0_pe1_pch_rxp(9)" )
			)
			( signal "P3E_CPU0_PE1_PCH_RXP<10>"
				( objectStatus "@baseboard_fab2_lib.baseboard_fab2(sch_1):p3e_cpu0_pe1_pch_rxp(10)" )
			)
			( signal "P3E_CPU0_PE1_PCH_RXP<11>"
				( objectStatus "@baseboard_fab2_lib.baseboard_fab2(sch_1):p3e_cpu0_pe1_pch_rxp(11)" )
			)
			( signal "P3E_CPU0_PE1_PCH_RXP<12>"
				( objectStatus "@baseboard_fab2_lib.baseboard_fab2(sch_1):p3e_cpu0_pe1_pch_rxp(12)" )
			)
			( signal "P3E_CPU0_PE1_PCH_RXP<13>"
				( objectStatus "@baseboard_fab2_lib.baseboard_fab2(sch_1):p3e_cpu0_pe1_pch_rxp(13)" )
			)
			( signal "P3E_CPU0_PE1_PCH_RXP<14>"
				( objectStatus "@baseboard_fab2_lib.baseboard_fab2(sch_1):p3e_cpu0_pe1_pch_rxp(14)" )
			)
			( signal "P3E_CPU0_PE1_PCH_RXP<15>"
				( objectStatus "@baseboard_fab2_lib.baseboard_fab2(sch_1):p3e_cpu0_pe1_pch_rxp(15)" )
			)
			( signal "P3E_CPU0_PE1_PCH_TXN<8>"
				( objectStatus "@baseboard_fab2_lib.baseboard_fab2(sch_1):p3e_cpu0_pe1_pch_txn(8)" )
			)
			( signal "P3E_CPU0_PE1_PCH_TXN<9>"
				( objectStatus "@baseboard_fab2_lib.baseboard_fab2(sch_1):p3e_cpu0_pe1_pch_txn(9)" )
			)
			( signal "P3E_CPU0_PE1_PCH_TXN<10>"
				( objectStatus "@baseboard_fab2_lib.baseboard_fab2(sch_1):p3e_cpu0_pe1_pch_txn(10)" )
			)
			( signal "P3E_CPU0_PE1_PCH_TXN<11>"
				( objectStatus "@baseboard_fab2_lib.baseboard_fab2(sch_1):p3e_cpu0_pe1_pch_txn(11)" )
			)
			( signal "P3E_CPU0_PE1_PCH_TXN<12>"
				( objectStatus "@baseboard_fab2_lib.baseboard_fab2(sch_1):p3e_cpu0_pe1_pch_txn(12)" )
			)
			( signal "P3E_CPU0_PE1_PCH_TXN<13>"
				( objectStatus "@baseboard_fab2_lib.baseboard_fab2(sch_1):p3e_cpu0_pe1_pch_txn(13)" )
			)
			( signal "P3E_CPU0_PE1_PCH_TXN<14>"
				( objectStatus "@baseboard_fab2_lib.baseboard_fab2(sch_1):p3e_cpu0_pe1_pch_txn(14)" )
			)
			( signal "P3E_CPU0_PE1_PCH_TXN<15>"
				( objectStatus "@baseboard_fab2_lib.baseboard_fab2(sch_1):p3e_cpu0_pe1_pch_txn(15)" )
			)
			( signal "P3E_CPU0_PE1_PCH_TXP<8>"
				( objectStatus "@baseboard_fab2_lib.baseboard_fab2(sch_1):p3e_cpu0_pe1_pch_txp(8)" )
			)
			( signal "P3E_CPU0_PE1_PCH_TXP<9>"
				( objectStatus "@baseboard_fab2_lib.baseboard_fab2(sch_1):p3e_cpu0_pe1_pch_txp(9)" )
			)
			( signal "P3E_CPU0_PE1_PCH_TXP<10>"
				( objectStatus "@baseboard_fab2_lib.baseboard_fab2(sch_1):p3e_cpu0_pe1_pch_txp(10)" )
			)
			( signal "P3E_CPU0_PE1_PCH_TXP<11>"
				( objectStatus "@baseboard_fab2_lib.baseboard_fab2(sch_1):p3e_cpu0_pe1_pch_txp(11)" )
			)
			( signal "P3E_CPU0_PE1_PCH_TXP<12>"
				( objectStatus "@baseboard_fab2_lib.baseboard_fab2(sch_1):p3e_cpu0_pe1_pch_txp(12)" )
			)
			( signal "P3E_CPU0_PE1_PCH_TXP<13>"
				( objectStatus "@baseboard_fab2_lib.baseboard_fab2(sch_1):p3e_cpu0_pe1_pch_txp(13)" )
			)
			( signal "P3E_CPU0_PE1_PCH_TXP<14>"
				( objectStatus "@baseboard_fab2_lib.baseboard_fab2(sch_1):p3e_cpu0_pe1_pch_txp(14)" )
			)
			( signal "P3E_CPU0_PE1_PCH_TXP<15>"
				( objectStatus "@baseboard_fab2_lib.baseboard_fab2(sch_1):p3e_cpu0_pe1_pch_txp(15)" )
			)
			( signal "P3E_CPU0_PE1_SS_RXN<0>"
				( objectStatus "@baseboard_fab2_lib.baseboard_fab2(sch_1):p3e_cpu0_pe1_ss_rxn(0)" )
			)
			( signal "P3E_CPU0_PE1_SS_RXN<1>"
				( objectStatus "@baseboard_fab2_lib.baseboard_fab2(sch_1):p3e_cpu0_pe1_ss_rxn(1)" )
			)
			( signal "P3E_CPU0_PE1_SS_RXN<2>"
				( objectStatus "@baseboard_fab2_lib.baseboard_fab2(sch_1):p3e_cpu0_pe1_ss_rxn(2)" )
			)
			( signal "P3E_CPU0_PE1_SS_RXN<3>"
				( objectStatus "@baseboard_fab2_lib.baseboard_fab2(sch_1):p3e_cpu0_pe1_ss_rxn(3)" )
			)
			( signal "P3E_CPU0_PE1_SS_RXN<4>"
				( objectStatus "@baseboard_fab2_lib.baseboard_fab2(sch_1):p3e_cpu0_pe1_ss_rxn(4)" )
			)
			( signal "P3E_CPU0_PE1_SS_RXN<5>"
				( objectStatus "@baseboard_fab2_lib.baseboard_fab2(sch_1):p3e_cpu0_pe1_ss_rxn(5)" )
			)
			( signal "P3E_CPU0_PE1_SS_RXN<6>"
				( objectStatus "@baseboard_fab2_lib.baseboard_fab2(sch_1):p3e_cpu0_pe1_ss_rxn(6)" )
			)
			( signal "P3E_CPU0_PE1_SS_RXN<7>"
				( objectStatus "@baseboard_fab2_lib.baseboard_fab2(sch_1):p3e_cpu0_pe1_ss_rxn(7)" )
			)
			( signal "P3E_CPU0_PE1_SS_RXP<0>"
				( objectStatus "@baseboard_fab2_lib.baseboard_fab2(sch_1):p3e_cpu0_pe1_ss_rxp(0)" )
			)
			( signal "P3E_CPU0_PE1_SS_RXP<1>"
				( objectStatus "@baseboard_fab2_lib.baseboard_fab2(sch_1):p3e_cpu0_pe1_ss_rxp(1)" )
			)
			( signal "P3E_CPU0_PE1_SS_RXP<2>"
				( objectStatus "@baseboard_fab2_lib.baseboard_fab2(sch_1):p3e_cpu0_pe1_ss_rxp(2)" )
			)
			( signal "P3E_CPU0_PE1_SS_RXP<3>"
				( objectStatus "@baseboard_fab2_lib.baseboard_fab2(sch_1):p3e_cpu0_pe1_ss_rxp(3)" )
			)
			( signal "P3E_CPU0_PE1_SS_RXP<4>"
				( objectStatus "@baseboard_fab2_lib.baseboard_fab2(sch_1):p3e_cpu0_pe1_ss_rxp(4)" )
			)
			( signal "P3E_CPU0_PE1_SS_RXP<5>"
				( objectStatus "@baseboard_fab2_lib.baseboard_fab2(sch_1):p3e_cpu0_pe1_ss_rxp(5)" )
			)
			( signal "P3E_CPU0_PE1_SS_RXP<6>"
				( objectStatus "@baseboard_fab2_lib.baseboard_fab2(sch_1):p3e_cpu0_pe1_ss_rxp(6)" )
			)
			( signal "P3E_CPU0_PE1_SS_RXP<7>"
				( objectStatus "@baseboard_fab2_lib.baseboard_fab2(sch_1):p3e_cpu0_pe1_ss_rxp(7)" )
			)
			( signal "P3E_CPU0_PE1_SS_TXN<0>"
				( objectStatus "@baseboard_fab2_lib.baseboard_fab2(sch_1):p3e_cpu0_pe1_ss_txn(0)" )
			)
			( signal "P3E_CPU0_PE1_SS_TXN<1>"
				( objectStatus "@baseboard_fab2_lib.baseboard_fab2(sch_1):p3e_cpu0_pe1_ss_txn(1)" )
			)
			( signal "P3E_CPU0_PE1_SS_TXN<2>"
				( objectStatus "@baseboard_fab2_lib.baseboard_fab2(sch_1):p3e_cpu0_pe1_ss_txn(2)" )
			)
			( signal "P3E_CPU0_PE1_SS_TXN<3>"
				( objectStatus "@baseboard_fab2_lib.baseboard_fab2(sch_1):p3e_cpu0_pe1_ss_txn(3)" )
			)
			( signal "P3E_CPU0_PE1_SS_TXN<4>"
				( objectStatus "@baseboard_fab2_lib.baseboard_fab2(sch_1):p3e_cpu0_pe1_ss_txn(4)" )
			)
			( signal "P3E_CPU0_PE1_SS_TXN<5>"
				( objectStatus "@baseboard_fab2_lib.baseboard_fab2(sch_1):p3e_cpu0_pe1_ss_txn(5)" )
			)
			( signal "P3E_CPU0_PE1_SS_TXN<6>"
				( objectStatus "@baseboard_fab2_lib.baseboard_fab2(sch_1):p3e_cpu0_pe1_ss_txn(6)" )
			)
			( signal "P3E_CPU0_PE1_SS_TXN<7>"
				( objectStatus "@baseboard_fab2_lib.baseboard_fab2(sch_1):p3e_cpu0_pe1_ss_txn(7)" )
			)
			( signal "P3E_CPU0_PE1_SS_TXP<0>"
				( objectStatus "@baseboard_fab2_lib.baseboard_fab2(sch_1):p3e_cpu0_pe1_ss_txp(0)" )
			)
			( signal "P3E_CPU0_PE1_SS_TXP<1>"
				( objectStatus "@baseboard_fab2_lib.baseboard_fab2(sch_1):p3e_cpu0_pe1_ss_txp(1)" )
			)
			( signal "P3E_CPU0_PE1_SS_TXP<2>"
				( objectStatus "@baseboard_fab2_lib.baseboard_fab2(sch_1):p3e_cpu0_pe1_ss_txp(2)" )
			)
			( signal "P3E_CPU0_PE1_SS_TXP<3>"
				( objectStatus "@baseboard_fab2_lib.baseboard_fab2(sch_1):p3e_cpu0_pe1_ss_txp(3)" )
			)
			( signal "P3E_CPU0_PE1_SS_TXP<4>"
				( objectStatus "@baseboard_fab2_lib.baseboard_fab2(sch_1):p3e_cpu0_pe1_ss_txp(4)" )
			)
			( signal "P3E_CPU0_PE1_SS_TXP<5>"
				( objectStatus "@baseboard_fab2_lib.baseboard_fab2(sch_1):p3e_cpu0_pe1_ss_txp(5)" )
			)
			( signal "P3E_CPU0_PE1_SS_TXP<6>"
				( objectStatus "@baseboard_fab2_lib.baseboard_fab2(sch_1):p3e_cpu0_pe1_ss_txp(6)" )
			)
			( signal "P3E_CPU0_PE1_SS_TXP<7>"
				( objectStatus "@baseboard_fab2_lib.baseboard_fab2(sch_1):p3e_cpu0_pe1_ss_txp(7)" )
			)
			( signal "P3E_CPU0_PE2_SS_RXN<0>"
				( objectStatus "@baseboard_fab2_lib.baseboard_fab2(sch_1):p3e_cpu0_pe2_ss_rxn(0)" )
			)
			( signal "P3E_CPU0_PE2_SS_RXN<1>"
				( objectStatus "@baseboard_fab2_lib.baseboard_fab2(sch_1):p3e_cpu0_pe2_ss_rxn(1)" )
			)
			( signal "P3E_CPU0_PE2_SS_RXN<2>"
				( objectStatus "@baseboard_fab2_lib.baseboard_fab2(sch_1):p3e_cpu0_pe2_ss_rxn(2)" )
			)
			( signal "P3E_CPU0_PE2_SS_RXN<3>"
				( objectStatus "@baseboard_fab2_lib.baseboard_fab2(sch_1):p3e_cpu0_pe2_ss_rxn(3)" )
			)
			( signal "P3E_CPU0_PE2_SS_RXN<4>"
				( objectStatus "@baseboard_fab2_lib.baseboard_fab2(sch_1):p3e_cpu0_pe2_ss_rxn(4)" )
			)
			( signal "P3E_CPU0_PE2_SS_RXN<5>"
				( objectStatus "@baseboard_fab2_lib.baseboard_fab2(sch_1):p3e_cpu0_pe2_ss_rxn(5)" )
			)
			( signal "P3E_CPU0_PE2_SS_RXN<6>"
				( objectStatus "@baseboard_fab2_lib.baseboard_fab2(sch_1):p3e_cpu0_pe2_ss_rxn(6)" )
			)
			( signal "P3E_CPU0_PE2_SS_RXN<7>"
				( objectStatus "@baseboard_fab2_lib.baseboard_fab2(sch_1):p3e_cpu0_pe2_ss_rxn(7)" )
			)
			( signal "P3E_CPU0_PE2_SS_RXN<8>"
				( objectStatus "@baseboard_fab2_lib.baseboard_fab2(sch_1):p3e_cpu0_pe2_ss_rxn(8)" )
			)
			( signal "P3E_CPU0_PE2_SS_RXN<9>"
				( objectStatus "@baseboard_fab2_lib.baseboard_fab2(sch_1):p3e_cpu0_pe2_ss_rxn(9)" )
			)
			( signal "P3E_CPU0_PE2_SS_RXN<10>"
				( objectStatus "@baseboard_fab2_lib.baseboard_fab2(sch_1):p3e_cpu0_pe2_ss_rxn(10)" )
			)
			( signal "P3E_CPU0_PE2_SS_RXN<11>"
				( objectStatus "@baseboard_fab2_lib.baseboard_fab2(sch_1):p3e_cpu0_pe2_ss_rxn(11)" )
			)
			( signal "P3E_CPU0_PE2_SS_RXN<12>"
				( objectStatus "@baseboard_fab2_lib.baseboard_fab2(sch_1):p3e_cpu0_pe2_ss_rxn(12)" )
			)
			( signal "P3E_CPU0_PE2_SS_RXN<13>"
				( objectStatus "@baseboard_fab2_lib.baseboard_fab2(sch_1):p3e_cpu0_pe2_ss_rxn(13)" )
			)
			( signal "P3E_CPU0_PE2_SS_RXN<14>"
				( objectStatus "@baseboard_fab2_lib.baseboard_fab2(sch_1):p3e_cpu0_pe2_ss_rxn(14)" )
			)
			( signal "P3E_CPU0_PE2_SS_RXN<15>"
				( objectStatus "@baseboard_fab2_lib.baseboard_fab2(sch_1):p3e_cpu0_pe2_ss_rxn(15)" )
			)
			( signal "P3E_CPU0_PE2_SS_RXP<0>"
				( objectStatus "@baseboard_fab2_lib.baseboard_fab2(sch_1):p3e_cpu0_pe2_ss_rxp(0)" )
			)
			( signal "P3E_CPU0_PE2_SS_RXP<1>"
				( objectStatus "@baseboard_fab2_lib.baseboard_fab2(sch_1):p3e_cpu0_pe2_ss_rxp(1)" )
			)
			( signal "P3E_CPU0_PE2_SS_RXP<2>"
				( objectStatus "@baseboard_fab2_lib.baseboard_fab2(sch_1):p3e_cpu0_pe2_ss_rxp(2)" )
			)
			( signal "P3E_CPU0_PE2_SS_RXP<3>"
				( objectStatus "@baseboard_fab2_lib.baseboard_fab2(sch_1):p3e_cpu0_pe2_ss_rxp(3)" )
			)
			( signal "P3E_CPU0_PE2_SS_RXP<4>"
				( objectStatus "@baseboard_fab2_lib.baseboard_fab2(sch_1):p3e_cpu0_pe2_ss_rxp(4)" )
			)
			( signal "P3E_CPU0_PE2_SS_RXP<5>"
				( objectStatus "@baseboard_fab2_lib.baseboard_fab2(sch_1):p3e_cpu0_pe2_ss_rxp(5)" )
			)
			( signal "P3E_CPU0_PE2_SS_RXP<6>"
				( objectStatus "@baseboard_fab2_lib.baseboard_fab2(sch_1):p3e_cpu0_pe2_ss_rxp(6)" )
			)
			( signal "P3E_CPU0_PE2_SS_RXP<7>"
				( objectStatus "@baseboard_fab2_lib.baseboard_fab2(sch_1):p3e_cpu0_pe2_ss_rxp(7)" )
			)
			( signal "P3E_CPU0_PE2_SS_RXP<8>"
				( objectStatus "@baseboard_fab2_lib.baseboard_fab2(sch_1):p3e_cpu0_pe2_ss_rxp(8)" )
			)
			( signal "P3E_CPU0_PE2_SS_RXP<9>"
				( objectStatus "@baseboard_fab2_lib.baseboard_fab2(sch_1):p3e_cpu0_pe2_ss_rxp(9)" )
			)
			( signal "P3E_CPU0_PE2_SS_RXP<10>"
				( objectStatus "@baseboard_fab2_lib.baseboard_fab2(sch_1):p3e_cpu0_pe2_ss_rxp(10)" )
			)
			( signal "P3E_CPU0_PE2_SS_RXP<11>"
				( objectStatus "@baseboard_fab2_lib.baseboard_fab2(sch_1):p3e_cpu0_pe2_ss_rxp(11)" )
			)
			( signal "P3E_CPU0_PE2_SS_RXP<12>"
				( objectStatus "@baseboard_fab2_lib.baseboard_fab2(sch_1):p3e_cpu0_pe2_ss_rxp(12)" )
			)
			( signal "P3E_CPU0_PE2_SS_RXP<13>"
				( objectStatus "@baseboard_fab2_lib.baseboard_fab2(sch_1):p3e_cpu0_pe2_ss_rxp(13)" )
			)
			( signal "P3E_CPU0_PE2_SS_RXP<14>"
				( objectStatus "@baseboard_fab2_lib.baseboard_fab2(sch_1):p3e_cpu0_pe2_ss_rxp(14)" )
			)
			( signal "P3E_CPU0_PE2_SS_RXP<15>"
				( objectStatus "@baseboard_fab2_lib.baseboard_fab2(sch_1):p3e_cpu0_pe2_ss_rxp(15)" )
			)
			( signal "P3E_CPU0_PE2_SS_TXN<0>"
				( objectStatus "@baseboard_fab2_lib.baseboard_fab2(sch_1):p3e_cpu0_pe2_ss_txn(0)" )
			)
			( signal "P3E_CPU0_PE2_SS_TXN<1>"
				( objectStatus "@baseboard_fab2_lib.baseboard_fab2(sch_1):p3e_cpu0_pe2_ss_txn(1)" )
			)
			( signal "P3E_CPU0_PE2_SS_TXN<2>"
				( objectStatus "@baseboard_fab2_lib.baseboard_fab2(sch_1):p3e_cpu0_pe2_ss_txn(2)" )
			)
			( signal "P3E_CPU0_PE2_SS_TXN<3>"
				( objectStatus "@baseboard_fab2_lib.baseboard_fab2(sch_1):p3e_cpu0_pe2_ss_txn(3)" )
			)
			( signal "P3E_CPU0_PE2_SS_TXN<4>"
				( objectStatus "@baseboard_fab2_lib.baseboard_fab2(sch_1):p3e_cpu0_pe2_ss_txn(4)" )
			)
			( signal "P3E_CPU0_PE2_SS_TXN<5>"
				( objectStatus "@baseboard_fab2_lib.baseboard_fab2(sch_1):p3e_cpu0_pe2_ss_txn(5)" )
			)
			( signal "P3E_CPU0_PE2_SS_TXN<6>"
				( objectStatus "@baseboard_fab2_lib.baseboard_fab2(sch_1):p3e_cpu0_pe2_ss_txn(6)" )
			)
			( signal "P3E_CPU0_PE2_SS_TXN<7>"
				( objectStatus "@baseboard_fab2_lib.baseboard_fab2(sch_1):p3e_cpu0_pe2_ss_txn(7)" )
			)
			( signal "P3E_CPU0_PE2_SS_TXN<8>"
				( objectStatus "@baseboard_fab2_lib.baseboard_fab2(sch_1):p3e_cpu0_pe2_ss_txn(8)" )
			)
			( signal "P3E_CPU0_PE2_SS_TXN<9>"
				( objectStatus "@baseboard_fab2_lib.baseboard_fab2(sch_1):p3e_cpu0_pe2_ss_txn(9)" )
			)
			( signal "P3E_CPU0_PE2_SS_TXN<10>"
				( objectStatus "@baseboard_fab2_lib.baseboard_fab2(sch_1):p3e_cpu0_pe2_ss_txn(10)" )
			)
			( signal "P3E_CPU0_PE2_SS_TXN<11>"
				( objectStatus "@baseboard_fab2_lib.baseboard_fab2(sch_1):p3e_cpu0_pe2_ss_txn(11)" )
			)
			( signal "P3E_CPU0_PE2_SS_TXN<12>"
				( objectStatus "@baseboard_fab2_lib.baseboard_fab2(sch_1):p3e_cpu0_pe2_ss_txn(12)" )
			)
			( signal "P3E_CPU0_PE2_SS_TXN<13>"
				( objectStatus "@baseboard_fab2_lib.baseboard_fab2(sch_1):p3e_cpu0_pe2_ss_txn(13)" )
			)
			( signal "P3E_CPU0_PE2_SS_TXN<14>"
				( objectStatus "@baseboard_fab2_lib.baseboard_fab2(sch_1):p3e_cpu0_pe2_ss_txn(14)" )
			)
			( signal "P3E_CPU0_PE2_SS_TXN<15>"
				( objectStatus "@baseboard_fab2_lib.baseboard_fab2(sch_1):p3e_cpu0_pe2_ss_txn(15)" )
			)
			( signal "P3E_CPU0_PE2_SS_TXP<0>"
				( objectStatus "@baseboard_fab2_lib.baseboard_fab2(sch_1):p3e_cpu0_pe2_ss_txp(0)" )
			)
			( signal "P3E_CPU0_PE2_SS_TXP<1>"
				( objectStatus "@baseboard_fab2_lib.baseboard_fab2(sch_1):p3e_cpu0_pe2_ss_txp(1)" )
			)
			( signal "P3E_CPU0_PE2_SS_TXP<2>"
				( objectStatus "@baseboard_fab2_lib.baseboard_fab2(sch_1):p3e_cpu0_pe2_ss_txp(2)" )
			)
			( signal "P3E_CPU0_PE2_SS_TXP<3>"
				( objectStatus "@baseboard_fab2_lib.baseboard_fab2(sch_1):p3e_cpu0_pe2_ss_txp(3)" )
			)
			( signal "P3E_CPU0_PE2_SS_TXP<4>"
				( objectStatus "@baseboard_fab2_lib.baseboard_fab2(sch_1):p3e_cpu0_pe2_ss_txp(4)" )
			)
			( signal "P3E_CPU0_PE2_SS_TXP<5>"
				( objectStatus "@baseboard_fab2_lib.baseboard_fab2(sch_1):p3e_cpu0_pe2_ss_txp(5)" )
			)
			( signal "P3E_CPU0_PE2_SS_TXP<6>"
				( objectStatus "@baseboard_fab2_lib.baseboard_fab2(sch_1):p3e_cpu0_pe2_ss_txp(6)" )
			)
			( signal "P3E_CPU0_PE2_SS_TXP<7>"
				( objectStatus "@baseboard_fab2_lib.baseboard_fab2(sch_1):p3e_cpu0_pe2_ss_txp(7)" )
			)
			( signal "P3E_CPU0_PE2_SS_TXP<8>"
				( objectStatus "@baseboard_fab2_lib.baseboard_fab2(sch_1):p3e_cpu0_pe2_ss_txp(8)" )
			)
			( signal "P3E_CPU0_PE2_SS_TXP<9>"
				( objectStatus "@baseboard_fab2_lib.baseboard_fab2(sch_1):p3e_cpu0_pe2_ss_txp(9)" )
			)
			( signal "P3E_CPU0_PE2_SS_TXP<10>"
				( objectStatus "@baseboard_fab2_lib.baseboard_fab2(sch_1):p3e_cpu0_pe2_ss_txp(10)" )
			)
			( signal "P3E_CPU0_PE2_SS_TXP<11>"
				( objectStatus "@baseboard_fab2_lib.baseboard_fab2(sch_1):p3e_cpu0_pe2_ss_txp(11)" )
			)
			( signal "P3E_CPU0_PE2_SS_TXP<12>"
				( objectStatus "@baseboard_fab2_lib.baseboard_fab2(sch_1):p3e_cpu0_pe2_ss_txp(12)" )
			)
			( signal "P3E_CPU0_PE2_SS_TXP<13>"
				( objectStatus "@baseboard_fab2_lib.baseboard_fab2(sch_1):p3e_cpu0_pe2_ss_txp(13)" )
			)
			( signal "P3E_CPU0_PE2_SS_TXP<14>"
				( objectStatus "@baseboard_fab2_lib.baseboard_fab2(sch_1):p3e_cpu0_pe2_ss_txp(14)" )
			)
			( signal "P3E_CPU0_PE2_SS_TXP<15>"
				( objectStatus "@baseboard_fab2_lib.baseboard_fab2(sch_1):p3e_cpu0_pe2_ss_txp(15)" )
			)
			( signal "P3E_CPU0_PE3_OCP_RXN<0>"
				( objectStatus "@baseboard_fab2_lib.baseboard_fab2(sch_1):p3e_cpu0_pe3_ocp_rxn(0)" )
			)
			( signal "P3E_CPU0_PE3_OCP_RXN<1>"
				( objectStatus "@baseboard_fab2_lib.baseboard_fab2(sch_1):p3e_cpu0_pe3_ocp_rxn(1)" )
			)
			( signal "P3E_CPU0_PE3_OCP_RXN<2>"
				( objectStatus "@baseboard_fab2_lib.baseboard_fab2(sch_1):p3e_cpu0_pe3_ocp_rxn(2)" )
			)
			( signal "P3E_CPU0_PE3_OCP_RXN<3>"
				( objectStatus "@baseboard_fab2_lib.baseboard_fab2(sch_1):p3e_cpu0_pe3_ocp_rxn(3)" )
			)
			( signal "P3E_CPU0_PE3_OCP_RXN<4>"
				( objectStatus "@baseboard_fab2_lib.baseboard_fab2(sch_1):p3e_cpu0_pe3_ocp_rxn(4)" )
			)
			( signal "P3E_CPU0_PE3_OCP_RXN<5>"
				( objectStatus "@baseboard_fab2_lib.baseboard_fab2(sch_1):p3e_cpu0_pe3_ocp_rxn(5)" )
			)
			( signal "P3E_CPU0_PE3_OCP_RXN<6>"
				( objectStatus "@baseboard_fab2_lib.baseboard_fab2(sch_1):p3e_cpu0_pe3_ocp_rxn(6)" )
			)
			( signal "P3E_CPU0_PE3_OCP_RXN<7>"
				( objectStatus "@baseboard_fab2_lib.baseboard_fab2(sch_1):p3e_cpu0_pe3_ocp_rxn(7)" )
			)
			( signal "P3E_CPU0_PE3_OCP_RXN<8>"
				( objectStatus "@baseboard_fab2_lib.baseboard_fab2(sch_1):p3e_cpu0_pe3_ocp_rxn(8)" )
			)
			( signal "P3E_CPU0_PE3_OCP_RXN<9>"
				( objectStatus "@baseboard_fab2_lib.baseboard_fab2(sch_1):p3e_cpu0_pe3_ocp_rxn(9)" )
			)
			( signal "P3E_CPU0_PE3_OCP_RXN<10>"
				( objectStatus "@baseboard_fab2_lib.baseboard_fab2(sch_1):p3e_cpu0_pe3_ocp_rxn(10)" )
			)
			( signal "P3E_CPU0_PE3_OCP_RXN<11>"
				( objectStatus "@baseboard_fab2_lib.baseboard_fab2(sch_1):p3e_cpu0_pe3_ocp_rxn(11)" )
			)
			( signal "P3E_CPU0_PE3_OCP_RXN<12>"
				( objectStatus "@baseboard_fab2_lib.baseboard_fab2(sch_1):p3e_cpu0_pe3_ocp_rxn(12)" )
			)
			( signal "P3E_CPU0_PE3_OCP_RXN<13>"
				( objectStatus "@baseboard_fab2_lib.baseboard_fab2(sch_1):p3e_cpu0_pe3_ocp_rxn(13)" )
			)
			( signal "P3E_CPU0_PE3_OCP_RXN<14>"
				( objectStatus "@baseboard_fab2_lib.baseboard_fab2(sch_1):p3e_cpu0_pe3_ocp_rxn(14)" )
			)
			( signal "P3E_CPU0_PE3_OCP_RXN<15>"
				( objectStatus "@baseboard_fab2_lib.baseboard_fab2(sch_1):p3e_cpu0_pe3_ocp_rxn(15)" )
			)
			( signal "P3E_CPU0_PE3_OCP_RXP<0>"
				( objectStatus "@baseboard_fab2_lib.baseboard_fab2(sch_1):p3e_cpu0_pe3_ocp_rxp(0)" )
			)
			( signal "P3E_CPU0_PE3_OCP_RXP<1>"
				( objectStatus "@baseboard_fab2_lib.baseboard_fab2(sch_1):p3e_cpu0_pe3_ocp_rxp(1)" )
			)
			( signal "P3E_CPU0_PE3_OCP_RXP<2>"
				( objectStatus "@baseboard_fab2_lib.baseboard_fab2(sch_1):p3e_cpu0_pe3_ocp_rxp(2)" )
			)
			( signal "P3E_CPU0_PE3_OCP_RXP<3>"
				( objectStatus "@baseboard_fab2_lib.baseboard_fab2(sch_1):p3e_cpu0_pe3_ocp_rxp(3)" )
			)
			( signal "P3E_CPU0_PE3_OCP_RXP<4>"
				( objectStatus "@baseboard_fab2_lib.baseboard_fab2(sch_1):p3e_cpu0_pe3_ocp_rxp(4)" )
			)
			( signal "P3E_CPU0_PE3_OCP_RXP<5>"
				( objectStatus "@baseboard_fab2_lib.baseboard_fab2(sch_1):p3e_cpu0_pe3_ocp_rxp(5)" )
			)
			( signal "P3E_CPU0_PE3_OCP_RXP<6>"
				( objectStatus "@baseboard_fab2_lib.baseboard_fab2(sch_1):p3e_cpu0_pe3_ocp_rxp(6)" )
			)
			( signal "P3E_CPU0_PE3_OCP_RXP<7>"
				( objectStatus "@baseboard_fab2_lib.baseboard_fab2(sch_1):p3e_cpu0_pe3_ocp_rxp(7)" )
			)
			( signal "P3E_CPU0_PE3_OCP_RXP<8>"
				( objectStatus "@baseboard_fab2_lib.baseboard_fab2(sch_1):p3e_cpu0_pe3_ocp_rxp(8)" )
			)
			( signal "P3E_CPU0_PE3_OCP_RXP<9>"
				( objectStatus "@baseboard_fab2_lib.baseboard_fab2(sch_1):p3e_cpu0_pe3_ocp_rxp(9)" )
			)
			( signal "P3E_CPU0_PE3_OCP_RXP<10>"
				( objectStatus "@baseboard_fab2_lib.baseboard_fab2(sch_1):p3e_cpu0_pe3_ocp_rxp(10)" )
			)
			( signal "P3E_CPU0_PE3_OCP_RXP<11>"
				( objectStatus "@baseboard_fab2_lib.baseboard_fab2(sch_1):p3e_cpu0_pe3_ocp_rxp(11)" )
			)
			( signal "P3E_CPU0_PE3_OCP_RXP<12>"
				( objectStatus "@baseboard_fab2_lib.baseboard_fab2(sch_1):p3e_cpu0_pe3_ocp_rxp(12)" )
			)
			( signal "P3E_CPU0_PE3_OCP_RXP<13>"
				( objectStatus "@baseboard_fab2_lib.baseboard_fab2(sch_1):p3e_cpu0_pe3_ocp_rxp(13)" )
			)
			( signal "P3E_CPU0_PE3_OCP_RXP<14>"
				( objectStatus "@baseboard_fab2_lib.baseboard_fab2(sch_1):p3e_cpu0_pe3_ocp_rxp(14)" )
			)
			( signal "P3E_CPU0_PE3_OCP_RXP<15>"
				( objectStatus "@baseboard_fab2_lib.baseboard_fab2(sch_1):p3e_cpu0_pe3_ocp_rxp(15)" )
			)
			( signal "P3E_CPU0_PE3_OCP_TXN<0>"
				( objectStatus "@baseboard_fab2_lib.baseboard_fab2(sch_1):p3e_cpu0_pe3_ocp_txn(0)" )
			)
			( signal "P3E_CPU0_PE3_OCP_TXN<1>"
				( objectStatus "@baseboard_fab2_lib.baseboard_fab2(sch_1):p3e_cpu0_pe3_ocp_txn(1)" )
			)
			( signal "P3E_CPU0_PE3_OCP_TXN<2>"
				( objectStatus "@baseboard_fab2_lib.baseboard_fab2(sch_1):p3e_cpu0_pe3_ocp_txn(2)" )
			)
			( signal "P3E_CPU0_PE3_OCP_TXN<3>"
				( objectStatus "@baseboard_fab2_lib.baseboard_fab2(sch_1):p3e_cpu0_pe3_ocp_txn(3)" )
			)
			( signal "P3E_CPU0_PE3_OCP_TXN<4>"
				( objectStatus "@baseboard_fab2_lib.baseboard_fab2(sch_1):p3e_cpu0_pe3_ocp_txn(4)" )
			)
			( signal "P3E_CPU0_PE3_OCP_TXN<5>"
				( objectStatus "@baseboard_fab2_lib.baseboard_fab2(sch_1):p3e_cpu0_pe3_ocp_txn(5)" )
			)
			( signal "P3E_CPU0_PE3_OCP_TXN<6>"
				( objectStatus "@baseboard_fab2_lib.baseboard_fab2(sch_1):p3e_cpu0_pe3_ocp_txn(6)" )
			)
			( signal "P3E_CPU0_PE3_OCP_TXN<7>"
				( objectStatus "@baseboard_fab2_lib.baseboard_fab2(sch_1):p3e_cpu0_pe3_ocp_txn(7)" )
			)
			( signal "P3E_CPU0_PE3_OCP_TXN<8>"
				( objectStatus "@baseboard_fab2_lib.baseboard_fab2(sch_1):p3e_cpu0_pe3_ocp_txn(8)" )
			)
			( signal "P3E_CPU0_PE3_OCP_TXN<9>"
				( objectStatus "@baseboard_fab2_lib.baseboard_fab2(sch_1):p3e_cpu0_pe3_ocp_txn(9)" )
			)
			( signal "P3E_CPU0_PE3_OCP_TXN<10>"
				( objectStatus "@baseboard_fab2_lib.baseboard_fab2(sch_1):p3e_cpu0_pe3_ocp_txn(10)" )
			)
			( signal "P3E_CPU0_PE3_OCP_TXN<11>"
				( objectStatus "@baseboard_fab2_lib.baseboard_fab2(sch_1):p3e_cpu0_pe3_ocp_txn(11)" )
			)
			( signal "P3E_CPU0_PE3_OCP_TXN<12>"
				( objectStatus "@baseboard_fab2_lib.baseboard_fab2(sch_1):p3e_cpu0_pe3_ocp_txn(12)" )
			)
			( signal "P3E_CPU0_PE3_OCP_TXN<13>"
				( objectStatus "@baseboard_fab2_lib.baseboard_fab2(sch_1):p3e_cpu0_pe3_ocp_txn(13)" )
			)
			( signal "P3E_CPU0_PE3_OCP_TXN<14>"
				( objectStatus "@baseboard_fab2_lib.baseboard_fab2(sch_1):p3e_cpu0_pe3_ocp_txn(14)" )
			)
			( signal "P3E_CPU0_PE3_OCP_TXN<15>"
				( objectStatus "@baseboard_fab2_lib.baseboard_fab2(sch_1):p3e_cpu0_pe3_ocp_txn(15)" )
			)
			( signal "P3E_CPU0_PE3_OCP_TXP<0>"
				( objectStatus "@baseboard_fab2_lib.baseboard_fab2(sch_1):p3e_cpu0_pe3_ocp_txp(0)" )
			)
			( signal "P3E_CPU0_PE3_OCP_TXP<1>"
				( objectStatus "@baseboard_fab2_lib.baseboard_fab2(sch_1):p3e_cpu0_pe3_ocp_txp(1)" )
			)
			( signal "P3E_CPU0_PE3_OCP_TXP<2>"
				( objectStatus "@baseboard_fab2_lib.baseboard_fab2(sch_1):p3e_cpu0_pe3_ocp_txp(2)" )
			)
			( signal "P3E_CPU0_PE3_OCP_TXP<3>"
				( objectStatus "@baseboard_fab2_lib.baseboard_fab2(sch_1):p3e_cpu0_pe3_ocp_txp(3)" )
			)
			( signal "P3E_CPU0_PE3_OCP_TXP<4>"
				( objectStatus "@baseboard_fab2_lib.baseboard_fab2(sch_1):p3e_cpu0_pe3_ocp_txp(4)" )
			)
			( signal "P3E_CPU0_PE3_OCP_TXP<5>"
				( objectStatus "@baseboard_fab2_lib.baseboard_fab2(sch_1):p3e_cpu0_pe3_ocp_txp(5)" )
			)
			( signal "P3E_CPU0_PE3_OCP_TXP<6>"
				( objectStatus "@baseboard_fab2_lib.baseboard_fab2(sch_1):p3e_cpu0_pe3_ocp_txp(6)" )
			)
			( signal "P3E_CPU0_PE3_OCP_TXP<7>"
				( objectStatus "@baseboard_fab2_lib.baseboard_fab2(sch_1):p3e_cpu0_pe3_ocp_txp(7)" )
			)
			( signal "P3E_CPU0_PE3_OCP_TXP<8>"
				( objectStatus "@baseboard_fab2_lib.baseboard_fab2(sch_1):p3e_cpu0_pe3_ocp_txp(8)" )
			)
			( signal "P3E_CPU0_PE3_OCP_TXP<9>"
				( objectStatus "@baseboard_fab2_lib.baseboard_fab2(sch_1):p3e_cpu0_pe3_ocp_txp(9)" )
			)
			( signal "P3E_CPU0_PE3_OCP_TXP<10>"
				( objectStatus "@baseboard_fab2_lib.baseboard_fab2(sch_1):p3e_cpu0_pe3_ocp_txp(10)" )
			)
			( signal "P3E_CPU0_PE3_OCP_TXP<11>"
				( objectStatus "@baseboard_fab2_lib.baseboard_fab2(sch_1):p3e_cpu0_pe3_ocp_txp(11)" )
			)
			( signal "P3E_CPU0_PE3_OCP_TXP<12>"
				( objectStatus "@baseboard_fab2_lib.baseboard_fab2(sch_1):p3e_cpu0_pe3_ocp_txp(12)" )
			)
			( signal "P3E_CPU0_PE3_OCP_TXP<13>"
				( objectStatus "@baseboard_fab2_lib.baseboard_fab2(sch_1):p3e_cpu0_pe3_ocp_txp(13)" )
			)
			( signal "P3E_CPU0_PE3_OCP_TXP<14>"
				( objectStatus "@baseboard_fab2_lib.baseboard_fab2(sch_1):p3e_cpu0_pe3_ocp_txp(14)" )
			)
			( signal "P3E_CPU0_PE3_OCP_TXP<15>"
				( objectStatus "@baseboard_fab2_lib.baseboard_fab2(sch_1):p3e_cpu0_pe3_ocp_txp(15)" )
			)
			( signal "UPI_CPU0_CPU1_P0P0_DN<0>"
				( objectStatus "@baseboard_fab2_lib.baseboard_fab2(sch_1):upi_cpu0_cpu1_p0p0_dn(0)" )
			)
			( signal "UPI_CPU0_CPU1_P0P0_DN<1>"
				( objectStatus "@baseboard_fab2_lib.baseboard_fab2(sch_1):upi_cpu0_cpu1_p0p0_dn(1)" )
			)
			( signal "UPI_CPU0_CPU1_P0P0_DN<2>"
				( objectStatus "@baseboard_fab2_lib.baseboard_fab2(sch_1):upi_cpu0_cpu1_p0p0_dn(2)" )
			)
			( signal "UPI_CPU0_CPU1_P0P0_DN<3>"
				( objectStatus "@baseboard_fab2_lib.baseboard_fab2(sch_1):upi_cpu0_cpu1_p0p0_dn(3)" )
			)
			( signal "UPI_CPU0_CPU1_P0P0_DN<4>"
				( objectStatus "@baseboard_fab2_lib.baseboard_fab2(sch_1):upi_cpu0_cpu1_p0p0_dn(4)" )
			)
			( signal "UPI_CPU0_CPU1_P0P0_DN<5>"
				( objectStatus "@baseboard_fab2_lib.baseboard_fab2(sch_1):upi_cpu0_cpu1_p0p0_dn(5)" )
			)
			( signal "UPI_CPU0_CPU1_P0P0_DN<6>"
				( objectStatus "@baseboard_fab2_lib.baseboard_fab2(sch_1):upi_cpu0_cpu1_p0p0_dn(6)" )
			)
			( signal "UPI_CPU0_CPU1_P0P0_DN<7>"
				( objectStatus "@baseboard_fab2_lib.baseboard_fab2(sch_1):upi_cpu0_cpu1_p0p0_dn(7)" )
			)
			( signal "UPI_CPU0_CPU1_P0P0_DN<8>"
				( objectStatus "@baseboard_fab2_lib.baseboard_fab2(sch_1):upi_cpu0_cpu1_p0p0_dn(8)" )
			)
			( signal "UPI_CPU0_CPU1_P0P0_DN<9>"
				( objectStatus "@baseboard_fab2_lib.baseboard_fab2(sch_1):upi_cpu0_cpu1_p0p0_dn(9)" )
			)
			( signal "UPI_CPU0_CPU1_P0P0_DN<10>"
				( objectStatus "@baseboard_fab2_lib.baseboard_fab2(sch_1):upi_cpu0_cpu1_p0p0_dn(10)" )
			)
			( signal "UPI_CPU0_CPU1_P0P0_DN<11>"
				( objectStatus "@baseboard_fab2_lib.baseboard_fab2(sch_1):upi_cpu0_cpu1_p0p0_dn(11)" )
			)
			( signal "UPI_CPU0_CPU1_P0P0_DN<12>"
				( objectStatus "@baseboard_fab2_lib.baseboard_fab2(sch_1):upi_cpu0_cpu1_p0p0_dn(12)" )
			)
			( signal "UPI_CPU0_CPU1_P0P0_DN<13>"
				( objectStatus "@baseboard_fab2_lib.baseboard_fab2(sch_1):upi_cpu0_cpu1_p0p0_dn(13)" )
			)
			( signal "UPI_CPU0_CPU1_P0P0_DN<14>"
				( objectStatus "@baseboard_fab2_lib.baseboard_fab2(sch_1):upi_cpu0_cpu1_p0p0_dn(14)" )
			)
			( signal "UPI_CPU0_CPU1_P0P0_DN<15>"
				( objectStatus "@baseboard_fab2_lib.baseboard_fab2(sch_1):upi_cpu0_cpu1_p0p0_dn(15)" )
			)
			( signal "UPI_CPU0_CPU1_P0P0_DN<16>"
				( objectStatus "@baseboard_fab2_lib.baseboard_fab2(sch_1):upi_cpu0_cpu1_p0p0_dn(16)" )
			)
			( signal "UPI_CPU0_CPU1_P0P0_DN<17>"
				( objectStatus "@baseboard_fab2_lib.baseboard_fab2(sch_1):upi_cpu0_cpu1_p0p0_dn(17)" )
			)
			( signal "UPI_CPU0_CPU1_P0P0_DN<18>"
				( objectStatus "@baseboard_fab2_lib.baseboard_fab2(sch_1):upi_cpu0_cpu1_p0p0_dn(18)" )
			)
			( signal "UPI_CPU0_CPU1_P0P0_DN<19>"
				( objectStatus "@baseboard_fab2_lib.baseboard_fab2(sch_1):upi_cpu0_cpu1_p0p0_dn(19)" )
			)
			( signal "UPI_CPU0_CPU1_P0P0_DP<0>"
				( objectStatus "@baseboard_fab2_lib.baseboard_fab2(sch_1):upi_cpu0_cpu1_p0p0_dp(0)" )
			)
			( signal "UPI_CPU0_CPU1_P0P0_DP<1>"
				( objectStatus "@baseboard_fab2_lib.baseboard_fab2(sch_1):upi_cpu0_cpu1_p0p0_dp(1)" )
			)
			( signal "UPI_CPU0_CPU1_P0P0_DP<2>"
				( objectStatus "@baseboard_fab2_lib.baseboard_fab2(sch_1):upi_cpu0_cpu1_p0p0_dp(2)" )
			)
			( signal "UPI_CPU0_CPU1_P0P0_DP<3>"
				( objectStatus "@baseboard_fab2_lib.baseboard_fab2(sch_1):upi_cpu0_cpu1_p0p0_dp(3)" )
			)
			( signal "UPI_CPU0_CPU1_P0P0_DP<4>"
				( objectStatus "@baseboard_fab2_lib.baseboard_fab2(sch_1):upi_cpu0_cpu1_p0p0_dp(4)" )
			)
			( signal "UPI_CPU0_CPU1_P0P0_DP<5>"
				( objectStatus "@baseboard_fab2_lib.baseboard_fab2(sch_1):upi_cpu0_cpu1_p0p0_dp(5)" )
			)
			( signal "UPI_CPU0_CPU1_P0P0_DP<6>"
				( objectStatus "@baseboard_fab2_lib.baseboard_fab2(sch_1):upi_cpu0_cpu1_p0p0_dp(6)" )
			)
			( signal "UPI_CPU0_CPU1_P0P0_DP<7>"
				( objectStatus "@baseboard_fab2_lib.baseboard_fab2(sch_1):upi_cpu0_cpu1_p0p0_dp(7)" )
			)
			( signal "UPI_CPU0_CPU1_P0P0_DP<8>"
				( objectStatus "@baseboard_fab2_lib.baseboard_fab2(sch_1):upi_cpu0_cpu1_p0p0_dp(8)" )
			)
			( signal "UPI_CPU0_CPU1_P0P0_DP<9>"
				( objectStatus "@baseboard_fab2_lib.baseboard_fab2(sch_1):upi_cpu0_cpu1_p0p0_dp(9)" )
			)
			( signal "UPI_CPU0_CPU1_P0P0_DP<10>"
				( objectStatus "@baseboard_fab2_lib.baseboard_fab2(sch_1):upi_cpu0_cpu1_p0p0_dp(10)" )
			)
			( signal "UPI_CPU0_CPU1_P0P0_DP<11>"
				( objectStatus "@baseboard_fab2_lib.baseboard_fab2(sch_1):upi_cpu0_cpu1_p0p0_dp(11)" )
			)
			( signal "UPI_CPU0_CPU1_P0P0_DP<12>"
				( objectStatus "@baseboard_fab2_lib.baseboard_fab2(sch_1):upi_cpu0_cpu1_p0p0_dp(12)" )
			)
			( signal "UPI_CPU0_CPU1_P0P0_DP<13>"
				( objectStatus "@baseboard_fab2_lib.baseboard_fab2(sch_1):upi_cpu0_cpu1_p0p0_dp(13)" )
			)
			( signal "UPI_CPU0_CPU1_P0P0_DP<14>"
				( objectStatus "@baseboard_fab2_lib.baseboard_fab2(sch_1):upi_cpu0_cpu1_p0p0_dp(14)" )
			)
			( signal "UPI_CPU0_CPU1_P0P0_DP<15>"
				( objectStatus "@baseboard_fab2_lib.baseboard_fab2(sch_1):upi_cpu0_cpu1_p0p0_dp(15)" )
			)
			( signal "UPI_CPU0_CPU1_P0P0_DP<16>"
				( objectStatus "@baseboard_fab2_lib.baseboard_fab2(sch_1):upi_cpu0_cpu1_p0p0_dp(16)" )
			)
			( signal "UPI_CPU0_CPU1_P0P0_DP<17>"
				( objectStatus "@baseboard_fab2_lib.baseboard_fab2(sch_1):upi_cpu0_cpu1_p0p0_dp(17)" )
			)
			( signal "UPI_CPU0_CPU1_P0P0_DP<18>"
				( objectStatus "@baseboard_fab2_lib.baseboard_fab2(sch_1):upi_cpu0_cpu1_p0p0_dp(18)" )
			)
			( signal "UPI_CPU0_CPU1_P0P0_DP<19>"
				( objectStatus "@baseboard_fab2_lib.baseboard_fab2(sch_1):upi_cpu0_cpu1_p0p0_dp(19)" )
			)
			( signal "UPI_CPU1_CPU0_P0P0_DN<0>"
				( objectStatus "@baseboard_fab2_lib.baseboard_fab2(sch_1):upi_cpu1_cpu0_p0p0_dn(0)" )
			)
			( signal "UPI_CPU1_CPU0_P0P0_DN<1>"
				( objectStatus "@baseboard_fab2_lib.baseboard_fab2(sch_1):upi_cpu1_cpu0_p0p0_dn(1)" )
			)
			( signal "UPI_CPU1_CPU0_P0P0_DN<2>"
				( objectStatus "@baseboard_fab2_lib.baseboard_fab2(sch_1):upi_cpu1_cpu0_p0p0_dn(2)" )
			)
			( signal "UPI_CPU1_CPU0_P0P0_DN<3>"
				( objectStatus "@baseboard_fab2_lib.baseboard_fab2(sch_1):upi_cpu1_cpu0_p0p0_dn(3)" )
			)
			( signal "UPI_CPU1_CPU0_P0P0_DN<4>"
				( objectStatus "@baseboard_fab2_lib.baseboard_fab2(sch_1):upi_cpu1_cpu0_p0p0_dn(4)" )
			)
			( signal "UPI_CPU1_CPU0_P0P0_DN<5>"
				( objectStatus "@baseboard_fab2_lib.baseboard_fab2(sch_1):upi_cpu1_cpu0_p0p0_dn(5)" )
			)
			( signal "UPI_CPU1_CPU0_P0P0_DN<6>"
				( objectStatus "@baseboard_fab2_lib.baseboard_fab2(sch_1):upi_cpu1_cpu0_p0p0_dn(6)" )
			)
			( signal "UPI_CPU1_CPU0_P0P0_DN<7>"
				( objectStatus "@baseboard_fab2_lib.baseboard_fab2(sch_1):upi_cpu1_cpu0_p0p0_dn(7)" )
			)
			( signal "UPI_CPU1_CPU0_P0P0_DN<8>"
				( objectStatus "@baseboard_fab2_lib.baseboard_fab2(sch_1):upi_cpu1_cpu0_p0p0_dn(8)" )
			)
			( signal "UPI_CPU1_CPU0_P0P0_DN<9>"
				( objectStatus "@baseboard_fab2_lib.baseboard_fab2(sch_1):upi_cpu1_cpu0_p0p0_dn(9)" )
			)
			( signal "UPI_CPU1_CPU0_P0P0_DN<10>"
				( objectStatus "@baseboard_fab2_lib.baseboard_fab2(sch_1):upi_cpu1_cpu0_p0p0_dn(10)" )
			)
			( signal "UPI_CPU1_CPU0_P0P0_DN<11>"
				( objectStatus "@baseboard_fab2_lib.baseboard_fab2(sch_1):upi_cpu1_cpu0_p0p0_dn(11)" )
			)
			( signal "UPI_CPU1_CPU0_P0P0_DN<12>"
				( objectStatus "@baseboard_fab2_lib.baseboard_fab2(sch_1):upi_cpu1_cpu0_p0p0_dn(12)" )
			)
			( signal "UPI_CPU1_CPU0_P0P0_DN<13>"
				( objectStatus "@baseboard_fab2_lib.baseboard_fab2(sch_1):upi_cpu1_cpu0_p0p0_dn(13)" )
			)
			( signal "UPI_CPU1_CPU0_P0P0_DN<14>"
				( objectStatus "@baseboard_fab2_lib.baseboard_fab2(sch_1):upi_cpu1_cpu0_p0p0_dn(14)" )
			)
			( signal "UPI_CPU1_CPU0_P0P0_DN<15>"
				( objectStatus "@baseboard_fab2_lib.baseboard_fab2(sch_1):upi_cpu1_cpu0_p0p0_dn(15)" )
			)
			( signal "UPI_CPU1_CPU0_P0P0_DN<16>"
				( objectStatus "@baseboard_fab2_lib.baseboard_fab2(sch_1):upi_cpu1_cpu0_p0p0_dn(16)" )
			)
			( signal "UPI_CPU1_CPU0_P0P0_DN<17>"
				( objectStatus "@baseboard_fab2_lib.baseboard_fab2(sch_1):upi_cpu1_cpu0_p0p0_dn(17)" )
			)
			( signal "UPI_CPU1_CPU0_P0P0_DN<18>"
				( objectStatus "@baseboard_fab2_lib.baseboard_fab2(sch_1):upi_cpu1_cpu0_p0p0_dn(18)" )
			)
			( signal "UPI_CPU1_CPU0_P0P0_DN<19>"
				( objectStatus "@baseboard_fab2_lib.baseboard_fab2(sch_1):upi_cpu1_cpu0_p0p0_dn(19)" )
			)
			( signal "UPI_CPU1_CPU0_P0P0_DP<0>"
				( objectStatus "@baseboard_fab2_lib.baseboard_fab2(sch_1):upi_cpu1_cpu0_p0p0_dp(0)" )
			)
			( signal "UPI_CPU1_CPU0_P0P0_DP<1>"
				( objectStatus "@baseboard_fab2_lib.baseboard_fab2(sch_1):upi_cpu1_cpu0_p0p0_dp(1)" )
			)
			( signal "UPI_CPU1_CPU0_P0P0_DP<2>"
				( objectStatus "@baseboard_fab2_lib.baseboard_fab2(sch_1):upi_cpu1_cpu0_p0p0_dp(2)" )
			)
			( signal "UPI_CPU1_CPU0_P0P0_DP<3>"
				( objectStatus "@baseboard_fab2_lib.baseboard_fab2(sch_1):upi_cpu1_cpu0_p0p0_dp(3)" )
			)
			( signal "UPI_CPU1_CPU0_P0P0_DP<4>"
				( objectStatus "@baseboard_fab2_lib.baseboard_fab2(sch_1):upi_cpu1_cpu0_p0p0_dp(4)" )
			)
			( signal "UPI_CPU1_CPU0_P0P0_DP<5>"
				( objectStatus "@baseboard_fab2_lib.baseboard_fab2(sch_1):upi_cpu1_cpu0_p0p0_dp(5)" )
			)
			( signal "UPI_CPU1_CPU0_P0P0_DP<6>"
				( objectStatus "@baseboard_fab2_lib.baseboard_fab2(sch_1):upi_cpu1_cpu0_p0p0_dp(6)" )
			)
			( signal "UPI_CPU1_CPU0_P0P0_DP<7>"
				( objectStatus "@baseboard_fab2_lib.baseboard_fab2(sch_1):upi_cpu1_cpu0_p0p0_dp(7)" )
			)
			( signal "UPI_CPU1_CPU0_P0P0_DP<8>"
				( objectStatus "@baseboard_fab2_lib.baseboard_fab2(sch_1):upi_cpu1_cpu0_p0p0_dp(8)" )
			)
			( signal "UPI_CPU1_CPU0_P0P0_DP<9>"
				( objectStatus "@baseboard_fab2_lib.baseboard_fab2(sch_1):upi_cpu1_cpu0_p0p0_dp(9)" )
			)
			( signal "UPI_CPU1_CPU0_P0P0_DP<10>"
				( objectStatus "@baseboard_fab2_lib.baseboard_fab2(sch_1):upi_cpu1_cpu0_p0p0_dp(10)" )
			)
			( signal "UPI_CPU1_CPU0_P0P0_DP<11>"
				( objectStatus "@baseboard_fab2_lib.baseboard_fab2(sch_1):upi_cpu1_cpu0_p0p0_dp(11)" )
			)
			( signal "UPI_CPU1_CPU0_P0P0_DP<12>"
				( objectStatus "@baseboard_fab2_lib.baseboard_fab2(sch_1):upi_cpu1_cpu0_p0p0_dp(12)" )
			)
			( signal "UPI_CPU1_CPU0_P0P0_DP<13>"
				( objectStatus "@baseboard_fab2_lib.baseboard_fab2(sch_1):upi_cpu1_cpu0_p0p0_dp(13)" )
			)
			( signal "UPI_CPU1_CPU0_P0P0_DP<14>"
				( objectStatus "@baseboard_fab2_lib.baseboard_fab2(sch_1):upi_cpu1_cpu0_p0p0_dp(14)" )
			)
			( signal "UPI_CPU1_CPU0_P0P0_DP<15>"
				( objectStatus "@baseboard_fab2_lib.baseboard_fab2(sch_1):upi_cpu1_cpu0_p0p0_dp(15)" )
			)
			( signal "UPI_CPU1_CPU0_P0P0_DP<16>"
				( objectStatus "@baseboard_fab2_lib.baseboard_fab2(sch_1):upi_cpu1_cpu0_p0p0_dp(16)" )
			)
			( signal "UPI_CPU1_CPU0_P0P0_DP<17>"
				( objectStatus "@baseboard_fab2_lib.baseboard_fab2(sch_1):upi_cpu1_cpu0_p0p0_dp(17)" )
			)
			( signal "UPI_CPU1_CPU0_P0P0_DP<18>"
				( objectStatus "@baseboard_fab2_lib.baseboard_fab2(sch_1):upi_cpu1_cpu0_p0p0_dp(18)" )
			)
			( signal "UPI_CPU1_CPU0_P0P0_DP<19>"
				( objectStatus "@baseboard_fab2_lib.baseboard_fab2(sch_1):upi_cpu1_cpu0_p0p0_dp(19)" )
			)
			( signal "UPI_CPU0_CPU1_P1P1_DN<0>"
				( objectStatus "@baseboard_fab2_lib.baseboard_fab2(sch_1):upi_cpu0_cpu1_p1p1_dn(0)" )
			)
			( signal "UPI_CPU0_CPU1_P1P1_DN<1>"
				( objectStatus "@baseboard_fab2_lib.baseboard_fab2(sch_1):upi_cpu0_cpu1_p1p1_dn(1)" )
			)
			( signal "UPI_CPU0_CPU1_P1P1_DN<2>"
				( objectStatus "@baseboard_fab2_lib.baseboard_fab2(sch_1):upi_cpu0_cpu1_p1p1_dn(2)" )
			)
			( signal "UPI_CPU0_CPU1_P1P1_DN<3>"
				( objectStatus "@baseboard_fab2_lib.baseboard_fab2(sch_1):upi_cpu0_cpu1_p1p1_dn(3)" )
			)
			( signal "UPI_CPU0_CPU1_P1P1_DN<4>"
				( objectStatus "@baseboard_fab2_lib.baseboard_fab2(sch_1):upi_cpu0_cpu1_p1p1_dn(4)" )
			)
			( signal "UPI_CPU0_CPU1_P1P1_DN<5>"
				( objectStatus "@baseboard_fab2_lib.baseboard_fab2(sch_1):upi_cpu0_cpu1_p1p1_dn(5)" )
			)
			( signal "UPI_CPU0_CPU1_P1P1_DN<6>"
				( objectStatus "@baseboard_fab2_lib.baseboard_fab2(sch_1):upi_cpu0_cpu1_p1p1_dn(6)" )
			)
			( signal "UPI_CPU0_CPU1_P1P1_DN<7>"
				( objectStatus "@baseboard_fab2_lib.baseboard_fab2(sch_1):upi_cpu0_cpu1_p1p1_dn(7)" )
			)
			( signal "UPI_CPU0_CPU1_P1P1_DN<8>"
				( objectStatus "@baseboard_fab2_lib.baseboard_fab2(sch_1):upi_cpu0_cpu1_p1p1_dn(8)" )
			)
			( signal "UPI_CPU0_CPU1_P1P1_DN<9>"
				( objectStatus "@baseboard_fab2_lib.baseboard_fab2(sch_1):upi_cpu0_cpu1_p1p1_dn(9)" )
			)
			( signal "UPI_CPU0_CPU1_P1P1_DN<10>"
				( objectStatus "@baseboard_fab2_lib.baseboard_fab2(sch_1):upi_cpu0_cpu1_p1p1_dn(10)" )
			)
			( signal "UPI_CPU0_CPU1_P1P1_DN<11>"
				( objectStatus "@baseboard_fab2_lib.baseboard_fab2(sch_1):upi_cpu0_cpu1_p1p1_dn(11)" )
			)
			( signal "UPI_CPU0_CPU1_P1P1_DN<12>"
				( objectStatus "@baseboard_fab2_lib.baseboard_fab2(sch_1):upi_cpu0_cpu1_p1p1_dn(12)" )
			)
			( signal "UPI_CPU0_CPU1_P1P1_DN<13>"
				( objectStatus "@baseboard_fab2_lib.baseboard_fab2(sch_1):upi_cpu0_cpu1_p1p1_dn(13)" )
			)
			( signal "UPI_CPU0_CPU1_P1P1_DN<14>"
				( objectStatus "@baseboard_fab2_lib.baseboard_fab2(sch_1):upi_cpu0_cpu1_p1p1_dn(14)" )
			)
			( signal "UPI_CPU0_CPU1_P1P1_DN<15>"
				( objectStatus "@baseboard_fab2_lib.baseboard_fab2(sch_1):upi_cpu0_cpu1_p1p1_dn(15)" )
			)
			( signal "UPI_CPU0_CPU1_P1P1_DN<16>"
				( objectStatus "@baseboard_fab2_lib.baseboard_fab2(sch_1):upi_cpu0_cpu1_p1p1_dn(16)" )
			)
			( signal "UPI_CPU0_CPU1_P1P1_DN<17>"
				( objectStatus "@baseboard_fab2_lib.baseboard_fab2(sch_1):upi_cpu0_cpu1_p1p1_dn(17)" )
			)
			( signal "UPI_CPU0_CPU1_P1P1_DN<18>"
				( objectStatus "@baseboard_fab2_lib.baseboard_fab2(sch_1):upi_cpu0_cpu1_p1p1_dn(18)" )
			)
			( signal "UPI_CPU0_CPU1_P1P1_DN<19>"
				( objectStatus "@baseboard_fab2_lib.baseboard_fab2(sch_1):upi_cpu0_cpu1_p1p1_dn(19)" )
			)
			( signal "UPI_CPU0_CPU1_P1P1_DP<0>"
				( objectStatus "@baseboard_fab2_lib.baseboard_fab2(sch_1):upi_cpu0_cpu1_p1p1_dp(0)" )
			)
			( signal "UPI_CPU0_CPU1_P1P1_DP<1>"
				( objectStatus "@baseboard_fab2_lib.baseboard_fab2(sch_1):upi_cpu0_cpu1_p1p1_dp(1)" )
			)
			( signal "UPI_CPU0_CPU1_P1P1_DP<2>"
				( objectStatus "@baseboard_fab2_lib.baseboard_fab2(sch_1):upi_cpu0_cpu1_p1p1_dp(2)" )
			)
			( signal "UPI_CPU0_CPU1_P1P1_DP<3>"
				( objectStatus "@baseboard_fab2_lib.baseboard_fab2(sch_1):upi_cpu0_cpu1_p1p1_dp(3)" )
			)
			( signal "UPI_CPU0_CPU1_P1P1_DP<4>"
				( objectStatus "@baseboard_fab2_lib.baseboard_fab2(sch_1):upi_cpu0_cpu1_p1p1_dp(4)" )
			)
			( signal "UPI_CPU0_CPU1_P1P1_DP<5>"
				( objectStatus "@baseboard_fab2_lib.baseboard_fab2(sch_1):upi_cpu0_cpu1_p1p1_dp(5)" )
			)
			( signal "UPI_CPU0_CPU1_P1P1_DP<6>"
				( objectStatus "@baseboard_fab2_lib.baseboard_fab2(sch_1):upi_cpu0_cpu1_p1p1_dp(6)" )
			)
			( signal "UPI_CPU0_CPU1_P1P1_DP<7>"
				( objectStatus "@baseboard_fab2_lib.baseboard_fab2(sch_1):upi_cpu0_cpu1_p1p1_dp(7)" )
			)
			( signal "UPI_CPU0_CPU1_P1P1_DP<8>"
				( objectStatus "@baseboard_fab2_lib.baseboard_fab2(sch_1):upi_cpu0_cpu1_p1p1_dp(8)" )
			)
			( signal "UPI_CPU0_CPU1_P1P1_DP<9>"
				( objectStatus "@baseboard_fab2_lib.baseboard_fab2(sch_1):upi_cpu0_cpu1_p1p1_dp(9)" )
			)
			( signal "UPI_CPU0_CPU1_P1P1_DP<10>"
				( objectStatus "@baseboard_fab2_lib.baseboard_fab2(sch_1):upi_cpu0_cpu1_p1p1_dp(10)" )
			)
			( signal "UPI_CPU0_CPU1_P1P1_DP<11>"
				( objectStatus "@baseboard_fab2_lib.baseboard_fab2(sch_1):upi_cpu0_cpu1_p1p1_dp(11)" )
			)
			( signal "UPI_CPU0_CPU1_P1P1_DP<12>"
				( objectStatus "@baseboard_fab2_lib.baseboard_fab2(sch_1):upi_cpu0_cpu1_p1p1_dp(12)" )
			)
			( signal "UPI_CPU0_CPU1_P1P1_DP<13>"
				( objectStatus "@baseboard_fab2_lib.baseboard_fab2(sch_1):upi_cpu0_cpu1_p1p1_dp(13)" )
			)
			( signal "UPI_CPU0_CPU1_P1P1_DP<14>"
				( objectStatus "@baseboard_fab2_lib.baseboard_fab2(sch_1):upi_cpu0_cpu1_p1p1_dp(14)" )
			)
			( signal "UPI_CPU0_CPU1_P1P1_DP<15>"
				( objectStatus "@baseboard_fab2_lib.baseboard_fab2(sch_1):upi_cpu0_cpu1_p1p1_dp(15)" )
			)
			( signal "UPI_CPU0_CPU1_P1P1_DP<16>"
				( objectStatus "@baseboard_fab2_lib.baseboard_fab2(sch_1):upi_cpu0_cpu1_p1p1_dp(16)" )
			)
			( signal "UPI_CPU0_CPU1_P1P1_DP<17>"
				( objectStatus "@baseboard_fab2_lib.baseboard_fab2(sch_1):upi_cpu0_cpu1_p1p1_dp(17)" )
			)
			( signal "UPI_CPU0_CPU1_P1P1_DP<18>"
				( objectStatus "@baseboard_fab2_lib.baseboard_fab2(sch_1):upi_cpu0_cpu1_p1p1_dp(18)" )
			)
			( signal "UPI_CPU0_CPU1_P1P1_DP<19>"
				( objectStatus "@baseboard_fab2_lib.baseboard_fab2(sch_1):upi_cpu0_cpu1_p1p1_dp(19)" )
			)
			( signal "UPI_CPU1_CPU0_P1P1_DN<0>"
				( objectStatus "@baseboard_fab2_lib.baseboard_fab2(sch_1):upi_cpu1_cpu0_p1p1_dn(0)" )
			)
			( signal "UPI_CPU1_CPU0_P1P1_DN<1>"
				( objectStatus "@baseboard_fab2_lib.baseboard_fab2(sch_1):upi_cpu1_cpu0_p1p1_dn(1)" )
			)
			( signal "UPI_CPU1_CPU0_P1P1_DN<2>"
				( objectStatus "@baseboard_fab2_lib.baseboard_fab2(sch_1):upi_cpu1_cpu0_p1p1_dn(2)" )
			)
			( signal "UPI_CPU1_CPU0_P1P1_DN<3>"
				( objectStatus "@baseboard_fab2_lib.baseboard_fab2(sch_1):upi_cpu1_cpu0_p1p1_dn(3)" )
			)
			( signal "UPI_CPU1_CPU0_P1P1_DN<4>"
				( objectStatus "@baseboard_fab2_lib.baseboard_fab2(sch_1):upi_cpu1_cpu0_p1p1_dn(4)" )
			)
			( signal "UPI_CPU1_CPU0_P1P1_DN<5>"
				( objectStatus "@baseboard_fab2_lib.baseboard_fab2(sch_1):upi_cpu1_cpu0_p1p1_dn(5)" )
			)
			( signal "UPI_CPU1_CPU0_P1P1_DN<6>"
				( objectStatus "@baseboard_fab2_lib.baseboard_fab2(sch_1):upi_cpu1_cpu0_p1p1_dn(6)" )
			)
			( signal "UPI_CPU1_CPU0_P1P1_DN<7>"
				( objectStatus "@baseboard_fab2_lib.baseboard_fab2(sch_1):upi_cpu1_cpu0_p1p1_dn(7)" )
			)
			( signal "UPI_CPU1_CPU0_P1P1_DN<8>"
				( objectStatus "@baseboard_fab2_lib.baseboard_fab2(sch_1):upi_cpu1_cpu0_p1p1_dn(8)" )
			)
			( signal "UPI_CPU1_CPU0_P1P1_DN<9>"
				( objectStatus "@baseboard_fab2_lib.baseboard_fab2(sch_1):upi_cpu1_cpu0_p1p1_dn(9)" )
			)
			( signal "UPI_CPU1_CPU0_P1P1_DN<10>"
				( objectStatus "@baseboard_fab2_lib.baseboard_fab2(sch_1):upi_cpu1_cpu0_p1p1_dn(10)" )
			)
			( signal "UPI_CPU1_CPU0_P1P1_DN<11>"
				( objectStatus "@baseboard_fab2_lib.baseboard_fab2(sch_1):upi_cpu1_cpu0_p1p1_dn(11)" )
			)
			( signal "UPI_CPU1_CPU0_P1P1_DN<12>"
				( objectStatus "@baseboard_fab2_lib.baseboard_fab2(sch_1):upi_cpu1_cpu0_p1p1_dn(12)" )
			)
			( signal "UPI_CPU1_CPU0_P1P1_DN<13>"
				( objectStatus "@baseboard_fab2_lib.baseboard_fab2(sch_1):upi_cpu1_cpu0_p1p1_dn(13)" )
			)
			( signal "UPI_CPU1_CPU0_P1P1_DN<14>"
				( objectStatus "@baseboard_fab2_lib.baseboard_fab2(sch_1):upi_cpu1_cpu0_p1p1_dn(14)" )
			)
			( signal "UPI_CPU1_CPU0_P1P1_DN<15>"
				( objectStatus "@baseboard_fab2_lib.baseboard_fab2(sch_1):upi_cpu1_cpu0_p1p1_dn(15)" )
			)
			( signal "UPI_CPU1_CPU0_P1P1_DN<16>"
				( objectStatus "@baseboard_fab2_lib.baseboard_fab2(sch_1):upi_cpu1_cpu0_p1p1_dn(16)" )
			)
			( signal "UPI_CPU1_CPU0_P1P1_DN<17>"
				( objectStatus "@baseboard_fab2_lib.baseboard_fab2(sch_1):upi_cpu1_cpu0_p1p1_dn(17)" )
			)
			( signal "UPI_CPU1_CPU0_P1P1_DN<18>"
				( objectStatus "@baseboard_fab2_lib.baseboard_fab2(sch_1):upi_cpu1_cpu0_p1p1_dn(18)" )
			)
			( signal "UPI_CPU1_CPU0_P1P1_DN<19>"
				( objectStatus "@baseboard_fab2_lib.baseboard_fab2(sch_1):upi_cpu1_cpu0_p1p1_dn(19)" )
			)
			( signal "UPI_CPU1_CPU0_P1P1_DP<0>"
				( objectStatus "@baseboard_fab2_lib.baseboard_fab2(sch_1):upi_cpu1_cpu0_p1p1_dp(0)" )
			)
			( signal "UPI_CPU1_CPU0_P1P1_DP<1>"
				( objectStatus "@baseboard_fab2_lib.baseboard_fab2(sch_1):upi_cpu1_cpu0_p1p1_dp(1)" )
			)
			( signal "UPI_CPU1_CPU0_P1P1_DP<2>"
				( objectStatus "@baseboard_fab2_lib.baseboard_fab2(sch_1):upi_cpu1_cpu0_p1p1_dp(2)" )
			)
			( signal "UPI_CPU1_CPU0_P1P1_DP<3>"
				( objectStatus "@baseboard_fab2_lib.baseboard_fab2(sch_1):upi_cpu1_cpu0_p1p1_dp(3)" )
			)
			( signal "UPI_CPU1_CPU0_P1P1_DP<4>"
				( objectStatus "@baseboard_fab2_lib.baseboard_fab2(sch_1):upi_cpu1_cpu0_p1p1_dp(4)" )
			)
			( signal "UPI_CPU1_CPU0_P1P1_DP<5>"
				( objectStatus "@baseboard_fab2_lib.baseboard_fab2(sch_1):upi_cpu1_cpu0_p1p1_dp(5)" )
			)
			( signal "UPI_CPU1_CPU0_P1P1_DP<6>"
				( objectStatus "@baseboard_fab2_lib.baseboard_fab2(sch_1):upi_cpu1_cpu0_p1p1_dp(6)" )
			)
			( signal "UPI_CPU1_CPU0_P1P1_DP<7>"
				( objectStatus "@baseboard_fab2_lib.baseboard_fab2(sch_1):upi_cpu1_cpu0_p1p1_dp(7)" )
			)
			( signal "UPI_CPU1_CPU0_P1P1_DP<8>"
				( objectStatus "@baseboard_fab2_lib.baseboard_fab2(sch_1):upi_cpu1_cpu0_p1p1_dp(8)" )
			)
			( signal "UPI_CPU1_CPU0_P1P1_DP<9>"
				( objectStatus "@baseboard_fab2_lib.baseboard_fab2(sch_1):upi_cpu1_cpu0_p1p1_dp(9)" )
			)
			( signal "UPI_CPU1_CPU0_P1P1_DP<10>"
				( objectStatus "@baseboard_fab2_lib.baseboard_fab2(sch_1):upi_cpu1_cpu0_p1p1_dp(10)" )
			)
			( signal "UPI_CPU1_CPU0_P1P1_DP<11>"
				( objectStatus "@baseboard_fab2_lib.baseboard_fab2(sch_1):upi_cpu1_cpu0_p1p1_dp(11)" )
			)
			( signal "UPI_CPU1_CPU0_P1P1_DP<12>"
				( objectStatus "@baseboard_fab2_lib.baseboard_fab2(sch_1):upi_cpu1_cpu0_p1p1_dp(12)" )
			)
			( signal "UPI_CPU1_CPU0_P1P1_DP<13>"
				( objectStatus "@baseboard_fab2_lib.baseboard_fab2(sch_1):upi_cpu1_cpu0_p1p1_dp(13)" )
			)
			( signal "UPI_CPU1_CPU0_P1P1_DP<14>"
				( objectStatus "@baseboard_fab2_lib.baseboard_fab2(sch_1):upi_cpu1_cpu0_p1p1_dp(14)" )
			)
			( signal "UPI_CPU1_CPU0_P1P1_DP<15>"
				( objectStatus "@baseboard_fab2_lib.baseboard_fab2(sch_1):upi_cpu1_cpu0_p1p1_dp(15)" )
			)
			( signal "UPI_CPU1_CPU0_P1P1_DP<16>"
				( objectStatus "@baseboard_fab2_lib.baseboard_fab2(sch_1):upi_cpu1_cpu0_p1p1_dp(16)" )
			)
			( signal "UPI_CPU1_CPU0_P1P1_DP<17>"
				( objectStatus "@baseboard_fab2_lib.baseboard_fab2(sch_1):upi_cpu1_cpu0_p1p1_dp(17)" )
			)
			( signal "UPI_CPU1_CPU0_P1P1_DP<18>"
				( objectStatus "@baseboard_fab2_lib.baseboard_fab2(sch_1):upi_cpu1_cpu0_p1p1_dp(18)" )
			)
			( signal "UPI_CPU1_CPU0_P1P1_DP<19>"
				( objectStatus "@baseboard_fab2_lib.baseboard_fab2(sch_1):upi_cpu1_cpu0_p1p1_dp(19)" )
			)
			( signal "TP_CPU0_UPI2_RSVD_CA12"
				( objectStatus "@baseboard_fab2_lib.baseboard_fab2(sch_1):tp_cpu0_upi2_rsvd_ca12" )
			)
			( signal "TP_CPU0_UPI2_RSVD_CB11"
				( objectStatus "@baseboard_fab2_lib.baseboard_fab2(sch_1):tp_cpu0_upi2_rsvd_cb11" )
			)
			( signal "TP_CPU0_UPI2_RSVD_CC10"
				( objectStatus "@baseboard_fab2_lib.baseboard_fab2(sch_1):tp_cpu0_upi2_rsvd_cc10" )
			)
			( signal "TP_CPU0_UPI2_RSVD_CC12"
				( objectStatus "@baseboard_fab2_lib.baseboard_fab2(sch_1):tp_cpu0_upi2_rsvd_cc12" )
			)
			( signal "TP_CPU0_UPI2_RSVD_CD11"
				( objectStatus "@baseboard_fab2_lib.baseboard_fab2(sch_1):tp_cpu0_upi2_rsvd_cd11" )
			)
			( signal "TP_CPU0_UPI2_RSVD_CE12"
				( objectStatus "@baseboard_fab2_lib.baseboard_fab2(sch_1):tp_cpu0_upi2_rsvd_ce12" )
			)
			( signal "TP_CPU0_UPI2_RSVD_CF11"
				( objectStatus "@baseboard_fab2_lib.baseboard_fab2(sch_1):tp_cpu0_upi2_rsvd_cf11" )
			)
			( signal "TP_CPU0_UPI2_RSVD_CF13"
				( objectStatus "@baseboard_fab2_lib.baseboard_fab2(sch_1):tp_cpu0_upi2_rsvd_cf13" )
			)
			( signal "TP_CPU0_UPI2_RSVD_CG12"
				( objectStatus "@baseboard_fab2_lib.baseboard_fab2(sch_1):tp_cpu0_upi2_rsvd_cg12" )
			)
			( signal "TP_CPU0_UPI2_RSVD_CH11"
				( objectStatus "@baseboard_fab2_lib.baseboard_fab2(sch_1):tp_cpu0_upi2_rsvd_ch11" )
			)
			( signal "TP_CPU0_UPI2_RSVD_CH13"
				( objectStatus "@baseboard_fab2_lib.baseboard_fab2(sch_1):tp_cpu0_upi2_rsvd_ch13" )
			)
			( signal "TP_CPU0_UPI2_RSVD_CJ14"
				( objectStatus "@baseboard_fab2_lib.baseboard_fab2(sch_1):tp_cpu0_upi2_rsvd_cj14" )
			)
			( signal "TP_CPU0_UPI2_RSVD_CK13"
				( objectStatus "@baseboard_fab2_lib.baseboard_fab2(sch_1):tp_cpu0_upi2_rsvd_ck13" )
			)
			( signal "TP_CPU0_UPI2_RSVD_CM13"
				( objectStatus "@baseboard_fab2_lib.baseboard_fab2(sch_1):tp_cpu0_upi2_rsvd_cm13" )
			)
			( signal "TP_CPU0_UPI2_RSVD_CR14"
				( objectStatus "@baseboard_fab2_lib.baseboard_fab2(sch_1):tp_cpu0_upi2_rsvd_cr14" )
			)
			( signal "TP_CPU0_UPI2_RSVD_CU14"
				( objectStatus "@baseboard_fab2_lib.baseboard_fab2(sch_1):tp_cpu0_upi2_rsvd_cu14" )
			)
			( signal "TP_CPU0_UPI2_RSVD_CV13"
				( objectStatus "@baseboard_fab2_lib.baseboard_fab2(sch_1):tp_cpu0_upi2_rsvd_cv13" )
			)
			( signal "TP_CPU0_UPI2_RSVD_CW14"
				( objectStatus "@baseboard_fab2_lib.baseboard_fab2(sch_1):tp_cpu0_upi2_rsvd_cw14" )
			)
			( signal "TP_CPU0_UPI2_RSVD_CW16"
				( objectStatus "@baseboard_fab2_lib.baseboard_fab2(sch_1):tp_cpu0_upi2_rsvd_cw16" )
			)
			( signal "TP_CPU0_UPI2_RSVD_DA16"
				( objectStatus "@baseboard_fab2_lib.baseboard_fab2(sch_1):tp_cpu0_upi2_rsvd_da16" )
			)
			( signal "TP_CPU0_UPI2_RSVD_DB15"
				( objectStatus "@baseboard_fab2_lib.baseboard_fab2(sch_1):tp_cpu0_upi2_rsvd_db15" )
			)
			( signal "TP_CPU0_UPI2_RSVD_DC16"
				( objectStatus "@baseboard_fab2_lib.baseboard_fab2(sch_1):tp_cpu0_upi2_rsvd_dc16" )
			)
			( signal "TP_CPU0_UPI2_RSVD_DD15"
				( objectStatus "@baseboard_fab2_lib.baseboard_fab2(sch_1):tp_cpu0_upi2_rsvd_dd15" )
			)
			( signal "TP_CPU0_UPI2_RSVD_DD17"
				( objectStatus "@baseboard_fab2_lib.baseboard_fab2(sch_1):tp_cpu0_upi2_rsvd_dd17" )
			)
			( signal "TP_CPU0_UPI2_RSVD_DE16"
				( objectStatus "@baseboard_fab2_lib.baseboard_fab2(sch_1):tp_cpu0_upi2_rsvd_de16" )
			)
			( signal "TP_CPU0_UPI2_RSVD_DF15"
				( objectStatus "@baseboard_fab2_lib.baseboard_fab2(sch_1):tp_cpu0_upi2_rsvd_df15" )
			)
			( signal "TP_CPU0_UPI2_RSVD_DF17"
				( objectStatus "@baseboard_fab2_lib.baseboard_fab2(sch_1):tp_cpu0_upi2_rsvd_df17" )
			)
			( signal "TP_CPU0_UPI2_RSVD_DG18"
				( objectStatus "@baseboard_fab2_lib.baseboard_fab2(sch_1):tp_cpu0_upi2_rsvd_dg18" )
			)
			( signal "TP_CPU0_UPI2_RSVD_DG20"
				( objectStatus "@baseboard_fab2_lib.baseboard_fab2(sch_1):tp_cpu0_upi2_rsvd_dg20" )
			)
			( signal "TP_CPU0_UPI2_RSVD_DH17"
				( objectStatus "@baseboard_fab2_lib.baseboard_fab2(sch_1):tp_cpu0_upi2_rsvd_dh17" )
			)
			( signal "TP_CPU0_UPI2_RSVD_DH19"
				( objectStatus "@baseboard_fab2_lib.baseboard_fab2(sch_1):tp_cpu0_upi2_rsvd_dh19" )
			)
			( signal "TP_CPU0_UPI2_RSVD_DJ18"
				( objectStatus "@baseboard_fab2_lib.baseboard_fab2(sch_1):tp_cpu0_upi2_rsvd_dj18" )
			)
			( signal "TP_CPU0_UPI2_RSVD_DJ20"
				( objectStatus "@baseboard_fab2_lib.baseboard_fab2(sch_1):tp_cpu0_upi2_rsvd_dj20" )
			)
			( signal "TP_CPU0_UPI2_RSVD_DK17"
				( objectStatus "@baseboard_fab2_lib.baseboard_fab2(sch_1):tp_cpu0_upi2_rsvd_dk17" )
			)
			( signal "TP_CPU0_UPI2_RSVD_DK19"
				( objectStatus "@baseboard_fab2_lib.baseboard_fab2(sch_1):tp_cpu0_upi2_rsvd_dk19" )
			)
			( signal "TP_CPU0_UPI2_RSVD_DL20"
				( objectStatus "@baseboard_fab2_lib.baseboard_fab2(sch_1):tp_cpu0_upi2_rsvd_dl20" )
			)
			( signal "TP_CPU0_UPI2_RSVD_DM21"
				( objectStatus "@baseboard_fab2_lib.baseboard_fab2(sch_1):tp_cpu0_upi2_rsvd_dm21" )
			)
			( signal "TP_CPU0_UPI2_RSVD_DN20"
				( objectStatus "@baseboard_fab2_lib.baseboard_fab2(sch_1):tp_cpu0_upi2_rsvd_dn20" )
			)
			( signal "TP_CPU0_UPI2_RSVD_DP21"
				( objectStatus "@baseboard_fab2_lib.baseboard_fab2(sch_1):tp_cpu0_upi2_rsvd_dp21" )
			)
			( signal "TP_CPU0_UPI2_RSVD_DT21"
				( objectStatus "@baseboard_fab2_lib.baseboard_fab2(sch_1):tp_cpu0_upi2_rsvd_dt21" )
			)
			( signal "CLK_100M_CPU0_RC_REFCLK1_DN"
				( objectStatus "@baseboard_fab2_lib.baseboard_fab2(sch_1):clk_100m_cpu0_rc_refclk1_dn" )
			)
			( signal "CLK_100M_CPU0_RC_REFCLK1_DP"
				( objectStatus "@baseboard_fab2_lib.baseboard_fab2(sch_1):clk_100m_cpu0_rc_refclk1_dp" )
			)
			( signal "TP_CPU0_RSVD_100"
				( objectStatus "@baseboard_fab2_lib.baseboard_fab2(sch_1):tp_cpu0_rsvd_100" )
			)
			( signal "TP_CPU0_RSVD_101"
				( objectStatus "@baseboard_fab2_lib.baseboard_fab2(sch_1):tp_cpu0_rsvd_101" )
			)
			( signal "TP_CPU0_RSVD_105"
				( objectStatus "@baseboard_fab2_lib.baseboard_fab2(sch_1):tp_cpu0_rsvd_105" )
			)
			( signal "TP_CPU0_RSVD_106"
				( objectStatus "@baseboard_fab2_lib.baseboard_fab2(sch_1):tp_cpu0_rsvd_106" )
			)
			( signal "TP_CPU0_RSVD_108"
				( objectStatus "@baseboard_fab2_lib.baseboard_fab2(sch_1):tp_cpu0_rsvd_108" )
			)
			( signal "TP_CPU0_RSVD_111"
				( objectStatus "@baseboard_fab2_lib.baseboard_fab2(sch_1):tp_cpu0_rsvd_111" )
			)
			( signal "TP_CPU0_RSVD_113"
				( objectStatus "@baseboard_fab2_lib.baseboard_fab2(sch_1):tp_cpu0_rsvd_113" )
			)
			( signal "TP_CPU0_RSVD_114"
				( objectStatus "@baseboard_fab2_lib.baseboard_fab2(sch_1):tp_cpu0_rsvd_114" )
			)
			( signal "TP_CPU0_RSVD_117"
				( objectStatus "@baseboard_fab2_lib.baseboard_fab2(sch_1):tp_cpu0_rsvd_117" )
			)
			( signal "TP_CPU0_RSVD_119"
				( objectStatus "@baseboard_fab2_lib.baseboard_fab2(sch_1):tp_cpu0_rsvd_119" )
			)
			( signal "TP_CPU0_RSVD_121"
				( objectStatus "@baseboard_fab2_lib.baseboard_fab2(sch_1):tp_cpu0_rsvd_121" )
			)
			( signal "TP_CPU0_RSVD_123"
				( objectStatus "@baseboard_fab2_lib.baseboard_fab2(sch_1):tp_cpu0_rsvd_123" )
			)
			( signal "TP_CPU0_RSVD_124"
				( objectStatus "@baseboard_fab2_lib.baseboard_fab2(sch_1):tp_cpu0_rsvd_124" )
			)
			( signal "TP_CPU0_RSVD_144"
				( objectStatus "@baseboard_fab2_lib.baseboard_fab2(sch_1):tp_cpu0_rsvd_144" )
			)
			( signal "TP_CPU0_RSVD_145"
				( objectStatus "@baseboard_fab2_lib.baseboard_fab2(sch_1):tp_cpu0_rsvd_145" )
			)
			( signal "TP_CPU0_RSVD_146"
				( objectStatus "@baseboard_fab2_lib.baseboard_fab2(sch_1):tp_cpu0_rsvd_146" )
			)
			( signal "TP_CPU0_RSVD_147"
				( objectStatus "@baseboard_fab2_lib.baseboard_fab2(sch_1):tp_cpu0_rsvd_147" )
			)
			( signal "TP_CPU0_RSVD_148"
				( objectStatus "@baseboard_fab2_lib.baseboard_fab2(sch_1):tp_cpu0_rsvd_148" )
			)
			( signal "TP_CPU0_RSVD_149"
				( objectStatus "@baseboard_fab2_lib.baseboard_fab2(sch_1):tp_cpu0_rsvd_149" )
			)
			( signal "TP_CPU0_RSVD_150"
				( objectStatus "@baseboard_fab2_lib.baseboard_fab2(sch_1):tp_cpu0_rsvd_150" )
			)
			( signal "TP_CPU0_RSVD_151"
				( objectStatus "@baseboard_fab2_lib.baseboard_fab2(sch_1):tp_cpu0_rsvd_151" )
			)
			( signal "TP_CPU0_RSVD_152"
				( objectStatus "@baseboard_fab2_lib.baseboard_fab2(sch_1):tp_cpu0_rsvd_152" )
			)
			( signal "TP_CPU0_RSVD_154"
				( objectStatus "@baseboard_fab2_lib.baseboard_fab2(sch_1):tp_cpu0_rsvd_154" )
			)
			( signal "TP_CPU0_RSVD_155"
				( objectStatus "@baseboard_fab2_lib.baseboard_fab2(sch_1):tp_cpu0_rsvd_155" )
			)
			( signal "TP_CPU0_RSVD_156"
				( objectStatus "@baseboard_fab2_lib.baseboard_fab2(sch_1):tp_cpu0_rsvd_156" )
			)
			( signal "TP_CPU0_RSVD_157"
				( objectStatus "@baseboard_fab2_lib.baseboard_fab2(sch_1):tp_cpu0_rsvd_157" )
			)
			( signal "TP_CPU0_RSVD_158"
				( objectStatus "@baseboard_fab2_lib.baseboard_fab2(sch_1):tp_cpu0_rsvd_158" )
			)
			( signal "TP_CPU0_RSVD_159"
				( objectStatus "@baseboard_fab2_lib.baseboard_fab2(sch_1):tp_cpu0_rsvd_159" )
			)
			( signal "TP_CPU0_RSVD_160"
				( objectStatus "@baseboard_fab2_lib.baseboard_fab2(sch_1):tp_cpu0_rsvd_160" )
			)
			( signal "TP_CPU0_RSVD_161"
				( objectStatus "@baseboard_fab2_lib.baseboard_fab2(sch_1):tp_cpu0_rsvd_161" )
			)
			( signal "TP_CPU0_RSVD_162"
				( objectStatus "@baseboard_fab2_lib.baseboard_fab2(sch_1):tp_cpu0_rsvd_162" )
			)
			( signal "TP_CPU0_RSVD_163"
				( objectStatus "@baseboard_fab2_lib.baseboard_fab2(sch_1):tp_cpu0_rsvd_163" )
			)
			( signal "TP_CPU0_RSVD_164"
				( objectStatus "@baseboard_fab2_lib.baseboard_fab2(sch_1):tp_cpu0_rsvd_164" )
			)
			( signal "TP_CPU0_RSVD_166"
				( objectStatus "@baseboard_fab2_lib.baseboard_fab2(sch_1):tp_cpu0_rsvd_166" )
			)
			( signal "TP_CPU0_RSVD_167"
				( objectStatus "@baseboard_fab2_lib.baseboard_fab2(sch_1):tp_cpu0_rsvd_167" )
			)
			( signal "TP_CPU0_RSVD_168"
				( objectStatus "@baseboard_fab2_lib.baseboard_fab2(sch_1):tp_cpu0_rsvd_168" )
			)
			( signal "TP_CPU0_RSVD_169"
				( objectStatus "@baseboard_fab2_lib.baseboard_fab2(sch_1):tp_cpu0_rsvd_169" )
			)
			( signal "TP_CPU0_RSVD_170"
				( objectStatus "@baseboard_fab2_lib.baseboard_fab2(sch_1):tp_cpu0_rsvd_170" )
			)
			( signal "TP_CPU0_RSVD_171"
				( objectStatus "@baseboard_fab2_lib.baseboard_fab2(sch_1):tp_cpu0_rsvd_171" )
			)
			( signal "TP_CPU0_RSVD_255"
				( objectStatus "@baseboard_fab2_lib.baseboard_fab2(sch_1):tp_cpu0_rsvd_255" )
			)
			( signal "TP_CPU0_RSVD_82"
				( objectStatus "@baseboard_fab2_lib.baseboard_fab2(sch_1):tp_cpu0_rsvd_82" )
			)
			( signal "TP_CPU0_RSVD_85"
				( objectStatus "@baseboard_fab2_lib.baseboard_fab2(sch_1):tp_cpu0_rsvd_85" )
			)
			( signal "TP_CPU0_RSVD_90"
				( objectStatus "@baseboard_fab2_lib.baseboard_fab2(sch_1):tp_cpu0_rsvd_90" )
			)
			( signal "TP_CPU0_RSVD_91"
				( objectStatus "@baseboard_fab2_lib.baseboard_fab2(sch_1):tp_cpu0_rsvd_91" )
			)
			( signal "TP_CPU0_RSVD_94"
				( objectStatus "@baseboard_fab2_lib.baseboard_fab2(sch_1):tp_cpu0_rsvd_94" )
			)
			( signal "TP_CPU0_RSVD_95"
				( objectStatus "@baseboard_fab2_lib.baseboard_fab2(sch_1):tp_cpu0_rsvd_95" )
			)
			( signal "TP_CPU0_RSVD_97"
				( objectStatus "@baseboard_fab2_lib.baseboard_fab2(sch_1):tp_cpu0_rsvd_97" )
			)
			( signal "TP_CPU0_RSVD_99"
				( objectStatus "@baseboard_fab2_lib.baseboard_fab2(sch_1):tp_cpu0_rsvd_99" )
			)
			( signal "TP_CPU0_TEST_10"
				( objectStatus "@baseboard_fab2_lib.baseboard_fab2(sch_1):tp_cpu0_test_10" )
			)
			( signal "TP_CPU0_TEST_6"
				( objectStatus "@baseboard_fab2_lib.baseboard_fab2(sch_1):tp_cpu0_test_6" )
			)
			( signal "TP_CPU0_TEST_7"
				( objectStatus "@baseboard_fab2_lib.baseboard_fab2(sch_1):tp_cpu0_test_7" )
			)
			( signal "TP_CPU0_TEST_8"
				( objectStatus "@baseboard_fab2_lib.baseboard_fab2(sch_1):tp_cpu0_test_8" )
			)
			( signal "TP_CPU0_TEST_9"
				( objectStatus "@baseboard_fab2_lib.baseboard_fab2(sch_1):tp_cpu0_test_9" )
			)
			( signal "PVCCIN_CPU0"
				( attribute "VOLTAGE" "2.0V"
					( Units "uVoltage" "V" 1.000000)
					( Status sAliasFlattened )
					( Origin gFrontEnd )
				)
				( objectStatus "@baseboard_fab2_lib.baseboard_fab2(sch_1):pvccin_cpu0" )
			)
			( signal "VSENSE_PMAX_CPU0"
				( objectStatus "@baseboard_fab2_lib.baseboard_fab2(sch_1):vsense_pmax_cpu0" )
			)
			( signal "VSENSE_PVCCIN_CPU0_SKT_VRTN"
				( objectStatus "@baseboard_fab2_lib.baseboard_fab2(sch_1):vsense_pvccin_cpu0_skt_vrtn" )
			)
			( signal "VSENSE_PVCCIN_CPU0_SKT_VSEN"
				( objectStatus "@baseboard_fab2_lib.baseboard_fab2(sch_1):vsense_pvccin_cpu0_skt_vsen" )
			)
			( signal "VSENSE_VCCINR2PMAX_CPU0"
				( objectStatus "@baseboard_fab2_lib.baseboard_fab2(sch_1):vsense_vccinr2pmax_cpu0" )
			)
			( signal "PVCCIOMCP_CPU0"
				( attribute "VOLTAGE" "+0.95"
					( Units "uVoltage" "V" 1.000000)
					( Status sAliasFlattened )
					( Origin gFrontEnd )
				)
				( objectStatus "@baseboard_fab2_lib.baseboard_fab2(sch_1):pvcciomcp_cpu0" )
			)
			( signal "PVDDQ_ABC"
				( attribute "VOLTAGE" "1.2V"
					( Units "uVoltage" "V" 1.000000)
					( Status sAliasFlattened )
					( Origin gFrontEnd )
				)
				( objectStatus "@baseboard_fab2_lib.baseboard_fab2(sch_1):pvddq_abc" )
			)
			( signal "PVDDQ_DEF"
				( attribute "VOLTAGE" "1.2V"
					( Units "uVoltage" "V" 1.000000)
					( Status sAliasFlattened )
					( Origin gFrontEnd )
				)
				( objectStatus "@baseboard_fab2_lib.baseboard_fab2(sch_1):pvddq_def" )
			)
			( signal "PVPP_ABC"
				( attribute "VOLTAGE" "2.5V"
					( Units "uVoltage" "V" 1.000000)
					( Status sAliasFlattened )
					( Origin gFrontEnd )
				)
				( objectStatus "@baseboard_fab2_lib.baseboard_fab2(sch_1):pvpp_abc" )
			)
			( signal "PVSA_CPU0"
				( attribute "VOLTAGE" "1.1V"
					( Units "uVoltage" "V" 1.000000)
					( Status sAliasFlattened )
					( Origin gFrontEnd )
				)
				( objectStatus "@baseboard_fab2_lib.baseboard_fab2(sch_1):pvsa_cpu0" )
			)
			( signal "PD_CPU0_MCP01_DMON"
				( objectStatus "@baseboard_fab2_lib.baseboard_fab2(sch_1):pd_cpu0_mcp01_dmon" )
			)
			( signal "TP_CPU0_KTI2_AMONV"
				( objectStatus "@baseboard_fab2_lib.baseboard_fab2(sch_1):tp_cpu0_kti2_amonv" )
			)
			( signal "TP_CPU0_KTI2_DFX_DN"
				( objectStatus "@baseboard_fab2_lib.baseboard_fab2(sch_1):tp_cpu0_kti2_dfx_dn" )
			)
			( signal "TP_CPU0_RSVD_0"
				( objectStatus "@baseboard_fab2_lib.baseboard_fab2(sch_1):tp_cpu0_rsvd_0" )
			)
			( signal "TP_CPU0_RSVD_1"
				( objectStatus "@baseboard_fab2_lib.baseboard_fab2(sch_1):tp_cpu0_rsvd_1" )
			)
			( signal "TP_CPU0_RSVD_10"
				( objectStatus "@baseboard_fab2_lib.baseboard_fab2(sch_1):tp_cpu0_rsvd_10" )
			)
			( signal "TP_CPU0_RSVD_11"
				( objectStatus "@baseboard_fab2_lib.baseboard_fab2(sch_1):tp_cpu0_rsvd_11" )
			)
			( signal "TP_CPU0_RSVD_12"
				( objectStatus "@baseboard_fab2_lib.baseboard_fab2(sch_1):tp_cpu0_rsvd_12" )
			)
			( signal "TP_CPU0_RSVD_13"
				( objectStatus "@baseboard_fab2_lib.baseboard_fab2(sch_1):tp_cpu0_rsvd_13" )
			)
			( signal "TP_CPU0_RSVD_14"
				( objectStatus "@baseboard_fab2_lib.baseboard_fab2(sch_1):tp_cpu0_rsvd_14" )
			)
			( signal "TP_CPU0_RSVD_15"
				( objectStatus "@baseboard_fab2_lib.baseboard_fab2(sch_1):tp_cpu0_rsvd_15" )
			)
			( signal "TP_CPU0_RSVD_16"
				( objectStatus "@baseboard_fab2_lib.baseboard_fab2(sch_1):tp_cpu0_rsvd_16" )
			)
			( signal "TP_CPU0_RSVD_17"
				( objectStatus "@baseboard_fab2_lib.baseboard_fab2(sch_1):tp_cpu0_rsvd_17" )
			)
			( signal "TP_CPU0_RSVD_18"
				( objectStatus "@baseboard_fab2_lib.baseboard_fab2(sch_1):tp_cpu0_rsvd_18" )
			)
			( signal "TP_CPU0_RSVD_19"
				( objectStatus "@baseboard_fab2_lib.baseboard_fab2(sch_1):tp_cpu0_rsvd_19" )
			)
			( signal "TP_CPU0_RSVD_2"
				( objectStatus "@baseboard_fab2_lib.baseboard_fab2(sch_1):tp_cpu0_rsvd_2" )
			)
			( signal "TP_CPU0_RSVD_20"
				( objectStatus "@baseboard_fab2_lib.baseboard_fab2(sch_1):tp_cpu0_rsvd_20" )
			)
			( signal "TP_CPU0_RSVD_21"
				( objectStatus "@baseboard_fab2_lib.baseboard_fab2(sch_1):tp_cpu0_rsvd_21" )
			)
			( signal "TP_CPU0_RSVD_22"
				( objectStatus "@baseboard_fab2_lib.baseboard_fab2(sch_1):tp_cpu0_rsvd_22" )
			)
			( signal "TP_CPU0_RSVD_23"
				( objectStatus "@baseboard_fab2_lib.baseboard_fab2(sch_1):tp_cpu0_rsvd_23" )
			)
			( signal "TP_CPU0_RSVD_24"
				( objectStatus "@baseboard_fab2_lib.baseboard_fab2(sch_1):tp_cpu0_rsvd_24" )
			)
			( signal "TP_CPU0_RSVD_25"
				( objectStatus "@baseboard_fab2_lib.baseboard_fab2(sch_1):tp_cpu0_rsvd_25" )
			)
			( signal "TP_CPU0_RSVD_26"
				( objectStatus "@baseboard_fab2_lib.baseboard_fab2(sch_1):tp_cpu0_rsvd_26" )
			)
			( signal "TP_CPU0_RSVD_27"
				( objectStatus "@baseboard_fab2_lib.baseboard_fab2(sch_1):tp_cpu0_rsvd_27" )
			)
			( signal "TP_CPU0_RSVD_28"
				( objectStatus "@baseboard_fab2_lib.baseboard_fab2(sch_1):tp_cpu0_rsvd_28" )
			)
			( signal "TP_CPU0_RSVD_29"
				( objectStatus "@baseboard_fab2_lib.baseboard_fab2(sch_1):tp_cpu0_rsvd_29" )
			)
			( signal "TP_CPU0_RSVD_3"
				( objectStatus "@baseboard_fab2_lib.baseboard_fab2(sch_1):tp_cpu0_rsvd_3" )
			)
			( signal "TP_CPU0_RSVD_30"
				( objectStatus "@baseboard_fab2_lib.baseboard_fab2(sch_1):tp_cpu0_rsvd_30" )
			)
			( signal "TP_CPU0_RSVD_31"
				( objectStatus "@baseboard_fab2_lib.baseboard_fab2(sch_1):tp_cpu0_rsvd_31" )
			)
			( signal "TP_CPU0_RSVD_32"
				( objectStatus "@baseboard_fab2_lib.baseboard_fab2(sch_1):tp_cpu0_rsvd_32" )
			)
			( signal "TP_CPU0_RSVD_33"
				( objectStatus "@baseboard_fab2_lib.baseboard_fab2(sch_1):tp_cpu0_rsvd_33" )
			)
			( signal "TP_CPU0_RSVD_34"
				( objectStatus "@baseboard_fab2_lib.baseboard_fab2(sch_1):tp_cpu0_rsvd_34" )
			)
			( signal "TP_CPU0_RSVD_35"
				( objectStatus "@baseboard_fab2_lib.baseboard_fab2(sch_1):tp_cpu0_rsvd_35" )
			)
			( signal "TP_CPU0_RSVD_36"
				( objectStatus "@baseboard_fab2_lib.baseboard_fab2(sch_1):tp_cpu0_rsvd_36" )
			)
			( signal "TP_CPU0_RSVD_37"
				( objectStatus "@baseboard_fab2_lib.baseboard_fab2(sch_1):tp_cpu0_rsvd_37" )
			)
			( signal "TP_CPU0_RSVD_38"
				( objectStatus "@baseboard_fab2_lib.baseboard_fab2(sch_1):tp_cpu0_rsvd_38" )
			)
			( signal "TP_CPU0_RSVD_39"
				( objectStatus "@baseboard_fab2_lib.baseboard_fab2(sch_1):tp_cpu0_rsvd_39" )
			)
			( signal "TP_CPU0_RSVD_4"
				( objectStatus "@baseboard_fab2_lib.baseboard_fab2(sch_1):tp_cpu0_rsvd_4" )
			)
			( signal "TP_CPU0_RSVD_40"
				( objectStatus "@baseboard_fab2_lib.baseboard_fab2(sch_1):tp_cpu0_rsvd_40" )
			)
			( signal "TP_CPU0_RSVD_41"
				( objectStatus "@baseboard_fab2_lib.baseboard_fab2(sch_1):tp_cpu0_rsvd_41" )
			)
			( signal "TP_CPU0_RSVD_42"
				( objectStatus "@baseboard_fab2_lib.baseboard_fab2(sch_1):tp_cpu0_rsvd_42" )
			)
			( signal "TP_CPU0_RSVD_43"
				( objectStatus "@baseboard_fab2_lib.baseboard_fab2(sch_1):tp_cpu0_rsvd_43" )
			)
			( signal "TP_CPU0_RSVD_44"
				( objectStatus "@baseboard_fab2_lib.baseboard_fab2(sch_1):tp_cpu0_rsvd_44" )
			)
			( signal "TP_CPU0_RSVD_45"
				( objectStatus "@baseboard_fab2_lib.baseboard_fab2(sch_1):tp_cpu0_rsvd_45" )
			)
			( signal "TP_CPU0_RSVD_46"
				( objectStatus "@baseboard_fab2_lib.baseboard_fab2(sch_1):tp_cpu0_rsvd_46" )
			)
			( signal "TP_CPU0_RSVD_47"
				( objectStatus "@baseboard_fab2_lib.baseboard_fab2(sch_1):tp_cpu0_rsvd_47" )
			)
			( signal "TP_CPU0_RSVD_48"
				( objectStatus "@baseboard_fab2_lib.baseboard_fab2(sch_1):tp_cpu0_rsvd_48" )
			)
			( signal "TP_CPU0_RSVD_49"
				( objectStatus "@baseboard_fab2_lib.baseboard_fab2(sch_1):tp_cpu0_rsvd_49" )
			)
			( signal "TP_CPU0_RSVD_5"
				( objectStatus "@baseboard_fab2_lib.baseboard_fab2(sch_1):tp_cpu0_rsvd_5" )
			)
			( signal "TP_CPU0_RSVD_50"
				( objectStatus "@baseboard_fab2_lib.baseboard_fab2(sch_1):tp_cpu0_rsvd_50" )
			)
			( signal "TP_CPU0_RSVD_51"
				( objectStatus "@baseboard_fab2_lib.baseboard_fab2(sch_1):tp_cpu0_rsvd_51" )
			)
			( signal "TP_CPU0_RSVD_53"
				( objectStatus "@baseboard_fab2_lib.baseboard_fab2(sch_1):tp_cpu0_rsvd_53" )
			)
			( signal "TP_CPU0_RSVD_54"
				( objectStatus "@baseboard_fab2_lib.baseboard_fab2(sch_1):tp_cpu0_rsvd_54" )
			)
			( signal "TP_CPU0_RSVD_55"
				( objectStatus "@baseboard_fab2_lib.baseboard_fab2(sch_1):tp_cpu0_rsvd_55" )
			)
			( signal "TP_CPU0_RSVD_56"
				( objectStatus "@baseboard_fab2_lib.baseboard_fab2(sch_1):tp_cpu0_rsvd_56" )
			)
			( signal "TP_CPU0_RSVD_57"
				( objectStatus "@baseboard_fab2_lib.baseboard_fab2(sch_1):tp_cpu0_rsvd_57" )
			)
			( signal "TP_CPU0_RSVD_59"
				( objectStatus "@baseboard_fab2_lib.baseboard_fab2(sch_1):tp_cpu0_rsvd_59" )
			)
			( signal "TP_CPU0_RSVD_6"
				( objectStatus "@baseboard_fab2_lib.baseboard_fab2(sch_1):tp_cpu0_rsvd_6" )
			)
			( signal "TP_CPU0_RSVD_60"
				( objectStatus "@baseboard_fab2_lib.baseboard_fab2(sch_1):tp_cpu0_rsvd_60" )
			)
			( signal "TP_CPU0_RSVD_61"
				( objectStatus "@baseboard_fab2_lib.baseboard_fab2(sch_1):tp_cpu0_rsvd_61" )
			)
			( signal "TP_CPU0_RSVD_64"
				( objectStatus "@baseboard_fab2_lib.baseboard_fab2(sch_1):tp_cpu0_rsvd_64" )
			)
			( signal "TP_CPU0_RSVD_66"
				( objectStatus "@baseboard_fab2_lib.baseboard_fab2(sch_1):tp_cpu0_rsvd_66" )
			)
			( signal "TP_CPU0_RSVD_67"
				( objectStatus "@baseboard_fab2_lib.baseboard_fab2(sch_1):tp_cpu0_rsvd_67" )
			)
			( signal "TP_CPU0_RSVD_69"
				( objectStatus "@baseboard_fab2_lib.baseboard_fab2(sch_1):tp_cpu0_rsvd_69" )
			)
			( signal "TP_CPU0_RSVD_7"
				( objectStatus "@baseboard_fab2_lib.baseboard_fab2(sch_1):tp_cpu0_rsvd_7" )
			)
			( signal "TP_CPU0_RSVD_70"
				( objectStatus "@baseboard_fab2_lib.baseboard_fab2(sch_1):tp_cpu0_rsvd_70" )
			)
			( signal "TP_CPU0_RSVD_72"
				( objectStatus "@baseboard_fab2_lib.baseboard_fab2(sch_1):tp_cpu0_rsvd_72" )
			)
			( signal "TP_CPU0_RSVD_73"
				( objectStatus "@baseboard_fab2_lib.baseboard_fab2(sch_1):tp_cpu0_rsvd_73" )
			)
			( signal "TP_CPU0_RSVD_8"
				( objectStatus "@baseboard_fab2_lib.baseboard_fab2(sch_1):tp_cpu0_rsvd_8" )
			)
			( signal "TP_CPU0_RSVD_9"
				( objectStatus "@baseboard_fab2_lib.baseboard_fab2(sch_1):tp_cpu0_rsvd_9" )
			)
			( signal "VSENSE_PVCCIO_CPU0_SKT_VRTN"
				( objectStatus "@baseboard_fab2_lib.baseboard_fab2(sch_1):vsense_pvccio_cpu0_skt_vrtn" )
			)
			( signal "VSENSE_PVCCIO_CPU0_SKT_VSEN"
				( objectStatus "@baseboard_fab2_lib.baseboard_fab2(sch_1):vsense_pvccio_cpu0_skt_vsen" )
			)
			( signal "VSENSE_PVCCIOMCP_CPU0_SKT_VRTN"
				( objectStatus "@baseboard_fab2_lib.baseboard_fab2(sch_1):vsense_pvcciomcp_cpu0_skt_vrtn" )
			)
			( signal "VSENSE_PVCCIOMCP_CPU0_SKT_VSEN"
				( objectStatus "@baseboard_fab2_lib.baseboard_fab2(sch_1):vsense_pvcciomcp_cpu0_skt_vsen" )
			)
			( signal "VSENSE_PVCCMCP_CPU0_SKT_VRTN"
				( objectStatus "@baseboard_fab2_lib.baseboard_fab2(sch_1):vsense_pvccmcp_cpu0_skt_vrtn" )
			)
			( signal "VSENSE_PVCCMCP_CPU0_SKT_VSEN"
				( objectStatus "@baseboard_fab2_lib.baseboard_fab2(sch_1):vsense_pvccmcp_cpu0_skt_vsen" )
			)
			( signal "VSENSE_PVSA_CPU0_SKT_VRTN"
				( objectStatus "@baseboard_fab2_lib.baseboard_fab2(sch_1):vsense_pvsa_cpu0_skt_vrtn" )
			)
			( signal "VSENSE_PVSA_CPU0_SKT_VSEN"
				( objectStatus "@baseboard_fab2_lib.baseboard_fab2(sch_1):vsense_pvsa_cpu0_skt_vsen" )
			)
			( signal "FM_ADR_COMPLETE_ABC_N"
				( objectStatus "@baseboard_fab2_lib.baseboard_fab2(sch_1):fm_adr_complete_abc_n" )
			)
			( signal "FM_DIMM_EVENT_COD_N"
				( objectStatus "@baseboard_fab2_lib.baseboard_fab2(sch_1):fm_dimm_event_cod_n" )
			)
			( signal "M_A_VREF"
				( objectStatus "@baseboard_fab2_lib.baseboard_fab2(sch_1):m_a_vref" )
			)
			( signal "P12V_NVDIMM_ABC"
				( attribute "VOLTAGE" "12.0"
					( Units "uVoltage" "V" 1.000000)
					( Status sAliasFlattened )
					( Origin gFrontEnd )
				)
				( objectStatus "@baseboard_fab2_lib.baseboard_fab2(sch_1):p12v_nvdimm_abc" )
			)
			( signal "PVTT_ABC"
				( attribute "VOLTAGE" "0.6V"
					( Units "uVoltage" "V" 1.000000)
					( Status sAliasFlattened )
					( Origin gFrontEnd )
				)
				( objectStatus "@baseboard_fab2_lib.baseboard_fab2(sch_1):pvtt_abc" )
			)
			( signal "SMB_DDR_ABC_VPP_SCL"
				( objectStatus "@baseboard_fab2_lib.baseboard_fab2(sch_1):smb_ddr_abc_vpp_scl" )
			)
			( signal "SMB_DDR_ABC_VPP_SDA"
				( objectStatus "@baseboard_fab2_lib.baseboard_fab2(sch_1):smb_ddr_abc_vpp_sda" )
			)
			( signal "TP_CH_A_DIMM_A0_RFU_0"
				( objectStatus "@baseboard_fab2_lib.baseboard_fab2(sch_1):tp_ch_a_dimm_a0_rfu_0" )
			)
			( signal "TP_CH_A_DIMM_A0_RFU_1"
				( objectStatus "@baseboard_fab2_lib.baseboard_fab2(sch_1):tp_ch_a_dimm_a0_rfu_1" )
			)
			( signal "TP_CH_A_DIMM_A0_RFU_2"
				( objectStatus "@baseboard_fab2_lib.baseboard_fab2(sch_1):tp_ch_a_dimm_a0_rfu_2" )
			)
			( signal "TP_CH_A_DIMM_A1_RFU_0"
				( objectStatus "@baseboard_fab2_lib.baseboard_fab2(sch_1):tp_ch_a_dimm_a1_rfu_0" )
			)
			( signal "TP_CH_A_DIMM_A1_RFU_1"
				( objectStatus "@baseboard_fab2_lib.baseboard_fab2(sch_1):tp_ch_a_dimm_a1_rfu_1" )
			)
			( signal "TP_CH_A_DIMM_A1_RFU_2"
				( objectStatus "@baseboard_fab2_lib.baseboard_fab2(sch_1):tp_ch_a_dimm_a1_rfu_2" )
			)
			( signal "M_B_VREF"
				( objectStatus "@baseboard_fab2_lib.baseboard_fab2(sch_1):m_b_vref" )
			)
			( signal "TP_CH_B_DIMM_B0_RFU_0"
				( objectStatus "@baseboard_fab2_lib.baseboard_fab2(sch_1):tp_ch_b_dimm_b0_rfu_0" )
			)
			( signal "TP_CH_B_DIMM_B0_RFU_1"
				( objectStatus "@baseboard_fab2_lib.baseboard_fab2(sch_1):tp_ch_b_dimm_b0_rfu_1" )
			)
			( signal "TP_CH_B_DIMM_B0_RFU_2"
				( objectStatus "@baseboard_fab2_lib.baseboard_fab2(sch_1):tp_ch_b_dimm_b0_rfu_2" )
			)
			( signal "TP_CH_B_DIMM_B1_RFU_0"
				( objectStatus "@baseboard_fab2_lib.baseboard_fab2(sch_1):tp_ch_b_dimm_b1_rfu_0" )
			)
			( signal "TP_CH_B_DIMM_B1_RFU_1"
				( objectStatus "@baseboard_fab2_lib.baseboard_fab2(sch_1):tp_ch_b_dimm_b1_rfu_1" )
			)
			( signal "TP_CH_B_DIMM_B1_RFU_2"
				( objectStatus "@baseboard_fab2_lib.baseboard_fab2(sch_1):tp_ch_b_dimm_b1_rfu_2" )
			)
			( signal "M_C_VREF"
				( objectStatus "@baseboard_fab2_lib.baseboard_fab2(sch_1):m_c_vref" )
			)
			( signal "TP_CH_C_DIMM_C0_RFU_0"
				( objectStatus "@baseboard_fab2_lib.baseboard_fab2(sch_1):tp_ch_c_dimm_c0_rfu_0" )
			)
			( signal "TP_CH_C_DIMM_C0_RFU_1"
				( objectStatus "@baseboard_fab2_lib.baseboard_fab2(sch_1):tp_ch_c_dimm_c0_rfu_1" )
			)
			( signal "TP_CH_C_DIMM_C0_RFU_2"
				( objectStatus "@baseboard_fab2_lib.baseboard_fab2(sch_1):tp_ch_c_dimm_c0_rfu_2" )
			)
			( signal "TP_CH_C_DIMM_C1_RFU_0"
				( objectStatus "@baseboard_fab2_lib.baseboard_fab2(sch_1):tp_ch_c_dimm_c1_rfu_0" )
			)
			( signal "TP_CH_C_DIMM_C1_RFU_1"
				( objectStatus "@baseboard_fab2_lib.baseboard_fab2(sch_1):tp_ch_c_dimm_c1_rfu_1" )
			)
			( signal "TP_CH_C_DIMM_C1_RFU_2"
				( objectStatus "@baseboard_fab2_lib.baseboard_fab2(sch_1):tp_ch_c_dimm_c1_rfu_2" )
			)
			( signal "FM_ADR_COMPLETE_DEF_N"
				( objectStatus "@baseboard_fab2_lib.baseboard_fab2(sch_1):fm_adr_complete_def_n" )
			)
			( signal "M_D_VREF"
				( objectStatus "@baseboard_fab2_lib.baseboard_fab2(sch_1):m_d_vref" )
			)
			( signal "P12V_NVDIMM_DEF"
				( attribute "VOLTAGE" "12.0"
					( Units "uVoltage" "V" 1.000000)
					( Status sAliasFlattened )
					( Origin gFrontEnd )
				)
				( objectStatus "@baseboard_fab2_lib.baseboard_fab2(sch_1):p12v_nvdimm_def" )
			)
			( signal "PVPP_DEF"
				( attribute "VOLTAGE" "2.5V"
					( Units "uVoltage" "V" 1.000000)
					( Status sAliasFlattened )
					( Origin gFrontEnd )
				)
				( objectStatus "@baseboard_fab2_lib.baseboard_fab2(sch_1):pvpp_def" )
			)
			( signal "PVTT_DEF"
				( attribute "VOLTAGE" "0.6V"
					( Units "uVoltage" "V" 1.000000)
					( Status sAliasFlattened )
					( Origin gFrontEnd )
				)
				( objectStatus "@baseboard_fab2_lib.baseboard_fab2(sch_1):pvtt_def" )
			)
			( signal "SMB_DDR_DEF_VPP_SCL"
				( objectStatus "@baseboard_fab2_lib.baseboard_fab2(sch_1):smb_ddr_def_vpp_scl" )
			)
			( signal "SMB_DDR_DEF_VPP_SDA"
				( objectStatus "@baseboard_fab2_lib.baseboard_fab2(sch_1):smb_ddr_def_vpp_sda" )
			)
			( signal "TP_CH_D_DIMM_D0_RFU_0"
				( objectStatus "@baseboard_fab2_lib.baseboard_fab2(sch_1):tp_ch_d_dimm_d0_rfu_0" )
			)
			( signal "TP_CH_D_DIMM_D0_RFU_1"
				( objectStatus "@baseboard_fab2_lib.baseboard_fab2(sch_1):tp_ch_d_dimm_d0_rfu_1" )
			)
			( signal "TP_CH_D_DIMM_D0_RFU_2"
				( objectStatus "@baseboard_fab2_lib.baseboard_fab2(sch_1):tp_ch_d_dimm_d0_rfu_2" )
			)
			( signal "TP_CH_D_DIMM_D1_RFU_0"
				( objectStatus "@baseboard_fab2_lib.baseboard_fab2(sch_1):tp_ch_d_dimm_d1_rfu_0" )
			)
			( signal "TP_CH_D_DIMM_D1_RFU_1"
				( objectStatus "@baseboard_fab2_lib.baseboard_fab2(sch_1):tp_ch_d_dimm_d1_rfu_1" )
			)
			( signal "TP_CH_D_DIMM_D1_RFU_2"
				( objectStatus "@baseboard_fab2_lib.baseboard_fab2(sch_1):tp_ch_d_dimm_d1_rfu_2" )
			)
			( signal "M_E_VREF"
				( objectStatus "@baseboard_fab2_lib.baseboard_fab2(sch_1):m_e_vref" )
			)
			( signal "TP_CH_E_DIMM_E0_RFU_0"
				( objectStatus "@baseboard_fab2_lib.baseboard_fab2(sch_1):tp_ch_e_dimm_e0_rfu_0" )
			)
			( signal "TP_CH_E_DIMM_E0_RFU_1"
				( objectStatus "@baseboard_fab2_lib.baseboard_fab2(sch_1):tp_ch_e_dimm_e0_rfu_1" )
			)
			( signal "TP_CH_E_DIMM_E0_RFU_2"
				( objectStatus "@baseboard_fab2_lib.baseboard_fab2(sch_1):tp_ch_e_dimm_e0_rfu_2" )
			)
			( signal "TP_CH_E_DIMM_E1_RFU_0"
				( objectStatus "@baseboard_fab2_lib.baseboard_fab2(sch_1):tp_ch_e_dimm_e1_rfu_0" )
			)
			( signal "TP_CH_E_DIMM_E1_RFU_1"
				( objectStatus "@baseboard_fab2_lib.baseboard_fab2(sch_1):tp_ch_e_dimm_e1_rfu_1" )
			)
			( signal "TP_CH_E_DIMM_E1_RFU_2"
				( objectStatus "@baseboard_fab2_lib.baseboard_fab2(sch_1):tp_ch_e_dimm_e1_rfu_2" )
			)
			( signal "M_F_VREF"
				( objectStatus "@baseboard_fab2_lib.baseboard_fab2(sch_1):m_f_vref" )
			)
			( signal "TP_CH_F_DIMM_F0_RFU_0"
				( objectStatus "@baseboard_fab2_lib.baseboard_fab2(sch_1):tp_ch_f_dimm_f0_rfu_0" )
			)
			( signal "TP_CH_F_DIMM_F0_RFU_1"
				( objectStatus "@baseboard_fab2_lib.baseboard_fab2(sch_1):tp_ch_f_dimm_f0_rfu_1" )
			)
			( signal "TP_CH_F_DIMM_F0_RFU_2"
				( objectStatus "@baseboard_fab2_lib.baseboard_fab2(sch_1):tp_ch_f_dimm_f0_rfu_2" )
			)
			( signal "TP_CH_F_DIMM_F1_RFU_0"
				( objectStatus "@baseboard_fab2_lib.baseboard_fab2(sch_1):tp_ch_f_dimm_f1_rfu_0" )
			)
			( signal "TP_CH_F_DIMM_F1_RFU_1"
				( objectStatus "@baseboard_fab2_lib.baseboard_fab2(sch_1):tp_ch_f_dimm_f1_rfu_1" )
			)
			( signal "TP_CH_F_DIMM_F1_RFU_2"
				( objectStatus "@baseboard_fab2_lib.baseboard_fab2(sch_1):tp_ch_f_dimm_f1_rfu_2" )
			)
			( signal "A_CPU1_GHJ_RCOMP0"
				( objectStatus "@baseboard_fab2_lib.baseboard_fab2(sch_1):a_cpu1_ghj_rcomp0" )
			)
			( signal "A_CPU1_GHJ_RCOMP1"
				( objectStatus "@baseboard_fab2_lib.baseboard_fab2(sch_1):a_cpu1_ghj_rcomp1" )
			)
			( signal "A_CPU1_GHJ_RCOMP2"
				( objectStatus "@baseboard_fab2_lib.baseboard_fab2(sch_1):a_cpu1_ghj_rcomp2" )
			)
			( signal "A_CPU1_KLM_RCOMP0"
				( objectStatus "@baseboard_fab2_lib.baseboard_fab2(sch_1):a_cpu1_klm_rcomp0" )
			)
			( signal "A_CPU1_KLM_RCOMP1"
				( objectStatus "@baseboard_fab2_lib.baseboard_fab2(sch_1):a_cpu1_klm_rcomp1" )
			)
			( signal "A_CPU1_KLM_RCOMP2"
				( objectStatus "@baseboard_fab2_lib.baseboard_fab2(sch_1):a_cpu1_klm_rcomp2" )
			)
			( signal "A_CPU1_MCP01_RBIAS"
				( objectStatus "@baseboard_fab2_lib.baseboard_fab2(sch_1):a_cpu1_mcp01_rbias" )
			)
			( signal "A_CPU1_PE012_RBIAS"
				( objectStatus "@baseboard_fab2_lib.baseboard_fab2(sch_1):a_cpu1_pe012_rbias" )
			)
			( signal "A_CPU1_PE3_RBIAS"
				( objectStatus "@baseboard_fab2_lib.baseboard_fab2(sch_1):a_cpu1_pe3_rbias" )
			)
			( signal "A_CPU1_UPI01_RBIAS"
				( objectStatus "@baseboard_fab2_lib.baseboard_fab2(sch_1):a_cpu1_upi01_rbias" )
			)
			( signal "A_CPU1_UPI2_RBIAS"
				( objectStatus "@baseboard_fab2_lib.baseboard_fab2(sch_1):a_cpu1_upi2_rbias" )
			)
			( signal "CLK_100M_CPU1_BCLK0_DN"
				( objectStatus "@baseboard_fab2_lib.baseboard_fab2(sch_1):clk_100m_cpu1_bclk0_dn" )
			)
			( signal "CLK_100M_CPU1_BCLK0_DP"
				( objectStatus "@baseboard_fab2_lib.baseboard_fab2(sch_1):clk_100m_cpu1_bclk0_dp" )
			)
			( signal "CLK_100M_CPU1_BCLK1_DN"
				( objectStatus "@baseboard_fab2_lib.baseboard_fab2(sch_1):clk_100m_cpu1_bclk1_dn" )
			)
			( signal "CLK_100M_CPU1_BCLK1_DP"
				( objectStatus "@baseboard_fab2_lib.baseboard_fab2(sch_1):clk_100m_cpu1_bclk1_dp" )
			)
			( signal "CLK_100M_CPU1_BCLK2_DN"
				( objectStatus "@baseboard_fab2_lib.baseboard_fab2(sch_1):clk_100m_cpu1_bclk2_dn" )
			)
			( signal "CLK_100M_CPU1_BCLK2_DP"
				( objectStatus "@baseboard_fab2_lib.baseboard_fab2(sch_1):clk_100m_cpu1_bclk2_dp" )
			)
			( signal "FM_CPU1_PKGID0"
				( objectStatus "@baseboard_fab2_lib.baseboard_fab2(sch_1):fm_cpu1_pkgid0" )
			)
			( signal "FM_CPU1_PKGID1"
				( objectStatus "@baseboard_fab2_lib.baseboard_fab2(sch_1):fm_cpu1_pkgid1" )
			)
			( signal "FM_CPU1_PKGID2"
				( objectStatus "@baseboard_fab2_lib.baseboard_fab2(sch_1):fm_cpu1_pkgid2" )
			)
			( signal "FM_CPU1_PROC_ID0"
				( objectStatus "@baseboard_fab2_lib.baseboard_fab2(sch_1):fm_cpu1_proc_id0" )
			)
			( signal "FM_CPU1_PROC_ID1"
				( objectStatus "@baseboard_fab2_lib.baseboard_fab2(sch_1):fm_cpu1_proc_id1" )
			)
			( signal "FM_CPU1_SKTOCC_LVT3_N"
				( objectStatus "@baseboard_fab2_lib.baseboard_fab2(sch_1):fm_cpu1_sktocc_lvt3_n" )
			)
			( signal "FM_CPU1_SM_WP"
				( objectStatus "@baseboard_fab2_lib.baseboard_fab2(sch_1):fm_cpu1_sm_wp" )
			)
			( signal "H_CPU1_BMCINIT"
				( objectStatus "@baseboard_fab2_lib.baseboard_fab2(sch_1):h_cpu1_bmcinit" )
			)
			( signal "H_CPU1_CATERR_G_N"
				( objectStatus "@baseboard_fab2_lib.baseboard_fab2(sch_1):h_cpu1_caterr_g_n" )
			)
			( signal "H_CPU1_ERR0_G_N"
				( objectStatus "@baseboard_fab2_lib.baseboard_fab2(sch_1):h_cpu1_err0_g_n" )
			)
			( signal "H_CPU1_ERR1_G_N"
				( objectStatus "@baseboard_fab2_lib.baseboard_fab2(sch_1):h_cpu1_err1_g_n" )
			)
			( signal "H_CPU1_ERR2_G_N"
				( objectStatus "@baseboard_fab2_lib.baseboard_fab2(sch_1):h_cpu1_err2_g_n" )
			)
			( signal "H_CPU1_FAST_WAKE_N"
				( objectStatus "@baseboard_fab2_lib.baseboard_fab2(sch_1):h_cpu1_fast_wake_n" )
			)
			( signal "H_CPU1_MEMGHJ_MEMHOT_G_N"
				( objectStatus "@baseboard_fab2_lib.baseboard_fab2(sch_1):h_cpu1_memghj_memhot_g_n" )
			)
			( signal "H_CPU1_MEMKLM_MEMHOT_G_N"
				( objectStatus "@baseboard_fab2_lib.baseboard_fab2(sch_1):h_cpu1_memklm_memhot_g_n" )
			)
			( signal "H_CPU1_MSMI_G_N"
				( objectStatus "@baseboard_fab2_lib.baseboard_fab2(sch_1):h_cpu1_msmi_g_n" )
			)
			( signal "H_CPU1_PROCHOT_G_N"
				( objectStatus "@baseboard_fab2_lib.baseboard_fab2(sch_1):h_cpu1_prochot_g_n" )
			)
			( signal "H_CPU1_THERMTRIP_G_N"
				( objectStatus "@baseboard_fab2_lib.baseboard_fab2(sch_1):h_cpu1_thermtrip_g_n" )
			)
			( signal "H_PM_SYNC_GTL_R2"
				( objectStatus "@baseboard_fab2_lib.baseboard_fab2(sch_1):h_pm_sync_gtl_r2" )
			)
			( signal "H_PMSYNC_CLK_24M_CPU1"
				( objectStatus "@baseboard_fab2_lib.baseboard_fab2(sch_1):h_pmsync_clk_24m_cpu1" )
			)
			( signal "M_G_CPU_VREF"
				( objectStatus "@baseboard_fab2_lib.baseboard_fab2(sch_1):m_g_cpu_vref" )
			)
			( signal "M_GHJ_RST_N"
				( objectStatus "@baseboard_fab2_lib.baseboard_fab2(sch_1):m_ghj_rst_n" )
			)
			( signal "M_H_CPU_VREF"
				( objectStatus "@baseboard_fab2_lib.baseboard_fab2(sch_1):m_h_cpu_vref" )
			)
			( signal "M_J_CPU_VREF"
				( objectStatus "@baseboard_fab2_lib.baseboard_fab2(sch_1):m_j_cpu_vref" )
			)
			( signal "M_K_CPU_VREF"
				( objectStatus "@baseboard_fab2_lib.baseboard_fab2(sch_1):m_k_cpu_vref" )
			)
			( signal "M_KLM_RST_N"
				( objectStatus "@baseboard_fab2_lib.baseboard_fab2(sch_1):m_klm_rst_n" )
			)
			( signal "M_L_CPU_VREF"
				( objectStatus "@baseboard_fab2_lib.baseboard_fab2(sch_1):m_l_cpu_vref" )
			)
			( signal "M_M_CPU_VREF"
				( objectStatus "@baseboard_fab2_lib.baseboard_fab2(sch_1):m_m_cpu_vref" )
			)
			( signal "PD_CPU1_BIST_ENABLE"
				( objectStatus "@baseboard_fab2_lib.baseboard_fab2(sch_1):pd_cpu1_bist_enable" )
			)
			( signal "PD_CPU1_KSFC_DIS"
				( objectStatus "@baseboard_fab2_lib.baseboard_fab2(sch_1):pd_cpu1_ksfc_dis" )
			)
			( signal "PD_CPU1_TEST12"
				( objectStatus "@baseboard_fab2_lib.baseboard_fab2(sch_1):pd_cpu1_test12" )
			)
			( signal "PD_CPU1_TEST13"
				( objectStatus "@baseboard_fab2_lib.baseboard_fab2(sch_1):pd_cpu1_test13" )
			)
			( signal "PD_CPU1_TEST14"
				( objectStatus "@baseboard_fab2_lib.baseboard_fab2(sch_1):pd_cpu1_test14" )
			)
			( signal "PD_CPU1_TXT_PLTEN"
				( objectStatus "@baseboard_fab2_lib.baseboard_fab2(sch_1):pd_cpu1_txt_plten" )
			)
			( signal "PD_PIROM_CPU1_ADDR1"
				( objectStatus "@baseboard_fab2_lib.baseboard_fab2(sch_1):pd_pirom_cpu1_addr1" )
			)
			( signal "PD_PIROM_CPU1_ADDR2"
				( objectStatus "@baseboard_fab2_lib.baseboard_fab2(sch_1):pd_pirom_cpu1_addr2" )
			)
			( signal "PU_CPU1_FRMAGENT"
				( objectStatus "@baseboard_fab2_lib.baseboard_fab2(sch_1):pu_cpu1_frmagent" )
			)
			( signal "PU_CPU1_LEGACY_SKT"
				( objectStatus "@baseboard_fab2_lib.baseboard_fab2(sch_1):pu_cpu1_legacy_skt" )
			)
			( signal "PU_CPU1_SAFE_MODE_BOOT"
				( objectStatus "@baseboard_fab2_lib.baseboard_fab2(sch_1):pu_cpu1_safe_mode_boot" )
			)
			( signal "PU_CPU1_SOCKET_ID_0"
				( objectStatus "@baseboard_fab2_lib.baseboard_fab2(sch_1):pu_cpu1_socket_id_0" )
			)
			( signal "PU_CPU1_SOCKET_ID_1"
				( objectStatus "@baseboard_fab2_lib.baseboard_fab2(sch_1):pu_cpu1_socket_id_1" )
			)
			( signal "PU_CPU1_TSC_SYNC"
				( objectStatus "@baseboard_fab2_lib.baseboard_fab2(sch_1):pu_cpu1_tsc_sync" )
			)
			( signal "PU_CPU1_TXT_AGENT"
				( objectStatus "@baseboard_fab2_lib.baseboard_fab2(sch_1):pu_cpu1_txt_agent" )
			)
			( signal "PU_PIROM_CPU1_ADDR0"
				( objectStatus "@baseboard_fab2_lib.baseboard_fab2(sch_1):pu_pirom_cpu1_addr0" )
			)
			( signal "PVCCIO_CPU1"
				( attribute "VOLTAGE" "1.1V"
					( Units "uVoltage" "V" 1.000000)
					( Status sAliasFlattened )
					( Origin gFrontEnd )
				)
				( objectStatus "@baseboard_fab2_lib.baseboard_fab2(sch_1):pvccio_cpu1" )
			)
			( signal "PWRGD_CPU1_DRAMPWROK_GHJ_G"
				( objectStatus "@baseboard_fab2_lib.baseboard_fab2(sch_1):pwrgd_cpu1_drampwrok_ghj_g" )
			)
			( signal "PWRGD_CPU1_DRAMPWROK_KLM_G"
				( objectStatus "@baseboard_fab2_lib.baseboard_fab2(sch_1):pwrgd_cpu1_drampwrok_klm_g" )
			)
			( signal "PWRGD_CPU1_G"
				( objectStatus "@baseboard_fab2_lib.baseboard_fab2(sch_1):pwrgd_cpu1_g" )
			)
			( signal "RST_CPU1_G_N"
				( objectStatus "@baseboard_fab2_lib.baseboard_fab2(sch_1):rst_cpu1_g_n" )
			)
			( signal "SMB_CPU1_PE_HP_GTL_SCL"
				( objectStatus "@baseboard_fab2_lib.baseboard_fab2(sch_1):smb_cpu1_pe_hp_gtl_scl" )
			)
			( signal "SMB_CPU1_PE_HP_GTL_SDA"
				( objectStatus "@baseboard_fab2_lib.baseboard_fab2(sch_1):smb_cpu1_pe_hp_gtl_sda" )
			)
			( signal "SMB_DDR_GHJ_SCL_G_R"
				( objectStatus "@baseboard_fab2_lib.baseboard_fab2(sch_1):smb_ddr_ghj_scl_g_r" )
			)
			( signal "SMB_DDR_GHJ_SDA_G_R"
				( objectStatus "@baseboard_fab2_lib.baseboard_fab2(sch_1):smb_ddr_ghj_sda_g_r" )
			)
			( signal "SMB_DDR_KLM_SCL_G_R"
				( objectStatus "@baseboard_fab2_lib.baseboard_fab2(sch_1):smb_ddr_klm_scl_g_r" )
			)
			( signal "SMB_DDR_KLM_SDA_G_R"
				( objectStatus "@baseboard_fab2_lib.baseboard_fab2(sch_1):smb_ddr_klm_sda_g_r" )
			)
			( signal "SMB_PIROM_CPU1_SCL"
				( objectStatus "@baseboard_fab2_lib.baseboard_fab2(sch_1):smb_pirom_cpu1_scl" )
			)
			( signal "SMB_PIROM_CPU1_SDA"
				( objectStatus "@baseboard_fab2_lib.baseboard_fab2(sch_1):smb_pirom_cpu1_sda" )
			)
			( signal "SVID_ALERT0_CPU1_N"
				( objectStatus "@baseboard_fab2_lib.baseboard_fab2(sch_1):svid_alert0_cpu1_n" )
			)
			( signal "SVID_ALERT0_CPU1_R_N"
				( objectStatus "@baseboard_fab2_lib.baseboard_fab2(sch_1):svid_alert0_cpu1_r_n" )
			)
			( signal "SVID_ALERT1_CPU1_N"
				( objectStatus "@baseboard_fab2_lib.baseboard_fab2(sch_1):svid_alert1_cpu1_n" )
			)
			( signal "SVID_ALERT1_CPU1_R_N"
				( objectStatus "@baseboard_fab2_lib.baseboard_fab2(sch_1):svid_alert1_cpu1_r_n" )
			)
			( signal "SVID_CLK0_CPU1"
				( objectStatus "@baseboard_fab2_lib.baseboard_fab2(sch_1):svid_clk0_cpu1" )
			)
			( signal "SVID_CLK0_CPU1_R"
				( objectStatus "@baseboard_fab2_lib.baseboard_fab2(sch_1):svid_clk0_cpu1_r" )
			)
			( signal "SVID_CLK1_CPU1"
				( objectStatus "@baseboard_fab2_lib.baseboard_fab2(sch_1):svid_clk1_cpu1" )
			)
			( signal "SVID_CLK1_CPU1_R"
				( objectStatus "@baseboard_fab2_lib.baseboard_fab2(sch_1):svid_clk1_cpu1_r" )
			)
			( signal "SVID_DIO0_CPU1"
				( objectStatus "@baseboard_fab2_lib.baseboard_fab2(sch_1):svid_dio0_cpu1" )
			)
			( signal "SVID_DIO0_CPU1_R"
				( objectStatus "@baseboard_fab2_lib.baseboard_fab2(sch_1):svid_dio0_cpu1_r" )
			)
			( signal "SVID_DIO1_CPU1"
				( objectStatus "@baseboard_fab2_lib.baseboard_fab2(sch_1):svid_dio1_cpu1" )
			)
			( signal "SVID_DIO1_CPU1_R"
				( objectStatus "@baseboard_fab2_lib.baseboard_fab2(sch_1):svid_dio1_cpu1_r" )
			)
			( signal "TP_CPU1_NMI"
				( objectStatus "@baseboard_fab2_lib.baseboard_fab2(sch_1):tp_cpu1_nmi" )
			)
			( signal "TP_CPU1_PROC_DIS_G_N"
				( objectStatus "@baseboard_fab2_lib.baseboard_fab2(sch_1):tp_cpu1_proc_dis_g_n" )
			)
			( signal "TP_CPU1_SOCKET_ID_2"
				( objectStatus "@baseboard_fab2_lib.baseboard_fab2(sch_1):tp_cpu1_socket_id_2" )
			)
			( signal "TP_XDP_CPU1_OBSDATA_B0_MBP2_N"
				( objectStatus "@baseboard_fab2_lib.baseboard_fab2(sch_1):tp_xdp_cpu1_obsdata_b0_mbp2_n" )
			)
			( signal "TP_XDP_CPU1_OBSDATA_B1_MBP3_N"
				( objectStatus "@baseboard_fab2_lib.baseboard_fab2(sch_1):tp_xdp_cpu1_obsdata_b1_mbp3_n" )
			)
			( signal "TP_XDP_CPU1_OBSDATA_B2_MBP4_N"
				( objectStatus "@baseboard_fab2_lib.baseboard_fab2(sch_1):tp_xdp_cpu1_obsdata_b2_mbp4_n" )
			)
			( signal "TP_XDP_CPU1_OBSDATA_B3_MBP5_N"
				( objectStatus "@baseboard_fab2_lib.baseboard_fab2(sch_1):tp_xdp_cpu1_obsdata_b3_mbp5_n" )
			)
			( signal "XDP_CPU1_TDI"
				( objectStatus "@baseboard_fab2_lib.baseboard_fab2(sch_1):xdp_cpu1_tdi" )
			)
			( signal "XDP_CPU1_TDO"
				( objectStatus "@baseboard_fab2_lib.baseboard_fab2(sch_1):xdp_cpu1_tdo" )
			)
			( signal "CLK_100M_CPU1_RC_REFCLK0_DN"
				( objectStatus "@baseboard_fab2_lib.baseboard_fab2(sch_1):clk_100m_cpu1_rc_refclk0_dn" )
			)
			( signal "CLK_100M_CPU1_RC_REFCLK0_DP"
				( objectStatus "@baseboard_fab2_lib.baseboard_fab2(sch_1):clk_100m_cpu1_rc_refclk0_dp" )
			)
			( signal "CLK_322M_OSC_CPU1_RC_DN"
				( objectStatus "@baseboard_fab2_lib.baseboard_fab2(sch_1):clk_322m_osc_cpu1_rc_dn" )
			)
			( signal "CLK_322M_OSC_CPU1_RC_DP"
				( objectStatus "@baseboard_fab2_lib.baseboard_fab2(sch_1):clk_322m_osc_cpu1_rc_dp" )
			)
			( signal "FM_CPU1_RC_ERROR_N"
				( objectStatus "@baseboard_fab2_lib.baseboard_fab2(sch_1):fm_cpu1_rc_error_n" )
			)
			( signal "H_CPU1_FIVR_FAULT_G"
				( objectStatus "@baseboard_fab2_lib.baseboard_fab2(sch_1):h_cpu1_fivr_fault_g" )
			)
			( signal "P1V8_MCP_CPU1"
				( attribute "VOLTAGE" "1.8"
					( Units "uVoltage" "V" 1.000000)
					( Status sAliasFlattened )
					( Origin gFrontEnd )
				)
				( objectStatus "@baseboard_fab2_lib.baseboard_fab2(sch_1):p1v8_mcp_cpu1" )
			)
			( signal "PD_CPU1_DMIMODE_OVERRIDE"
				( objectStatus "@baseboard_fab2_lib.baseboard_fab2(sch_1):pd_cpu1_dmimode_override" )
			)
			( signal "PD_CPU1_RSVD_TEST_1"
				( objectStatus "@baseboard_fab2_lib.baseboard_fab2(sch_1):pd_cpu1_rsvd_test_1" )
			)
			( signal "PD_CPU1_RSVD_TEST_2"
				( objectStatus "@baseboard_fab2_lib.baseboard_fab2(sch_1):pd_cpu1_rsvd_test_2" )
			)
			( signal "PVCCMCP_CPU1"
				( attribute "VOLTAGE" "+0.95"
					( Units "uVoltage" "V" 1.000000)
					( Status sAliasFlattened )
					( Origin gFrontEnd )
				)
				( objectStatus "@baseboard_fab2_lib.baseboard_fab2(sch_1):pvccmcp_cpu1" )
			)
			( signal "TP_CPU1_RSVD_194"
				( objectStatus "@baseboard_fab2_lib.baseboard_fab2(sch_1):tp_cpu1_rsvd_194" )
			)
			( signal "TP_CPU1_RSVD_198"
				( objectStatus "@baseboard_fab2_lib.baseboard_fab2(sch_1):tp_cpu1_rsvd_198" )
			)
			( signal "TP_CPU1_RSVD_199"
				( objectStatus "@baseboard_fab2_lib.baseboard_fab2(sch_1):tp_cpu1_rsvd_199" )
			)
			( signal "TP_CPU1_RSVD_204"
				( objectStatus "@baseboard_fab2_lib.baseboard_fab2(sch_1):tp_cpu1_rsvd_204" )
			)
			( signal "TP_CPU1_RSVD_205"
				( objectStatus "@baseboard_fab2_lib.baseboard_fab2(sch_1):tp_cpu1_rsvd_205" )
			)
			( signal "TP_CPU1_RSVD_208"
				( objectStatus "@baseboard_fab2_lib.baseboard_fab2(sch_1):tp_cpu1_rsvd_208" )
			)
			( signal "TP_CPU1_RSVD_210"
				( objectStatus "@baseboard_fab2_lib.baseboard_fab2(sch_1):tp_cpu1_rsvd_210" )
			)
			( signal "TP_CPU1_RSVD_211"
				( objectStatus "@baseboard_fab2_lib.baseboard_fab2(sch_1):tp_cpu1_rsvd_211" )
			)
			( signal "TP_CPU1_RSVD_212"
				( objectStatus "@baseboard_fab2_lib.baseboard_fab2(sch_1):tp_cpu1_rsvd_212" )
			)
			( signal "TP_CPU1_RSVD_214"
				( objectStatus "@baseboard_fab2_lib.baseboard_fab2(sch_1):tp_cpu1_rsvd_214" )
			)
			( signal "TP_CPU1_RSVD_216"
				( objectStatus "@baseboard_fab2_lib.baseboard_fab2(sch_1):tp_cpu1_rsvd_216" )
			)
			( signal "TP_CPU1_RSVD_217"
				( objectStatus "@baseboard_fab2_lib.baseboard_fab2(sch_1):tp_cpu1_rsvd_217" )
			)
			( signal "TP_CPU1_RSVD_218"
				( objectStatus "@baseboard_fab2_lib.baseboard_fab2(sch_1):tp_cpu1_rsvd_218" )
			)
			( signal "TP_CPU1_RSVD_219"
				( objectStatus "@baseboard_fab2_lib.baseboard_fab2(sch_1):tp_cpu1_rsvd_219" )
			)
			( signal "TP_CPU1_RSVD_222"
				( objectStatus "@baseboard_fab2_lib.baseboard_fab2(sch_1):tp_cpu1_rsvd_222" )
			)
			( signal "TP_CPU1_RSVD_223"
				( objectStatus "@baseboard_fab2_lib.baseboard_fab2(sch_1):tp_cpu1_rsvd_223" )
			)
			( signal "TP_CPU1_RSVD_224"
				( objectStatus "@baseboard_fab2_lib.baseboard_fab2(sch_1):tp_cpu1_rsvd_224" )
			)
			( signal "TP_CPU1_RSVD_225"
				( objectStatus "@baseboard_fab2_lib.baseboard_fab2(sch_1):tp_cpu1_rsvd_225" )
			)
			( signal "TP_CPU1_RSVD_226"
				( objectStatus "@baseboard_fab2_lib.baseboard_fab2(sch_1):tp_cpu1_rsvd_226" )
			)
			( signal "TP_CPU1_RSVD_227"
				( objectStatus "@baseboard_fab2_lib.baseboard_fab2(sch_1):tp_cpu1_rsvd_227" )
			)
			( signal "TP_CPU1_RSVD_228"
				( objectStatus "@baseboard_fab2_lib.baseboard_fab2(sch_1):tp_cpu1_rsvd_228" )
			)
			( signal "TP_CPU1_RSVD_229"
				( objectStatus "@baseboard_fab2_lib.baseboard_fab2(sch_1):tp_cpu1_rsvd_229" )
			)
			( signal "TP_CPU1_RSVD_230"
				( objectStatus "@baseboard_fab2_lib.baseboard_fab2(sch_1):tp_cpu1_rsvd_230" )
			)
			( signal "TP_CPU1_RSVD_231"
				( objectStatus "@baseboard_fab2_lib.baseboard_fab2(sch_1):tp_cpu1_rsvd_231" )
			)
			( signal "TP_CPU1_RSVD_232"
				( objectStatus "@baseboard_fab2_lib.baseboard_fab2(sch_1):tp_cpu1_rsvd_232" )
			)
			( signal "TP_CPU1_RSVD_233"
				( objectStatus "@baseboard_fab2_lib.baseboard_fab2(sch_1):tp_cpu1_rsvd_233" )
			)
			( signal "TP_CPU1_RSVD_234"
				( objectStatus "@baseboard_fab2_lib.baseboard_fab2(sch_1):tp_cpu1_rsvd_234" )
			)
			( signal "TP_CPU1_RSVD_235"
				( objectStatus "@baseboard_fab2_lib.baseboard_fab2(sch_1):tp_cpu1_rsvd_235" )
			)
			( signal "TP_CPU1_RSVD_236"
				( objectStatus "@baseboard_fab2_lib.baseboard_fab2(sch_1):tp_cpu1_rsvd_236" )
			)
			( signal "TP_CPU1_RSVD_237"
				( objectStatus "@baseboard_fab2_lib.baseboard_fab2(sch_1):tp_cpu1_rsvd_237" )
			)
			( signal "TP_CPU1_RSVD_238"
				( objectStatus "@baseboard_fab2_lib.baseboard_fab2(sch_1):tp_cpu1_rsvd_238" )
			)
			( signal "TP_CPU1_RSVD_239"
				( objectStatus "@baseboard_fab2_lib.baseboard_fab2(sch_1):tp_cpu1_rsvd_239" )
			)
			( signal "TP_CPU1_RSVD_240"
				( objectStatus "@baseboard_fab2_lib.baseboard_fab2(sch_1):tp_cpu1_rsvd_240" )
			)
			( signal "TP_CPU1_RSVD_241"
				( objectStatus "@baseboard_fab2_lib.baseboard_fab2(sch_1):tp_cpu1_rsvd_241" )
			)
			( signal "TP_CPU1_RSVD_242"
				( objectStatus "@baseboard_fab2_lib.baseboard_fab2(sch_1):tp_cpu1_rsvd_242" )
			)
			( signal "TP_CPU1_RSVD_243"
				( objectStatus "@baseboard_fab2_lib.baseboard_fab2(sch_1):tp_cpu1_rsvd_243" )
			)
			( signal "TP_CPU1_RSVD_244"
				( objectStatus "@baseboard_fab2_lib.baseboard_fab2(sch_1):tp_cpu1_rsvd_244" )
			)
			( signal "TP_CPU1_RSVD_245"
				( objectStatus "@baseboard_fab2_lib.baseboard_fab2(sch_1):tp_cpu1_rsvd_245" )
			)
			( signal "TP_CPU1_RSVD_246"
				( objectStatus "@baseboard_fab2_lib.baseboard_fab2(sch_1):tp_cpu1_rsvd_246" )
			)
			( signal "TP_CPU1_RSVD_247"
				( objectStatus "@baseboard_fab2_lib.baseboard_fab2(sch_1):tp_cpu1_rsvd_247" )
			)
			( signal "TP_CPU1_RSVD_248"
				( objectStatus "@baseboard_fab2_lib.baseboard_fab2(sch_1):tp_cpu1_rsvd_248" )
			)
			( signal "TP_CPU1_RSVD_249"
				( objectStatus "@baseboard_fab2_lib.baseboard_fab2(sch_1):tp_cpu1_rsvd_249" )
			)
			( signal "TP_CPU1_RSVD_250"
				( objectStatus "@baseboard_fab2_lib.baseboard_fab2(sch_1):tp_cpu1_rsvd_250" )
			)
			( signal "TP_CPU1_RSVD_251"
				( objectStatus "@baseboard_fab2_lib.baseboard_fab2(sch_1):tp_cpu1_rsvd_251" )
			)
			( signal "TP_CPU1_RSVD_252"
				( objectStatus "@baseboard_fab2_lib.baseboard_fab2(sch_1):tp_cpu1_rsvd_252" )
			)
			( signal "TP_CPU1_RSVD_253"
				( objectStatus "@baseboard_fab2_lib.baseboard_fab2(sch_1):tp_cpu1_rsvd_253" )
			)
			( signal "TP_CPU1_RSVD_254"
				( objectStatus "@baseboard_fab2_lib.baseboard_fab2(sch_1):tp_cpu1_rsvd_254" )
			)
			( signal "TP_CPU1_RSVD_256"
				( objectStatus "@baseboard_fab2_lib.baseboard_fab2(sch_1):tp_cpu1_rsvd_256" )
			)
			( signal "TP_CPU1_RSVD_258"
				( objectStatus "@baseboard_fab2_lib.baseboard_fab2(sch_1):tp_cpu1_rsvd_258" )
			)
			( signal "TP_CPU1_RSVD_259"
				( objectStatus "@baseboard_fab2_lib.baseboard_fab2(sch_1):tp_cpu1_rsvd_259" )
			)
			( signal "TP_CPU1_RSVD_260"
				( objectStatus "@baseboard_fab2_lib.baseboard_fab2(sch_1):tp_cpu1_rsvd_260" )
			)
			( signal "TP_CPU1_RSVD_261"
				( objectStatus "@baseboard_fab2_lib.baseboard_fab2(sch_1):tp_cpu1_rsvd_261" )
			)
			( signal "TP_CPU1_RSVD_262"
				( objectStatus "@baseboard_fab2_lib.baseboard_fab2(sch_1):tp_cpu1_rsvd_262" )
			)
			( signal "TP_CPU1_RSVD_263"
				( objectStatus "@baseboard_fab2_lib.baseboard_fab2(sch_1):tp_cpu1_rsvd_263" )
			)
			( signal "TP_CPU1_RSVD_264"
				( objectStatus "@baseboard_fab2_lib.baseboard_fab2(sch_1):tp_cpu1_rsvd_264" )
			)
			( signal "TP_CPU1_RSVD_265"
				( objectStatus "@baseboard_fab2_lib.baseboard_fab2(sch_1):tp_cpu1_rsvd_265" )
			)
			( signal "TP_CPU1_RSVD_266"
				( objectStatus "@baseboard_fab2_lib.baseboard_fab2(sch_1):tp_cpu1_rsvd_266" )
			)
			( signal "TP_CPU1_RSVD_267"
				( objectStatus "@baseboard_fab2_lib.baseboard_fab2(sch_1):tp_cpu1_rsvd_267" )
			)
			( signal "TP_CPU1_RSVD_268"
				( objectStatus "@baseboard_fab2_lib.baseboard_fab2(sch_1):tp_cpu1_rsvd_268" )
			)
			( signal "TP_CPU1_RSVD_269"
				( objectStatus "@baseboard_fab2_lib.baseboard_fab2(sch_1):tp_cpu1_rsvd_269" )
			)
			( signal "TP_CPU1_RSVD_270"
				( objectStatus "@baseboard_fab2_lib.baseboard_fab2(sch_1):tp_cpu1_rsvd_270" )
			)
			( signal "TP_CPU1_RSVD_271"
				( objectStatus "@baseboard_fab2_lib.baseboard_fab2(sch_1):tp_cpu1_rsvd_271" )
			)
			( signal "TP_CPU1_RSVD_272"
				( objectStatus "@baseboard_fab2_lib.baseboard_fab2(sch_1):tp_cpu1_rsvd_272" )
			)
			( signal "TP_CPU1_RSVD_273"
				( objectStatus "@baseboard_fab2_lib.baseboard_fab2(sch_1):tp_cpu1_rsvd_273" )
			)
			( signal "TP_CPU1_RSVD_274"
				( objectStatus "@baseboard_fab2_lib.baseboard_fab2(sch_1):tp_cpu1_rsvd_274" )
			)
			( signal "TP_CPU1_RSVD_275"
				( objectStatus "@baseboard_fab2_lib.baseboard_fab2(sch_1):tp_cpu1_rsvd_275" )
			)
			( signal "TP_CPU1_RSVD_276"
				( objectStatus "@baseboard_fab2_lib.baseboard_fab2(sch_1):tp_cpu1_rsvd_276" )
			)
			( signal "TP_CPU1_RSVD_277"
				( objectStatus "@baseboard_fab2_lib.baseboard_fab2(sch_1):tp_cpu1_rsvd_277" )
			)
			( signal "TP_CPU1_RSVD_278"
				( objectStatus "@baseboard_fab2_lib.baseboard_fab2(sch_1):tp_cpu1_rsvd_278" )
			)
			( signal "TP_CPU1_RSVD_279"
				( objectStatus "@baseboard_fab2_lib.baseboard_fab2(sch_1):tp_cpu1_rsvd_279" )
			)
			( signal "TP_CPU1_RSVD_280"
				( objectStatus "@baseboard_fab2_lib.baseboard_fab2(sch_1):tp_cpu1_rsvd_280" )
			)
			( signal "TP_CPU1_RSVD_281"
				( objectStatus "@baseboard_fab2_lib.baseboard_fab2(sch_1):tp_cpu1_rsvd_281" )
			)
			( signal "TP_CPU1_RSVD_282"
				( objectStatus "@baseboard_fab2_lib.baseboard_fab2(sch_1):tp_cpu1_rsvd_282" )
			)
			( signal "TP_CPU1_RSVD_283"
				( objectStatus "@baseboard_fab2_lib.baseboard_fab2(sch_1):tp_cpu1_rsvd_283" )
			)
			( signal "TP_CPU1_RSVD_284"
				( objectStatus "@baseboard_fab2_lib.baseboard_fab2(sch_1):tp_cpu1_rsvd_284" )
			)
			( signal "TP_CPU1_RSVD_285"
				( objectStatus "@baseboard_fab2_lib.baseboard_fab2(sch_1):tp_cpu1_rsvd_285" )
			)
			( signal "TP_CPU1_RSVD_286"
				( objectStatus "@baseboard_fab2_lib.baseboard_fab2(sch_1):tp_cpu1_rsvd_286" )
			)
			( signal "TP_CPU1_RSVD_287"
				( objectStatus "@baseboard_fab2_lib.baseboard_fab2(sch_1):tp_cpu1_rsvd_287" )
			)
			( signal "TP_CPU1_RSVD_288"
				( objectStatus "@baseboard_fab2_lib.baseboard_fab2(sch_1):tp_cpu1_rsvd_288" )
			)
			( signal "TP_CPU1_RSVD_289"
				( objectStatus "@baseboard_fab2_lib.baseboard_fab2(sch_1):tp_cpu1_rsvd_289" )
			)
			( signal "TP_CPU1_RSVD_290"
				( objectStatus "@baseboard_fab2_lib.baseboard_fab2(sch_1):tp_cpu1_rsvd_290" )
			)
			( signal "TP_CPU1_RSVD_291"
				( objectStatus "@baseboard_fab2_lib.baseboard_fab2(sch_1):tp_cpu1_rsvd_291" )
			)
			( signal "TP_CPU1_RSVD_292"
				( objectStatus "@baseboard_fab2_lib.baseboard_fab2(sch_1):tp_cpu1_rsvd_292" )
			)
			( signal "TP_CPU1_RSVD_293"
				( objectStatus "@baseboard_fab2_lib.baseboard_fab2(sch_1):tp_cpu1_rsvd_293" )
			)
			( signal "TP_CPU1_RSVD_298"
				( objectStatus "@baseboard_fab2_lib.baseboard_fab2(sch_1):tp_cpu1_rsvd_298" )
			)
			( signal "TP_CPU1_RSVD_299"
				( objectStatus "@baseboard_fab2_lib.baseboard_fab2(sch_1):tp_cpu1_rsvd_299" )
			)
			( signal "TP_CPU1_RSVD_300"
				( objectStatus "@baseboard_fab2_lib.baseboard_fab2(sch_1):tp_cpu1_rsvd_300" )
			)
			( signal "TP_CPU1_RSVD_303"
				( objectStatus "@baseboard_fab2_lib.baseboard_fab2(sch_1):tp_cpu1_rsvd_303" )
			)
			( signal "TP_CPU1_RSVD_304"
				( objectStatus "@baseboard_fab2_lib.baseboard_fab2(sch_1):tp_cpu1_rsvd_304" )
			)
			( signal "TP_CPU1_RSVD_TEST_11"
				( objectStatus "@baseboard_fab2_lib.baseboard_fab2(sch_1):tp_cpu1_rsvd_test_11" )
			)
			( signal "TP_CPU1_RSVD_TEST_3"
				( objectStatus "@baseboard_fab2_lib.baseboard_fab2(sch_1):tp_cpu1_rsvd_test_3" )
			)
			( signal "TP_CPU1_RSVD_TEST_4"
				( objectStatus "@baseboard_fab2_lib.baseboard_fab2(sch_1):tp_cpu1_rsvd_test_4" )
			)
			( signal "TP_CPU1_RSVD_TEST_5"
				( objectStatus "@baseboard_fab2_lib.baseboard_fab2(sch_1):tp_cpu1_rsvd_test_5" )
			)
			( signal "VSENSE_P1V8MCP_CPU1_SKT_VRTN"
				( objectStatus "@baseboard_fab2_lib.baseboard_fab2(sch_1):vsense_p1v8mcp_cpu1_skt_vrtn" )
			)
			( signal "VSENSE_P1V8MCP_CPU1_SKT_VSEN"
				( objectStatus "@baseboard_fab2_lib.baseboard_fab2(sch_1):vsense_p1v8mcp_cpu1_skt_vsen" )
			)
			( signal "M_G_ACT_N"
				( objectStatus "@baseboard_fab2_lib.baseboard_fab2(sch_1):m_g_act_n" )
			)
			( signal "M_G_ALERT_N"
				( objectStatus "@baseboard_fab2_lib.baseboard_fab2(sch_1):m_g_alert_n" )
			)
			( signal "M_G_BA<0>"
				( objectStatus "@baseboard_fab2_lib.baseboard_fab2(sch_1):m_g_ba(0)" )
			)
			( signal "M_G_BA<1>"
				( objectStatus "@baseboard_fab2_lib.baseboard_fab2(sch_1):m_g_ba(1)" )
			)
			( signal "M_G_BG<0>"
				( objectStatus "@baseboard_fab2_lib.baseboard_fab2(sch_1):m_g_bg(0)" )
			)
			( signal "M_G_BG<1>"
				( objectStatus "@baseboard_fab2_lib.baseboard_fab2(sch_1):m_g_bg(1)" )
			)
			( signal "M_G_C<2>"
				( objectStatus "@baseboard_fab2_lib.baseboard_fab2(sch_1):m_g_c(2)" )
			)
			( signal "M_G_CKE<0>"
				( objectStatus "@baseboard_fab2_lib.baseboard_fab2(sch_1):m_g_cke(0)" )
			)
			( signal "M_G_CKE<1>"
				( objectStatus "@baseboard_fab2_lib.baseboard_fab2(sch_1):m_g_cke(1)" )
			)
			( signal "M_G_CKE<2>"
				( objectStatus "@baseboard_fab2_lib.baseboard_fab2(sch_1):m_g_cke(2)" )
			)
			( signal "M_G_CKE<3>"
				( objectStatus "@baseboard_fab2_lib.baseboard_fab2(sch_1):m_g_cke(3)" )
			)
			( signal "M_G_CLK_DN<0>"
				( objectStatus "@baseboard_fab2_lib.baseboard_fab2(sch_1):m_g_clk_dn(0)" )
			)
			( signal "M_G_CLK_DN<1>"
				( objectStatus "@baseboard_fab2_lib.baseboard_fab2(sch_1):m_g_clk_dn(1)" )
			)
			( signal "M_G_CLK_DN<2>"
				( objectStatus "@baseboard_fab2_lib.baseboard_fab2(sch_1):m_g_clk_dn(2)" )
			)
			( signal "M_G_CLK_DN<3>"
				( objectStatus "@baseboard_fab2_lib.baseboard_fab2(sch_1):m_g_clk_dn(3)" )
			)
			( signal "M_G_CLK_DP<0>"
				( objectStatus "@baseboard_fab2_lib.baseboard_fab2(sch_1):m_g_clk_dp(0)" )
			)
			( signal "M_G_CLK_DP<1>"
				( objectStatus "@baseboard_fab2_lib.baseboard_fab2(sch_1):m_g_clk_dp(1)" )
			)
			( signal "M_G_CLK_DP<2>"
				( objectStatus "@baseboard_fab2_lib.baseboard_fab2(sch_1):m_g_clk_dp(2)" )
			)
			( signal "M_G_CLK_DP<3>"
				( objectStatus "@baseboard_fab2_lib.baseboard_fab2(sch_1):m_g_clk_dp(3)" )
			)
			( signal "M_G_CS_N<0>"
				( objectStatus "@baseboard_fab2_lib.baseboard_fab2(sch_1):m_g_cs_n(0)" )
			)
			( signal "M_G_CS_N<1>"
				( objectStatus "@baseboard_fab2_lib.baseboard_fab2(sch_1):m_g_cs_n(1)" )
			)
			( signal "M_G_CS_N<2>"
				( objectStatus "@baseboard_fab2_lib.baseboard_fab2(sch_1):m_g_cs_n(2)" )
			)
			( signal "M_G_CS_N<3>"
				( objectStatus "@baseboard_fab2_lib.baseboard_fab2(sch_1):m_g_cs_n(3)" )
			)
			( signal "M_G_CS_N<4>"
				( objectStatus "@baseboard_fab2_lib.baseboard_fab2(sch_1):m_g_cs_n(4)" )
			)
			( signal "M_G_CS_N<5>"
				( objectStatus "@baseboard_fab2_lib.baseboard_fab2(sch_1):m_g_cs_n(5)" )
			)
			( signal "M_G_CS_N<6>"
				( objectStatus "@baseboard_fab2_lib.baseboard_fab2(sch_1):m_g_cs_n(6)" )
			)
			( signal "M_G_CS_N<7>"
				( objectStatus "@baseboard_fab2_lib.baseboard_fab2(sch_1):m_g_cs_n(7)" )
			)
			( signal "M_G_DQ<0>"
				( objectStatus "@baseboard_fab2_lib.baseboard_fab2(sch_1):m_g_dq(0)" )
			)
			( signal "M_G_DQ<1>"
				( objectStatus "@baseboard_fab2_lib.baseboard_fab2(sch_1):m_g_dq(1)" )
			)
			( signal "M_G_DQ<2>"
				( objectStatus "@baseboard_fab2_lib.baseboard_fab2(sch_1):m_g_dq(2)" )
			)
			( signal "M_G_DQ<3>"
				( objectStatus "@baseboard_fab2_lib.baseboard_fab2(sch_1):m_g_dq(3)" )
			)
			( signal "M_G_DQ<4>"
				( objectStatus "@baseboard_fab2_lib.baseboard_fab2(sch_1):m_g_dq(4)" )
			)
			( signal "M_G_DQ<5>"
				( objectStatus "@baseboard_fab2_lib.baseboard_fab2(sch_1):m_g_dq(5)" )
			)
			( signal "M_G_DQ<6>"
				( objectStatus "@baseboard_fab2_lib.baseboard_fab2(sch_1):m_g_dq(6)" )
			)
			( signal "M_G_DQ<7>"
				( objectStatus "@baseboard_fab2_lib.baseboard_fab2(sch_1):m_g_dq(7)" )
			)
			( signal "M_G_DQ<8>"
				( objectStatus "@baseboard_fab2_lib.baseboard_fab2(sch_1):m_g_dq(8)" )
			)
			( signal "M_G_DQ<9>"
				( objectStatus "@baseboard_fab2_lib.baseboard_fab2(sch_1):m_g_dq(9)" )
			)
			( signal "M_G_DQ<10>"
				( objectStatus "@baseboard_fab2_lib.baseboard_fab2(sch_1):m_g_dq(10)" )
			)
			( signal "M_G_DQ<11>"
				( objectStatus "@baseboard_fab2_lib.baseboard_fab2(sch_1):m_g_dq(11)" )
			)
			( signal "M_G_DQ<12>"
				( objectStatus "@baseboard_fab2_lib.baseboard_fab2(sch_1):m_g_dq(12)" )
			)
			( signal "M_G_DQ<13>"
				( objectStatus "@baseboard_fab2_lib.baseboard_fab2(sch_1):m_g_dq(13)" )
			)
			( signal "M_G_DQ<14>"
				( objectStatus "@baseboard_fab2_lib.baseboard_fab2(sch_1):m_g_dq(14)" )
			)
			( signal "M_G_DQ<15>"
				( objectStatus "@baseboard_fab2_lib.baseboard_fab2(sch_1):m_g_dq(15)" )
			)
			( signal "M_G_DQ<16>"
				( objectStatus "@baseboard_fab2_lib.baseboard_fab2(sch_1):m_g_dq(16)" )
			)
			( signal "M_G_DQ<17>"
				( objectStatus "@baseboard_fab2_lib.baseboard_fab2(sch_1):m_g_dq(17)" )
			)
			( signal "M_G_DQ<18>"
				( objectStatus "@baseboard_fab2_lib.baseboard_fab2(sch_1):m_g_dq(18)" )
			)
			( signal "M_G_DQ<19>"
				( objectStatus "@baseboard_fab2_lib.baseboard_fab2(sch_1):m_g_dq(19)" )
			)
			( signal "M_G_DQ<20>"
				( objectStatus "@baseboard_fab2_lib.baseboard_fab2(sch_1):m_g_dq(20)" )
			)
			( signal "M_G_DQ<21>"
				( objectStatus "@baseboard_fab2_lib.baseboard_fab2(sch_1):m_g_dq(21)" )
			)
			( signal "M_G_DQ<22>"
				( objectStatus "@baseboard_fab2_lib.baseboard_fab2(sch_1):m_g_dq(22)" )
			)
			( signal "M_G_DQ<23>"
				( objectStatus "@baseboard_fab2_lib.baseboard_fab2(sch_1):m_g_dq(23)" )
			)
			( signal "M_G_DQ<24>"
				( objectStatus "@baseboard_fab2_lib.baseboard_fab2(sch_1):m_g_dq(24)" )
			)
			( signal "M_G_DQ<25>"
				( objectStatus "@baseboard_fab2_lib.baseboard_fab2(sch_1):m_g_dq(25)" )
			)
			( signal "M_G_DQ<26>"
				( objectStatus "@baseboard_fab2_lib.baseboard_fab2(sch_1):m_g_dq(26)" )
			)
			( signal "M_G_DQ<27>"
				( objectStatus "@baseboard_fab2_lib.baseboard_fab2(sch_1):m_g_dq(27)" )
			)
			( signal "M_G_DQ<28>"
				( objectStatus "@baseboard_fab2_lib.baseboard_fab2(sch_1):m_g_dq(28)" )
			)
			( signal "M_G_DQ<29>"
				( objectStatus "@baseboard_fab2_lib.baseboard_fab2(sch_1):m_g_dq(29)" )
			)
			( signal "M_G_DQ<30>"
				( objectStatus "@baseboard_fab2_lib.baseboard_fab2(sch_1):m_g_dq(30)" )
			)
			( signal "M_G_DQ<31>"
				( objectStatus "@baseboard_fab2_lib.baseboard_fab2(sch_1):m_g_dq(31)" )
			)
			( signal "M_G_DQ<32>"
				( objectStatus "@baseboard_fab2_lib.baseboard_fab2(sch_1):m_g_dq(32)" )
			)
			( signal "M_G_DQ<33>"
				( objectStatus "@baseboard_fab2_lib.baseboard_fab2(sch_1):m_g_dq(33)" )
			)
			( signal "M_G_DQ<34>"
				( objectStatus "@baseboard_fab2_lib.baseboard_fab2(sch_1):m_g_dq(34)" )
			)
			( signal "M_G_DQ<35>"
				( objectStatus "@baseboard_fab2_lib.baseboard_fab2(sch_1):m_g_dq(35)" )
			)
			( signal "M_G_DQ<36>"
				( objectStatus "@baseboard_fab2_lib.baseboard_fab2(sch_1):m_g_dq(36)" )
			)
			( signal "M_G_DQ<37>"
				( objectStatus "@baseboard_fab2_lib.baseboard_fab2(sch_1):m_g_dq(37)" )
			)
			( signal "M_G_DQ<38>"
				( objectStatus "@baseboard_fab2_lib.baseboard_fab2(sch_1):m_g_dq(38)" )
			)
			( signal "M_G_DQ<39>"
				( objectStatus "@baseboard_fab2_lib.baseboard_fab2(sch_1):m_g_dq(39)" )
			)
			( signal "M_G_DQ<40>"
				( objectStatus "@baseboard_fab2_lib.baseboard_fab2(sch_1):m_g_dq(40)" )
			)
			( signal "M_G_DQ<41>"
				( objectStatus "@baseboard_fab2_lib.baseboard_fab2(sch_1):m_g_dq(41)" )
			)
			( signal "M_G_DQ<42>"
				( objectStatus "@baseboard_fab2_lib.baseboard_fab2(sch_1):m_g_dq(42)" )
			)
			( signal "M_G_DQ<43>"
				( objectStatus "@baseboard_fab2_lib.baseboard_fab2(sch_1):m_g_dq(43)" )
			)
			( signal "M_G_DQ<44>"
				( objectStatus "@baseboard_fab2_lib.baseboard_fab2(sch_1):m_g_dq(44)" )
			)
			( signal "M_G_DQ<45>"
				( objectStatus "@baseboard_fab2_lib.baseboard_fab2(sch_1):m_g_dq(45)" )
			)
			( signal "M_G_DQ<46>"
				( objectStatus "@baseboard_fab2_lib.baseboard_fab2(sch_1):m_g_dq(46)" )
			)
			( signal "M_G_DQ<47>"
				( objectStatus "@baseboard_fab2_lib.baseboard_fab2(sch_1):m_g_dq(47)" )
			)
			( signal "M_G_DQ<48>"
				( objectStatus "@baseboard_fab2_lib.baseboard_fab2(sch_1):m_g_dq(48)" )
			)
			( signal "M_G_DQ<49>"
				( objectStatus "@baseboard_fab2_lib.baseboard_fab2(sch_1):m_g_dq(49)" )
			)
			( signal "M_G_DQ<50>"
				( objectStatus "@baseboard_fab2_lib.baseboard_fab2(sch_1):m_g_dq(50)" )
			)
			( signal "M_G_DQ<51>"
				( objectStatus "@baseboard_fab2_lib.baseboard_fab2(sch_1):m_g_dq(51)" )
			)
			( signal "M_G_DQ<52>"
				( objectStatus "@baseboard_fab2_lib.baseboard_fab2(sch_1):m_g_dq(52)" )
			)
			( signal "M_G_DQ<53>"
				( objectStatus "@baseboard_fab2_lib.baseboard_fab2(sch_1):m_g_dq(53)" )
			)
			( signal "M_G_DQ<54>"
				( objectStatus "@baseboard_fab2_lib.baseboard_fab2(sch_1):m_g_dq(54)" )
			)
			( signal "M_G_DQ<55>"
				( objectStatus "@baseboard_fab2_lib.baseboard_fab2(sch_1):m_g_dq(55)" )
			)
			( signal "M_G_DQ<56>"
				( objectStatus "@baseboard_fab2_lib.baseboard_fab2(sch_1):m_g_dq(56)" )
			)
			( signal "M_G_DQ<57>"
				( objectStatus "@baseboard_fab2_lib.baseboard_fab2(sch_1):m_g_dq(57)" )
			)
			( signal "M_G_DQ<58>"
				( objectStatus "@baseboard_fab2_lib.baseboard_fab2(sch_1):m_g_dq(58)" )
			)
			( signal "M_G_DQ<59>"
				( objectStatus "@baseboard_fab2_lib.baseboard_fab2(sch_1):m_g_dq(59)" )
			)
			( signal "M_G_DQ<60>"
				( objectStatus "@baseboard_fab2_lib.baseboard_fab2(sch_1):m_g_dq(60)" )
			)
			( signal "M_G_DQ<61>"
				( objectStatus "@baseboard_fab2_lib.baseboard_fab2(sch_1):m_g_dq(61)" )
			)
			( signal "M_G_DQ<62>"
				( objectStatus "@baseboard_fab2_lib.baseboard_fab2(sch_1):m_g_dq(62)" )
			)
			( signal "M_G_DQ<63>"
				( objectStatus "@baseboard_fab2_lib.baseboard_fab2(sch_1):m_g_dq(63)" )
			)
			( signal "M_G_DQS_DN<0>"
				( objectStatus "@baseboard_fab2_lib.baseboard_fab2(sch_1):m_g_dqs_dn(0)" )
			)
			( signal "M_G_DQS_DN<1>"
				( objectStatus "@baseboard_fab2_lib.baseboard_fab2(sch_1):m_g_dqs_dn(1)" )
			)
			( signal "M_G_DQS_DN<2>"
				( objectStatus "@baseboard_fab2_lib.baseboard_fab2(sch_1):m_g_dqs_dn(2)" )
			)
			( signal "M_G_DQS_DN<3>"
				( objectStatus "@baseboard_fab2_lib.baseboard_fab2(sch_1):m_g_dqs_dn(3)" )
			)
			( signal "M_G_DQS_DN<4>"
				( objectStatus "@baseboard_fab2_lib.baseboard_fab2(sch_1):m_g_dqs_dn(4)" )
			)
			( signal "M_G_DQS_DN<5>"
				( objectStatus "@baseboard_fab2_lib.baseboard_fab2(sch_1):m_g_dqs_dn(5)" )
			)
			( signal "M_G_DQS_DN<6>"
				( objectStatus "@baseboard_fab2_lib.baseboard_fab2(sch_1):m_g_dqs_dn(6)" )
			)
			( signal "M_G_DQS_DN<7>"
				( objectStatus "@baseboard_fab2_lib.baseboard_fab2(sch_1):m_g_dqs_dn(7)" )
			)
			( signal "M_G_DQS_DN<8>"
				( objectStatus "@baseboard_fab2_lib.baseboard_fab2(sch_1):m_g_dqs_dn(8)" )
			)
			( signal "M_G_DQS_DN<9>"
				( objectStatus "@baseboard_fab2_lib.baseboard_fab2(sch_1):m_g_dqs_dn(9)" )
			)
			( signal "M_G_DQS_DN<10>"
				( objectStatus "@baseboard_fab2_lib.baseboard_fab2(sch_1):m_g_dqs_dn(10)" )
			)
			( signal "M_G_DQS_DN<11>"
				( objectStatus "@baseboard_fab2_lib.baseboard_fab2(sch_1):m_g_dqs_dn(11)" )
			)
			( signal "M_G_DQS_DN<12>"
				( objectStatus "@baseboard_fab2_lib.baseboard_fab2(sch_1):m_g_dqs_dn(12)" )
			)
			( signal "M_G_DQS_DN<13>"
				( objectStatus "@baseboard_fab2_lib.baseboard_fab2(sch_1):m_g_dqs_dn(13)" )
			)
			( signal "M_G_DQS_DN<14>"
				( objectStatus "@baseboard_fab2_lib.baseboard_fab2(sch_1):m_g_dqs_dn(14)" )
			)
			( signal "M_G_DQS_DN<15>"
				( objectStatus "@baseboard_fab2_lib.baseboard_fab2(sch_1):m_g_dqs_dn(15)" )
			)
			( signal "M_G_DQS_DN<16>"
				( objectStatus "@baseboard_fab2_lib.baseboard_fab2(sch_1):m_g_dqs_dn(16)" )
			)
			( signal "M_G_DQS_DN<17>"
				( objectStatus "@baseboard_fab2_lib.baseboard_fab2(sch_1):m_g_dqs_dn(17)" )
			)
			( signal "M_G_DQS_DP<0>"
				( objectStatus "@baseboard_fab2_lib.baseboard_fab2(sch_1):m_g_dqs_dp(0)" )
			)
			( signal "M_G_DQS_DP<1>"
				( objectStatus "@baseboard_fab2_lib.baseboard_fab2(sch_1):m_g_dqs_dp(1)" )
			)
			( signal "M_G_DQS_DP<2>"
				( objectStatus "@baseboard_fab2_lib.baseboard_fab2(sch_1):m_g_dqs_dp(2)" )
			)
			( signal "M_G_DQS_DP<3>"
				( objectStatus "@baseboard_fab2_lib.baseboard_fab2(sch_1):m_g_dqs_dp(3)" )
			)
			( signal "M_G_DQS_DP<4>"
				( objectStatus "@baseboard_fab2_lib.baseboard_fab2(sch_1):m_g_dqs_dp(4)" )
			)
			( signal "M_G_DQS_DP<5>"
				( objectStatus "@baseboard_fab2_lib.baseboard_fab2(sch_1):m_g_dqs_dp(5)" )
			)
			( signal "M_G_DQS_DP<6>"
				( objectStatus "@baseboard_fab2_lib.baseboard_fab2(sch_1):m_g_dqs_dp(6)" )
			)
			( signal "M_G_DQS_DP<7>"
				( objectStatus "@baseboard_fab2_lib.baseboard_fab2(sch_1):m_g_dqs_dp(7)" )
			)
			( signal "M_G_DQS_DP<8>"
				( objectStatus "@baseboard_fab2_lib.baseboard_fab2(sch_1):m_g_dqs_dp(8)" )
			)
			( signal "M_G_DQS_DP<9>"
				( objectStatus "@baseboard_fab2_lib.baseboard_fab2(sch_1):m_g_dqs_dp(9)" )
			)
			( signal "M_G_DQS_DP<10>"
				( objectStatus "@baseboard_fab2_lib.baseboard_fab2(sch_1):m_g_dqs_dp(10)" )
			)
			( signal "M_G_DQS_DP<11>"
				( objectStatus "@baseboard_fab2_lib.baseboard_fab2(sch_1):m_g_dqs_dp(11)" )
			)
			( signal "M_G_DQS_DP<12>"
				( objectStatus "@baseboard_fab2_lib.baseboard_fab2(sch_1):m_g_dqs_dp(12)" )
			)
			( signal "M_G_DQS_DP<13>"
				( objectStatus "@baseboard_fab2_lib.baseboard_fab2(sch_1):m_g_dqs_dp(13)" )
			)
			( signal "M_G_DQS_DP<14>"
				( objectStatus "@baseboard_fab2_lib.baseboard_fab2(sch_1):m_g_dqs_dp(14)" )
			)
			( signal "M_G_DQS_DP<15>"
				( objectStatus "@baseboard_fab2_lib.baseboard_fab2(sch_1):m_g_dqs_dp(15)" )
			)
			( signal "M_G_DQS_DP<16>"
				( objectStatus "@baseboard_fab2_lib.baseboard_fab2(sch_1):m_g_dqs_dp(16)" )
			)
			( signal "M_G_DQS_DP<17>"
				( objectStatus "@baseboard_fab2_lib.baseboard_fab2(sch_1):m_g_dqs_dp(17)" )
			)
			( signal "M_G_ECC<0>"
				( objectStatus "@baseboard_fab2_lib.baseboard_fab2(sch_1):m_g_ecc(0)" )
			)
			( signal "M_G_ECC<1>"
				( objectStatus "@baseboard_fab2_lib.baseboard_fab2(sch_1):m_g_ecc(1)" )
			)
			( signal "M_G_ECC<2>"
				( objectStatus "@baseboard_fab2_lib.baseboard_fab2(sch_1):m_g_ecc(2)" )
			)
			( signal "M_G_ECC<3>"
				( objectStatus "@baseboard_fab2_lib.baseboard_fab2(sch_1):m_g_ecc(3)" )
			)
			( signal "M_G_ECC<4>"
				( objectStatus "@baseboard_fab2_lib.baseboard_fab2(sch_1):m_g_ecc(4)" )
			)
			( signal "M_G_ECC<5>"
				( objectStatus "@baseboard_fab2_lib.baseboard_fab2(sch_1):m_g_ecc(5)" )
			)
			( signal "M_G_ECC<6>"
				( objectStatus "@baseboard_fab2_lib.baseboard_fab2(sch_1):m_g_ecc(6)" )
			)
			( signal "M_G_ECC<7>"
				( objectStatus "@baseboard_fab2_lib.baseboard_fab2(sch_1):m_g_ecc(7)" )
			)
			( signal "M_G_MA<0>"
				( objectStatus "@baseboard_fab2_lib.baseboard_fab2(sch_1):m_g_ma(0)" )
			)
			( signal "M_G_MA<1>"
				( objectStatus "@baseboard_fab2_lib.baseboard_fab2(sch_1):m_g_ma(1)" )
			)
			( signal "M_G_MA<2>"
				( objectStatus "@baseboard_fab2_lib.baseboard_fab2(sch_1):m_g_ma(2)" )
			)
			( signal "M_G_MA<3>"
				( objectStatus "@baseboard_fab2_lib.baseboard_fab2(sch_1):m_g_ma(3)" )
			)
			( signal "M_G_MA<4>"
				( objectStatus "@baseboard_fab2_lib.baseboard_fab2(sch_1):m_g_ma(4)" )
			)
			( signal "M_G_MA<5>"
				( objectStatus "@baseboard_fab2_lib.baseboard_fab2(sch_1):m_g_ma(5)" )
			)
			( signal "M_G_MA<6>"
				( objectStatus "@baseboard_fab2_lib.baseboard_fab2(sch_1):m_g_ma(6)" )
			)
			( signal "M_G_MA<7>"
				( objectStatus "@baseboard_fab2_lib.baseboard_fab2(sch_1):m_g_ma(7)" )
			)
			( signal "M_G_MA<8>"
				( objectStatus "@baseboard_fab2_lib.baseboard_fab2(sch_1):m_g_ma(8)" )
			)
			( signal "M_G_MA<9>"
				( objectStatus "@baseboard_fab2_lib.baseboard_fab2(sch_1):m_g_ma(9)" )
			)
			( signal "M_G_MA<10>"
				( objectStatus "@baseboard_fab2_lib.baseboard_fab2(sch_1):m_g_ma(10)" )
			)
			( signal "M_G_MA<11>"
				( objectStatus "@baseboard_fab2_lib.baseboard_fab2(sch_1):m_g_ma(11)" )
			)
			( signal "M_G_MA<12>"
				( objectStatus "@baseboard_fab2_lib.baseboard_fab2(sch_1):m_g_ma(12)" )
			)
			( signal "M_G_MA<13>"
				( objectStatus "@baseboard_fab2_lib.baseboard_fab2(sch_1):m_g_ma(13)" )
			)
			( signal "M_G_MA<14>"
				( objectStatus "@baseboard_fab2_lib.baseboard_fab2(sch_1):m_g_ma(14)" )
			)
			( signal "M_G_MA<15>"
				( objectStatus "@baseboard_fab2_lib.baseboard_fab2(sch_1):m_g_ma(15)" )
			)
			( signal "M_G_MA<16>"
				( objectStatus "@baseboard_fab2_lib.baseboard_fab2(sch_1):m_g_ma(16)" )
			)
			( signal "M_G_MA<17>"
				( objectStatus "@baseboard_fab2_lib.baseboard_fab2(sch_1):m_g_ma(17)" )
			)
			( signal "M_G_ODT<0>"
				( objectStatus "@baseboard_fab2_lib.baseboard_fab2(sch_1):m_g_odt(0)" )
			)
			( signal "M_G_ODT<1>"
				( objectStatus "@baseboard_fab2_lib.baseboard_fab2(sch_1):m_g_odt(1)" )
			)
			( signal "M_G_ODT<2>"
				( objectStatus "@baseboard_fab2_lib.baseboard_fab2(sch_1):m_g_odt(2)" )
			)
			( signal "M_G_ODT<3>"
				( objectStatus "@baseboard_fab2_lib.baseboard_fab2(sch_1):m_g_odt(3)" )
			)
			( signal "M_G_PAR"
				( objectStatus "@baseboard_fab2_lib.baseboard_fab2(sch_1):m_g_par" )
			)
			( signal "M_H_ACT_N"
				( objectStatus "@baseboard_fab2_lib.baseboard_fab2(sch_1):m_h_act_n" )
			)
			( signal "M_H_ALERT_N"
				( objectStatus "@baseboard_fab2_lib.baseboard_fab2(sch_1):m_h_alert_n" )
			)
			( signal "M_H_BA<0>"
				( objectStatus "@baseboard_fab2_lib.baseboard_fab2(sch_1):m_h_ba(0)" )
			)
			( signal "M_H_BA<1>"
				( objectStatus "@baseboard_fab2_lib.baseboard_fab2(sch_1):m_h_ba(1)" )
			)
			( signal "M_H_BG<0>"
				( objectStatus "@baseboard_fab2_lib.baseboard_fab2(sch_1):m_h_bg(0)" )
			)
			( signal "M_H_BG<1>"
				( objectStatus "@baseboard_fab2_lib.baseboard_fab2(sch_1):m_h_bg(1)" )
			)
			( signal "M_H_C<2>"
				( objectStatus "@baseboard_fab2_lib.baseboard_fab2(sch_1):m_h_c(2)" )
			)
			( signal "M_H_CKE<0>"
				( objectStatus "@baseboard_fab2_lib.baseboard_fab2(sch_1):m_h_cke(0)" )
			)
			( signal "M_H_CKE<1>"
				( objectStatus "@baseboard_fab2_lib.baseboard_fab2(sch_1):m_h_cke(1)" )
			)
			( signal "M_H_CKE<2>"
				( objectStatus "@baseboard_fab2_lib.baseboard_fab2(sch_1):m_h_cke(2)" )
			)
			( signal "M_H_CKE<3>"
				( objectStatus "@baseboard_fab2_lib.baseboard_fab2(sch_1):m_h_cke(3)" )
			)
			( signal "M_H_CLK_DN<0>"
				( objectStatus "@baseboard_fab2_lib.baseboard_fab2(sch_1):m_h_clk_dn(0)" )
			)
			( signal "M_H_CLK_DN<1>"
				( objectStatus "@baseboard_fab2_lib.baseboard_fab2(sch_1):m_h_clk_dn(1)" )
			)
			( signal "M_H_CLK_DN<2>"
				( objectStatus "@baseboard_fab2_lib.baseboard_fab2(sch_1):m_h_clk_dn(2)" )
			)
			( signal "M_H_CLK_DN<3>"
				( objectStatus "@baseboard_fab2_lib.baseboard_fab2(sch_1):m_h_clk_dn(3)" )
			)
			( signal "M_H_CLK_DP<0>"
				( objectStatus "@baseboard_fab2_lib.baseboard_fab2(sch_1):m_h_clk_dp(0)" )
			)
			( signal "M_H_CLK_DP<1>"
				( objectStatus "@baseboard_fab2_lib.baseboard_fab2(sch_1):m_h_clk_dp(1)" )
			)
			( signal "M_H_CLK_DP<2>"
				( objectStatus "@baseboard_fab2_lib.baseboard_fab2(sch_1):m_h_clk_dp(2)" )
			)
			( signal "M_H_CLK_DP<3>"
				( objectStatus "@baseboard_fab2_lib.baseboard_fab2(sch_1):m_h_clk_dp(3)" )
			)
			( signal "M_H_CS_N<0>"
				( objectStatus "@baseboard_fab2_lib.baseboard_fab2(sch_1):m_h_cs_n(0)" )
			)
			( signal "M_H_CS_N<1>"
				( objectStatus "@baseboard_fab2_lib.baseboard_fab2(sch_1):m_h_cs_n(1)" )
			)
			( signal "M_H_CS_N<2>"
				( objectStatus "@baseboard_fab2_lib.baseboard_fab2(sch_1):m_h_cs_n(2)" )
			)
			( signal "M_H_CS_N<3>"
				( objectStatus "@baseboard_fab2_lib.baseboard_fab2(sch_1):m_h_cs_n(3)" )
			)
			( signal "M_H_CS_N<4>"
				( objectStatus "@baseboard_fab2_lib.baseboard_fab2(sch_1):m_h_cs_n(4)" )
			)
			( signal "M_H_CS_N<5>"
				( objectStatus "@baseboard_fab2_lib.baseboard_fab2(sch_1):m_h_cs_n(5)" )
			)
			( signal "M_H_CS_N<6>"
				( objectStatus "@baseboard_fab2_lib.baseboard_fab2(sch_1):m_h_cs_n(6)" )
			)
			( signal "M_H_CS_N<7>"
				( objectStatus "@baseboard_fab2_lib.baseboard_fab2(sch_1):m_h_cs_n(7)" )
			)
			( signal "M_H_DQ<0>"
				( objectStatus "@baseboard_fab2_lib.baseboard_fab2(sch_1):m_h_dq(0)" )
			)
			( signal "M_H_DQ<1>"
				( objectStatus "@baseboard_fab2_lib.baseboard_fab2(sch_1):m_h_dq(1)" )
			)
			( signal "M_H_DQ<2>"
				( objectStatus "@baseboard_fab2_lib.baseboard_fab2(sch_1):m_h_dq(2)" )
			)
			( signal "M_H_DQ<3>"
				( objectStatus "@baseboard_fab2_lib.baseboard_fab2(sch_1):m_h_dq(3)" )
			)
			( signal "M_H_DQ<4>"
				( objectStatus "@baseboard_fab2_lib.baseboard_fab2(sch_1):m_h_dq(4)" )
			)
			( signal "M_H_DQ<5>"
				( objectStatus "@baseboard_fab2_lib.baseboard_fab2(sch_1):m_h_dq(5)" )
			)
			( signal "M_H_DQ<6>"
				( objectStatus "@baseboard_fab2_lib.baseboard_fab2(sch_1):m_h_dq(6)" )
			)
			( signal "M_H_DQ<7>"
				( objectStatus "@baseboard_fab2_lib.baseboard_fab2(sch_1):m_h_dq(7)" )
			)
			( signal "M_H_DQ<8>"
				( objectStatus "@baseboard_fab2_lib.baseboard_fab2(sch_1):m_h_dq(8)" )
			)
			( signal "M_H_DQ<9>"
				( objectStatus "@baseboard_fab2_lib.baseboard_fab2(sch_1):m_h_dq(9)" )
			)
			( signal "M_H_DQ<10>"
				( objectStatus "@baseboard_fab2_lib.baseboard_fab2(sch_1):m_h_dq(10)" )
			)
			( signal "M_H_DQ<11>"
				( objectStatus "@baseboard_fab2_lib.baseboard_fab2(sch_1):m_h_dq(11)" )
			)
			( signal "M_H_DQ<12>"
				( objectStatus "@baseboard_fab2_lib.baseboard_fab2(sch_1):m_h_dq(12)" )
			)
			( signal "M_H_DQ<13>"
				( objectStatus "@baseboard_fab2_lib.baseboard_fab2(sch_1):m_h_dq(13)" )
			)
			( signal "M_H_DQ<14>"
				( objectStatus "@baseboard_fab2_lib.baseboard_fab2(sch_1):m_h_dq(14)" )
			)
			( signal "M_H_DQ<15>"
				( objectStatus "@baseboard_fab2_lib.baseboard_fab2(sch_1):m_h_dq(15)" )
			)
			( signal "M_H_DQ<16>"
				( objectStatus "@baseboard_fab2_lib.baseboard_fab2(sch_1):m_h_dq(16)" )
			)
			( signal "M_H_DQ<17>"
				( objectStatus "@baseboard_fab2_lib.baseboard_fab2(sch_1):m_h_dq(17)" )
			)
			( signal "M_H_DQ<18>"
				( objectStatus "@baseboard_fab2_lib.baseboard_fab2(sch_1):m_h_dq(18)" )
			)
			( signal "M_H_DQ<19>"
				( objectStatus "@baseboard_fab2_lib.baseboard_fab2(sch_1):m_h_dq(19)" )
			)
			( signal "M_H_DQ<20>"
				( objectStatus "@baseboard_fab2_lib.baseboard_fab2(sch_1):m_h_dq(20)" )
			)
			( signal "M_H_DQ<21>"
				( objectStatus "@baseboard_fab2_lib.baseboard_fab2(sch_1):m_h_dq(21)" )
			)
			( signal "M_H_DQ<22>"
				( objectStatus "@baseboard_fab2_lib.baseboard_fab2(sch_1):m_h_dq(22)" )
			)
			( signal "M_H_DQ<23>"
				( objectStatus "@baseboard_fab2_lib.baseboard_fab2(sch_1):m_h_dq(23)" )
			)
			( signal "M_H_DQ<24>"
				( objectStatus "@baseboard_fab2_lib.baseboard_fab2(sch_1):m_h_dq(24)" )
			)
			( signal "M_H_DQ<25>"
				( objectStatus "@baseboard_fab2_lib.baseboard_fab2(sch_1):m_h_dq(25)" )
			)
			( signal "M_H_DQ<26>"
				( objectStatus "@baseboard_fab2_lib.baseboard_fab2(sch_1):m_h_dq(26)" )
			)
			( signal "M_H_DQ<27>"
				( objectStatus "@baseboard_fab2_lib.baseboard_fab2(sch_1):m_h_dq(27)" )
			)
			( signal "M_H_DQ<28>"
				( objectStatus "@baseboard_fab2_lib.baseboard_fab2(sch_1):m_h_dq(28)" )
			)
			( signal "M_H_DQ<29>"
				( objectStatus "@baseboard_fab2_lib.baseboard_fab2(sch_1):m_h_dq(29)" )
			)
			( signal "M_H_DQ<30>"
				( objectStatus "@baseboard_fab2_lib.baseboard_fab2(sch_1):m_h_dq(30)" )
			)
			( signal "M_H_DQ<31>"
				( objectStatus "@baseboard_fab2_lib.baseboard_fab2(sch_1):m_h_dq(31)" )
			)
			( signal "M_H_DQ<32>"
				( objectStatus "@baseboard_fab2_lib.baseboard_fab2(sch_1):m_h_dq(32)" )
			)
			( signal "M_H_DQ<33>"
				( objectStatus "@baseboard_fab2_lib.baseboard_fab2(sch_1):m_h_dq(33)" )
			)
			( signal "M_H_DQ<34>"
				( objectStatus "@baseboard_fab2_lib.baseboard_fab2(sch_1):m_h_dq(34)" )
			)
			( signal "M_H_DQ<35>"
				( objectStatus "@baseboard_fab2_lib.baseboard_fab2(sch_1):m_h_dq(35)" )
			)
			( signal "M_H_DQ<36>"
				( objectStatus "@baseboard_fab2_lib.baseboard_fab2(sch_1):m_h_dq(36)" )
			)
			( signal "M_H_DQ<37>"
				( objectStatus "@baseboard_fab2_lib.baseboard_fab2(sch_1):m_h_dq(37)" )
			)
			( signal "M_H_DQ<38>"
				( objectStatus "@baseboard_fab2_lib.baseboard_fab2(sch_1):m_h_dq(38)" )
			)
			( signal "M_H_DQ<39>"
				( objectStatus "@baseboard_fab2_lib.baseboard_fab2(sch_1):m_h_dq(39)" )
			)
			( signal "M_H_DQ<40>"
				( objectStatus "@baseboard_fab2_lib.baseboard_fab2(sch_1):m_h_dq(40)" )
			)
			( signal "M_H_DQ<41>"
				( objectStatus "@baseboard_fab2_lib.baseboard_fab2(sch_1):m_h_dq(41)" )
			)
			( signal "M_H_DQ<42>"
				( objectStatus "@baseboard_fab2_lib.baseboard_fab2(sch_1):m_h_dq(42)" )
			)
			( signal "M_H_DQ<43>"
				( objectStatus "@baseboard_fab2_lib.baseboard_fab2(sch_1):m_h_dq(43)" )
			)
			( signal "M_H_DQ<44>"
				( objectStatus "@baseboard_fab2_lib.baseboard_fab2(sch_1):m_h_dq(44)" )
			)
			( signal "M_H_DQ<45>"
				( objectStatus "@baseboard_fab2_lib.baseboard_fab2(sch_1):m_h_dq(45)" )
			)
			( signal "M_H_DQ<46>"
				( objectStatus "@baseboard_fab2_lib.baseboard_fab2(sch_1):m_h_dq(46)" )
			)
			( signal "M_H_DQ<47>"
				( objectStatus "@baseboard_fab2_lib.baseboard_fab2(sch_1):m_h_dq(47)" )
			)
			( signal "M_H_DQ<48>"
				( objectStatus "@baseboard_fab2_lib.baseboard_fab2(sch_1):m_h_dq(48)" )
			)
			( signal "M_H_DQ<49>"
				( objectStatus "@baseboard_fab2_lib.baseboard_fab2(sch_1):m_h_dq(49)" )
			)
			( signal "M_H_DQ<50>"
				( objectStatus "@baseboard_fab2_lib.baseboard_fab2(sch_1):m_h_dq(50)" )
			)
			( signal "M_H_DQ<51>"
				( objectStatus "@baseboard_fab2_lib.baseboard_fab2(sch_1):m_h_dq(51)" )
			)
			( signal "M_H_DQ<52>"
				( objectStatus "@baseboard_fab2_lib.baseboard_fab2(sch_1):m_h_dq(52)" )
			)
			( signal "M_H_DQ<53>"
				( objectStatus "@baseboard_fab2_lib.baseboard_fab2(sch_1):m_h_dq(53)" )
			)
			( signal "M_H_DQ<54>"
				( objectStatus "@baseboard_fab2_lib.baseboard_fab2(sch_1):m_h_dq(54)" )
			)
			( signal "M_H_DQ<55>"
				( objectStatus "@baseboard_fab2_lib.baseboard_fab2(sch_1):m_h_dq(55)" )
			)
			( signal "M_H_DQ<56>"
				( objectStatus "@baseboard_fab2_lib.baseboard_fab2(sch_1):m_h_dq(56)" )
			)
			( signal "M_H_DQ<57>"
				( objectStatus "@baseboard_fab2_lib.baseboard_fab2(sch_1):m_h_dq(57)" )
			)
			( signal "M_H_DQ<58>"
				( objectStatus "@baseboard_fab2_lib.baseboard_fab2(sch_1):m_h_dq(58)" )
			)
			( signal "M_H_DQ<59>"
				( objectStatus "@baseboard_fab2_lib.baseboard_fab2(sch_1):m_h_dq(59)" )
			)
			( signal "M_H_DQ<60>"
				( objectStatus "@baseboard_fab2_lib.baseboard_fab2(sch_1):m_h_dq(60)" )
			)
			( signal "M_H_DQ<61>"
				( objectStatus "@baseboard_fab2_lib.baseboard_fab2(sch_1):m_h_dq(61)" )
			)
			( signal "M_H_DQ<62>"
				( objectStatus "@baseboard_fab2_lib.baseboard_fab2(sch_1):m_h_dq(62)" )
			)
			( signal "M_H_DQ<63>"
				( objectStatus "@baseboard_fab2_lib.baseboard_fab2(sch_1):m_h_dq(63)" )
			)
			( signal "M_H_DQS_DN<0>"
				( objectStatus "@baseboard_fab2_lib.baseboard_fab2(sch_1):m_h_dqs_dn(0)" )
			)
			( signal "M_H_DQS_DN<1>"
				( objectStatus "@baseboard_fab2_lib.baseboard_fab2(sch_1):m_h_dqs_dn(1)" )
			)
			( signal "M_H_DQS_DN<2>"
				( objectStatus "@baseboard_fab2_lib.baseboard_fab2(sch_1):m_h_dqs_dn(2)" )
			)
			( signal "M_H_DQS_DN<3>"
				( objectStatus "@baseboard_fab2_lib.baseboard_fab2(sch_1):m_h_dqs_dn(3)" )
			)
			( signal "M_H_DQS_DN<4>"
				( objectStatus "@baseboard_fab2_lib.baseboard_fab2(sch_1):m_h_dqs_dn(4)" )
			)
			( signal "M_H_DQS_DN<5>"
				( objectStatus "@baseboard_fab2_lib.baseboard_fab2(sch_1):m_h_dqs_dn(5)" )
			)
			( signal "M_H_DQS_DN<6>"
				( objectStatus "@baseboard_fab2_lib.baseboard_fab2(sch_1):m_h_dqs_dn(6)" )
			)
			( signal "M_H_DQS_DN<7>"
				( objectStatus "@baseboard_fab2_lib.baseboard_fab2(sch_1):m_h_dqs_dn(7)" )
			)
			( signal "M_H_DQS_DN<8>"
				( objectStatus "@baseboard_fab2_lib.baseboard_fab2(sch_1):m_h_dqs_dn(8)" )
			)
			( signal "M_H_DQS_DN<9>"
				( objectStatus "@baseboard_fab2_lib.baseboard_fab2(sch_1):m_h_dqs_dn(9)" )
			)
			( signal "M_H_DQS_DN<10>"
				( objectStatus "@baseboard_fab2_lib.baseboard_fab2(sch_1):m_h_dqs_dn(10)" )
			)
			( signal "M_H_DQS_DN<11>"
				( objectStatus "@baseboard_fab2_lib.baseboard_fab2(sch_1):m_h_dqs_dn(11)" )
			)
			( signal "M_H_DQS_DN<12>"
				( objectStatus "@baseboard_fab2_lib.baseboard_fab2(sch_1):m_h_dqs_dn(12)" )
			)
			( signal "M_H_DQS_DN<13>"
				( objectStatus "@baseboard_fab2_lib.baseboard_fab2(sch_1):m_h_dqs_dn(13)" )
			)
			( signal "M_H_DQS_DN<14>"
				( objectStatus "@baseboard_fab2_lib.baseboard_fab2(sch_1):m_h_dqs_dn(14)" )
			)
			( signal "M_H_DQS_DN<15>"
				( objectStatus "@baseboard_fab2_lib.baseboard_fab2(sch_1):m_h_dqs_dn(15)" )
			)
			( signal "M_H_DQS_DN<16>"
				( objectStatus "@baseboard_fab2_lib.baseboard_fab2(sch_1):m_h_dqs_dn(16)" )
			)
			( signal "M_H_DQS_DN<17>"
				( objectStatus "@baseboard_fab2_lib.baseboard_fab2(sch_1):m_h_dqs_dn(17)" )
			)
			( signal "M_H_DQS_DP<0>"
				( objectStatus "@baseboard_fab2_lib.baseboard_fab2(sch_1):m_h_dqs_dp(0)" )
			)
			( signal "M_H_DQS_DP<1>"
				( objectStatus "@baseboard_fab2_lib.baseboard_fab2(sch_1):m_h_dqs_dp(1)" )
			)
			( signal "M_H_DQS_DP<2>"
				( objectStatus "@baseboard_fab2_lib.baseboard_fab2(sch_1):m_h_dqs_dp(2)" )
			)
			( signal "M_H_DQS_DP<3>"
				( objectStatus "@baseboard_fab2_lib.baseboard_fab2(sch_1):m_h_dqs_dp(3)" )
			)
			( signal "M_H_DQS_DP<4>"
				( objectStatus "@baseboard_fab2_lib.baseboard_fab2(sch_1):m_h_dqs_dp(4)" )
			)
			( signal "M_H_DQS_DP<5>"
				( objectStatus "@baseboard_fab2_lib.baseboard_fab2(sch_1):m_h_dqs_dp(5)" )
			)
			( signal "M_H_DQS_DP<6>"
				( objectStatus "@baseboard_fab2_lib.baseboard_fab2(sch_1):m_h_dqs_dp(6)" )
			)
			( signal "M_H_DQS_DP<7>"
				( objectStatus "@baseboard_fab2_lib.baseboard_fab2(sch_1):m_h_dqs_dp(7)" )
			)
			( signal "M_H_DQS_DP<8>"
				( objectStatus "@baseboard_fab2_lib.baseboard_fab2(sch_1):m_h_dqs_dp(8)" )
			)
			( signal "M_H_DQS_DP<9>"
				( objectStatus "@baseboard_fab2_lib.baseboard_fab2(sch_1):m_h_dqs_dp(9)" )
			)
			( signal "M_H_DQS_DP<10>"
				( objectStatus "@baseboard_fab2_lib.baseboard_fab2(sch_1):m_h_dqs_dp(10)" )
			)
			( signal "M_H_DQS_DP<11>"
				( objectStatus "@baseboard_fab2_lib.baseboard_fab2(sch_1):m_h_dqs_dp(11)" )
			)
			( signal "M_H_DQS_DP<12>"
				( objectStatus "@baseboard_fab2_lib.baseboard_fab2(sch_1):m_h_dqs_dp(12)" )
			)
			( signal "M_H_DQS_DP<13>"
				( objectStatus "@baseboard_fab2_lib.baseboard_fab2(sch_1):m_h_dqs_dp(13)" )
			)
			( signal "M_H_DQS_DP<14>"
				( objectStatus "@baseboard_fab2_lib.baseboard_fab2(sch_1):m_h_dqs_dp(14)" )
			)
			( signal "M_H_DQS_DP<15>"
				( objectStatus "@baseboard_fab2_lib.baseboard_fab2(sch_1):m_h_dqs_dp(15)" )
			)
			( signal "M_H_DQS_DP<16>"
				( objectStatus "@baseboard_fab2_lib.baseboard_fab2(sch_1):m_h_dqs_dp(16)" )
			)
			( signal "M_H_DQS_DP<17>"
				( objectStatus "@baseboard_fab2_lib.baseboard_fab2(sch_1):m_h_dqs_dp(17)" )
			)
			( signal "M_H_ECC<0>"
				( objectStatus "@baseboard_fab2_lib.baseboard_fab2(sch_1):m_h_ecc(0)" )
			)
			( signal "M_H_ECC<1>"
				( objectStatus "@baseboard_fab2_lib.baseboard_fab2(sch_1):m_h_ecc(1)" )
			)
			( signal "M_H_ECC<2>"
				( objectStatus "@baseboard_fab2_lib.baseboard_fab2(sch_1):m_h_ecc(2)" )
			)
			( signal "M_H_ECC<3>"
				( objectStatus "@baseboard_fab2_lib.baseboard_fab2(sch_1):m_h_ecc(3)" )
			)
			( signal "M_H_ECC<4>"
				( objectStatus "@baseboard_fab2_lib.baseboard_fab2(sch_1):m_h_ecc(4)" )
			)
			( signal "M_H_ECC<5>"
				( objectStatus "@baseboard_fab2_lib.baseboard_fab2(sch_1):m_h_ecc(5)" )
			)
			( signal "M_H_ECC<6>"
				( objectStatus "@baseboard_fab2_lib.baseboard_fab2(sch_1):m_h_ecc(6)" )
			)
			( signal "M_H_ECC<7>"
				( objectStatus "@baseboard_fab2_lib.baseboard_fab2(sch_1):m_h_ecc(7)" )
			)
			( signal "M_H_MA<0>"
				( objectStatus "@baseboard_fab2_lib.baseboard_fab2(sch_1):m_h_ma(0)" )
			)
			( signal "M_H_MA<1>"
				( objectStatus "@baseboard_fab2_lib.baseboard_fab2(sch_1):m_h_ma(1)" )
			)
			( signal "M_H_MA<2>"
				( objectStatus "@baseboard_fab2_lib.baseboard_fab2(sch_1):m_h_ma(2)" )
			)
			( signal "M_H_MA<3>"
				( objectStatus "@baseboard_fab2_lib.baseboard_fab2(sch_1):m_h_ma(3)" )
			)
			( signal "M_H_MA<4>"
				( objectStatus "@baseboard_fab2_lib.baseboard_fab2(sch_1):m_h_ma(4)" )
			)
			( signal "M_H_MA<5>"
				( objectStatus "@baseboard_fab2_lib.baseboard_fab2(sch_1):m_h_ma(5)" )
			)
			( signal "M_H_MA<6>"
				( objectStatus "@baseboard_fab2_lib.baseboard_fab2(sch_1):m_h_ma(6)" )
			)
			( signal "M_H_MA<7>"
				( objectStatus "@baseboard_fab2_lib.baseboard_fab2(sch_1):m_h_ma(7)" )
			)
			( signal "M_H_MA<8>"
				( objectStatus "@baseboard_fab2_lib.baseboard_fab2(sch_1):m_h_ma(8)" )
			)
			( signal "M_H_MA<9>"
				( objectStatus "@baseboard_fab2_lib.baseboard_fab2(sch_1):m_h_ma(9)" )
			)
			( signal "M_H_MA<10>"
				( objectStatus "@baseboard_fab2_lib.baseboard_fab2(sch_1):m_h_ma(10)" )
			)
			( signal "M_H_MA<11>"
				( objectStatus "@baseboard_fab2_lib.baseboard_fab2(sch_1):m_h_ma(11)" )
			)
			( signal "M_H_MA<12>"
				( objectStatus "@baseboard_fab2_lib.baseboard_fab2(sch_1):m_h_ma(12)" )
			)
			( signal "M_H_MA<13>"
				( objectStatus "@baseboard_fab2_lib.baseboard_fab2(sch_1):m_h_ma(13)" )
			)
			( signal "M_H_MA<14>"
				( objectStatus "@baseboard_fab2_lib.baseboard_fab2(sch_1):m_h_ma(14)" )
			)
			( signal "M_H_MA<15>"
				( objectStatus "@baseboard_fab2_lib.baseboard_fab2(sch_1):m_h_ma(15)" )
			)
			( signal "M_H_MA<16>"
				( objectStatus "@baseboard_fab2_lib.baseboard_fab2(sch_1):m_h_ma(16)" )
			)
			( signal "M_H_MA<17>"
				( objectStatus "@baseboard_fab2_lib.baseboard_fab2(sch_1):m_h_ma(17)" )
			)
			( signal "M_H_ODT<0>"
				( objectStatus "@baseboard_fab2_lib.baseboard_fab2(sch_1):m_h_odt(0)" )
			)
			( signal "M_H_ODT<1>"
				( objectStatus "@baseboard_fab2_lib.baseboard_fab2(sch_1):m_h_odt(1)" )
			)
			( signal "M_H_ODT<2>"
				( objectStatus "@baseboard_fab2_lib.baseboard_fab2(sch_1):m_h_odt(2)" )
			)
			( signal "M_H_ODT<3>"
				( objectStatus "@baseboard_fab2_lib.baseboard_fab2(sch_1):m_h_odt(3)" )
			)
			( signal "M_H_PAR"
				( objectStatus "@baseboard_fab2_lib.baseboard_fab2(sch_1):m_h_par" )
			)
			( signal "M_J_ACT_N"
				( objectStatus "@baseboard_fab2_lib.baseboard_fab2(sch_1):m_j_act_n" )
			)
			( signal "M_J_ALERT_N"
				( objectStatus "@baseboard_fab2_lib.baseboard_fab2(sch_1):m_j_alert_n" )
			)
			( signal "M_J_BA<0>"
				( objectStatus "@baseboard_fab2_lib.baseboard_fab2(sch_1):m_j_ba(0)" )
			)
			( signal "M_J_BA<1>"
				( objectStatus "@baseboard_fab2_lib.baseboard_fab2(sch_1):m_j_ba(1)" )
			)
			( signal "M_J_BG<0>"
				( objectStatus "@baseboard_fab2_lib.baseboard_fab2(sch_1):m_j_bg(0)" )
			)
			( signal "M_J_BG<1>"
				( objectStatus "@baseboard_fab2_lib.baseboard_fab2(sch_1):m_j_bg(1)" )
			)
			( signal "M_J_C<2>"
				( objectStatus "@baseboard_fab2_lib.baseboard_fab2(sch_1):m_j_c(2)" )
			)
			( signal "M_J_CKE<0>"
				( objectStatus "@baseboard_fab2_lib.baseboard_fab2(sch_1):m_j_cke(0)" )
			)
			( signal "M_J_CKE<1>"
				( objectStatus "@baseboard_fab2_lib.baseboard_fab2(sch_1):m_j_cke(1)" )
			)
			( signal "M_J_CKE<2>"
				( objectStatus "@baseboard_fab2_lib.baseboard_fab2(sch_1):m_j_cke(2)" )
			)
			( signal "M_J_CKE<3>"
				( objectStatus "@baseboard_fab2_lib.baseboard_fab2(sch_1):m_j_cke(3)" )
			)
			( signal "M_J_CLK_DN<0>"
				( objectStatus "@baseboard_fab2_lib.baseboard_fab2(sch_1):m_j_clk_dn(0)" )
			)
			( signal "M_J_CLK_DN<1>"
				( objectStatus "@baseboard_fab2_lib.baseboard_fab2(sch_1):m_j_clk_dn(1)" )
			)
			( signal "M_J_CLK_DN<2>"
				( objectStatus "@baseboard_fab2_lib.baseboard_fab2(sch_1):m_j_clk_dn(2)" )
			)
			( signal "M_J_CLK_DN<3>"
				( objectStatus "@baseboard_fab2_lib.baseboard_fab2(sch_1):m_j_clk_dn(3)" )
			)
			( signal "M_J_CLK_DP<0>"
				( objectStatus "@baseboard_fab2_lib.baseboard_fab2(sch_1):m_j_clk_dp(0)" )
			)
			( signal "M_J_CLK_DP<1>"
				( objectStatus "@baseboard_fab2_lib.baseboard_fab2(sch_1):m_j_clk_dp(1)" )
			)
			( signal "M_J_CLK_DP<2>"
				( objectStatus "@baseboard_fab2_lib.baseboard_fab2(sch_1):m_j_clk_dp(2)" )
			)
			( signal "M_J_CLK_DP<3>"
				( objectStatus "@baseboard_fab2_lib.baseboard_fab2(sch_1):m_j_clk_dp(3)" )
			)
			( signal "M_J_CS_N<0>"
				( objectStatus "@baseboard_fab2_lib.baseboard_fab2(sch_1):m_j_cs_n(0)" )
			)
			( signal "M_J_CS_N<1>"
				( objectStatus "@baseboard_fab2_lib.baseboard_fab2(sch_1):m_j_cs_n(1)" )
			)
			( signal "M_J_CS_N<2>"
				( objectStatus "@baseboard_fab2_lib.baseboard_fab2(sch_1):m_j_cs_n(2)" )
			)
			( signal "M_J_CS_N<3>"
				( objectStatus "@baseboard_fab2_lib.baseboard_fab2(sch_1):m_j_cs_n(3)" )
			)
			( signal "M_J_CS_N<4>"
				( objectStatus "@baseboard_fab2_lib.baseboard_fab2(sch_1):m_j_cs_n(4)" )
			)
			( signal "M_J_CS_N<5>"
				( objectStatus "@baseboard_fab2_lib.baseboard_fab2(sch_1):m_j_cs_n(5)" )
			)
			( signal "M_J_CS_N<6>"
				( objectStatus "@baseboard_fab2_lib.baseboard_fab2(sch_1):m_j_cs_n(6)" )
			)
			( signal "M_J_CS_N<7>"
				( objectStatus "@baseboard_fab2_lib.baseboard_fab2(sch_1):m_j_cs_n(7)" )
			)
			( signal "M_J_DQ<0>"
				( objectStatus "@baseboard_fab2_lib.baseboard_fab2(sch_1):m_j_dq(0)" )
			)
			( signal "M_J_DQ<1>"
				( objectStatus "@baseboard_fab2_lib.baseboard_fab2(sch_1):m_j_dq(1)" )
			)
			( signal "M_J_DQ<2>"
				( objectStatus "@baseboard_fab2_lib.baseboard_fab2(sch_1):m_j_dq(2)" )
			)
			( signal "M_J_DQ<3>"
				( objectStatus "@baseboard_fab2_lib.baseboard_fab2(sch_1):m_j_dq(3)" )
			)
			( signal "M_J_DQ<4>"
				( objectStatus "@baseboard_fab2_lib.baseboard_fab2(sch_1):m_j_dq(4)" )
			)
			( signal "M_J_DQ<5>"
				( objectStatus "@baseboard_fab2_lib.baseboard_fab2(sch_1):m_j_dq(5)" )
			)
			( signal "M_J_DQ<6>"
				( objectStatus "@baseboard_fab2_lib.baseboard_fab2(sch_1):m_j_dq(6)" )
			)
			( signal "M_J_DQ<7>"
				( objectStatus "@baseboard_fab2_lib.baseboard_fab2(sch_1):m_j_dq(7)" )
			)
			( signal "M_J_DQ<8>"
				( objectStatus "@baseboard_fab2_lib.baseboard_fab2(sch_1):m_j_dq(8)" )
			)
			( signal "M_J_DQ<9>"
				( objectStatus "@baseboard_fab2_lib.baseboard_fab2(sch_1):m_j_dq(9)" )
			)
			( signal "M_J_DQ<10>"
				( objectStatus "@baseboard_fab2_lib.baseboard_fab2(sch_1):m_j_dq(10)" )
			)
			( signal "M_J_DQ<11>"
				( objectStatus "@baseboard_fab2_lib.baseboard_fab2(sch_1):m_j_dq(11)" )
			)
			( signal "M_J_DQ<12>"
				( objectStatus "@baseboard_fab2_lib.baseboard_fab2(sch_1):m_j_dq(12)" )
			)
			( signal "M_J_DQ<13>"
				( objectStatus "@baseboard_fab2_lib.baseboard_fab2(sch_1):m_j_dq(13)" )
			)
			( signal "M_J_DQ<14>"
				( objectStatus "@baseboard_fab2_lib.baseboard_fab2(sch_1):m_j_dq(14)" )
			)
			( signal "M_J_DQ<15>"
				( objectStatus "@baseboard_fab2_lib.baseboard_fab2(sch_1):m_j_dq(15)" )
			)
			( signal "M_J_DQ<16>"
				( objectStatus "@baseboard_fab2_lib.baseboard_fab2(sch_1):m_j_dq(16)" )
			)
			( signal "M_J_DQ<17>"
				( objectStatus "@baseboard_fab2_lib.baseboard_fab2(sch_1):m_j_dq(17)" )
			)
			( signal "M_J_DQ<18>"
				( objectStatus "@baseboard_fab2_lib.baseboard_fab2(sch_1):m_j_dq(18)" )
			)
			( signal "M_J_DQ<19>"
				( objectStatus "@baseboard_fab2_lib.baseboard_fab2(sch_1):m_j_dq(19)" )
			)
			( signal "M_J_DQ<20>"
				( objectStatus "@baseboard_fab2_lib.baseboard_fab2(sch_1):m_j_dq(20)" )
			)
			( signal "M_J_DQ<21>"
				( objectStatus "@baseboard_fab2_lib.baseboard_fab2(sch_1):m_j_dq(21)" )
			)
			( signal "M_J_DQ<22>"
				( objectStatus "@baseboard_fab2_lib.baseboard_fab2(sch_1):m_j_dq(22)" )
			)
			( signal "M_J_DQ<23>"
				( objectStatus "@baseboard_fab2_lib.baseboard_fab2(sch_1):m_j_dq(23)" )
			)
			( signal "M_J_DQ<24>"
				( objectStatus "@baseboard_fab2_lib.baseboard_fab2(sch_1):m_j_dq(24)" )
			)
			( signal "M_J_DQ<25>"
				( objectStatus "@baseboard_fab2_lib.baseboard_fab2(sch_1):m_j_dq(25)" )
			)
			( signal "M_J_DQ<26>"
				( objectStatus "@baseboard_fab2_lib.baseboard_fab2(sch_1):m_j_dq(26)" )
			)
			( signal "M_J_DQ<27>"
				( objectStatus "@baseboard_fab2_lib.baseboard_fab2(sch_1):m_j_dq(27)" )
			)
			( signal "M_J_DQ<28>"
				( objectStatus "@baseboard_fab2_lib.baseboard_fab2(sch_1):m_j_dq(28)" )
			)
			( signal "M_J_DQ<29>"
				( objectStatus "@baseboard_fab2_lib.baseboard_fab2(sch_1):m_j_dq(29)" )
			)
			( signal "M_J_DQ<30>"
				( objectStatus "@baseboard_fab2_lib.baseboard_fab2(sch_1):m_j_dq(30)" )
			)
			( signal "M_J_DQ<31>"
				( objectStatus "@baseboard_fab2_lib.baseboard_fab2(sch_1):m_j_dq(31)" )
			)
			( signal "M_J_DQ<32>"
				( objectStatus "@baseboard_fab2_lib.baseboard_fab2(sch_1):m_j_dq(32)" )
			)
			( signal "M_J_DQ<33>"
				( objectStatus "@baseboard_fab2_lib.baseboard_fab2(sch_1):m_j_dq(33)" )
			)
			( signal "M_J_DQ<34>"
				( objectStatus "@baseboard_fab2_lib.baseboard_fab2(sch_1):m_j_dq(34)" )
			)
			( signal "M_J_DQ<35>"
				( objectStatus "@baseboard_fab2_lib.baseboard_fab2(sch_1):m_j_dq(35)" )
			)
			( signal "M_J_DQ<36>"
				( objectStatus "@baseboard_fab2_lib.baseboard_fab2(sch_1):m_j_dq(36)" )
			)
			( signal "M_J_DQ<37>"
				( objectStatus "@baseboard_fab2_lib.baseboard_fab2(sch_1):m_j_dq(37)" )
			)
			( signal "M_J_DQ<38>"
				( objectStatus "@baseboard_fab2_lib.baseboard_fab2(sch_1):m_j_dq(38)" )
			)
			( signal "M_J_DQ<39>"
				( objectStatus "@baseboard_fab2_lib.baseboard_fab2(sch_1):m_j_dq(39)" )
			)
			( signal "M_J_DQ<40>"
				( objectStatus "@baseboard_fab2_lib.baseboard_fab2(sch_1):m_j_dq(40)" )
			)
			( signal "M_J_DQ<41>"
				( objectStatus "@baseboard_fab2_lib.baseboard_fab2(sch_1):m_j_dq(41)" )
			)
			( signal "M_J_DQ<42>"
				( objectStatus "@baseboard_fab2_lib.baseboard_fab2(sch_1):m_j_dq(42)" )
			)
			( signal "M_J_DQ<43>"
				( objectStatus "@baseboard_fab2_lib.baseboard_fab2(sch_1):m_j_dq(43)" )
			)
			( signal "M_J_DQ<44>"
				( objectStatus "@baseboard_fab2_lib.baseboard_fab2(sch_1):m_j_dq(44)" )
			)
			( signal "M_J_DQ<45>"
				( objectStatus "@baseboard_fab2_lib.baseboard_fab2(sch_1):m_j_dq(45)" )
			)
			( signal "M_J_DQ<46>"
				( objectStatus "@baseboard_fab2_lib.baseboard_fab2(sch_1):m_j_dq(46)" )
			)
			( signal "M_J_DQ<47>"
				( objectStatus "@baseboard_fab2_lib.baseboard_fab2(sch_1):m_j_dq(47)" )
			)
			( signal "M_J_DQ<48>"
				( objectStatus "@baseboard_fab2_lib.baseboard_fab2(sch_1):m_j_dq(48)" )
			)
			( signal "M_J_DQ<49>"
				( objectStatus "@baseboard_fab2_lib.baseboard_fab2(sch_1):m_j_dq(49)" )
			)
			( signal "M_J_DQ<50>"
				( objectStatus "@baseboard_fab2_lib.baseboard_fab2(sch_1):m_j_dq(50)" )
			)
			( signal "M_J_DQ<51>"
				( objectStatus "@baseboard_fab2_lib.baseboard_fab2(sch_1):m_j_dq(51)" )
			)
			( signal "M_J_DQ<52>"
				( objectStatus "@baseboard_fab2_lib.baseboard_fab2(sch_1):m_j_dq(52)" )
			)
			( signal "M_J_DQ<53>"
				( objectStatus "@baseboard_fab2_lib.baseboard_fab2(sch_1):m_j_dq(53)" )
			)
			( signal "M_J_DQ<54>"
				( objectStatus "@baseboard_fab2_lib.baseboard_fab2(sch_1):m_j_dq(54)" )
			)
			( signal "M_J_DQ<55>"
				( objectStatus "@baseboard_fab2_lib.baseboard_fab2(sch_1):m_j_dq(55)" )
			)
			( signal "M_J_DQ<56>"
				( objectStatus "@baseboard_fab2_lib.baseboard_fab2(sch_1):m_j_dq(56)" )
			)
			( signal "M_J_DQ<57>"
				( objectStatus "@baseboard_fab2_lib.baseboard_fab2(sch_1):m_j_dq(57)" )
			)
			( signal "M_J_DQ<58>"
				( objectStatus "@baseboard_fab2_lib.baseboard_fab2(sch_1):m_j_dq(58)" )
			)
			( signal "M_J_DQ<59>"
				( objectStatus "@baseboard_fab2_lib.baseboard_fab2(sch_1):m_j_dq(59)" )
			)
			( signal "M_J_DQ<60>"
				( objectStatus "@baseboard_fab2_lib.baseboard_fab2(sch_1):m_j_dq(60)" )
			)
			( signal "M_J_DQ<61>"
				( objectStatus "@baseboard_fab2_lib.baseboard_fab2(sch_1):m_j_dq(61)" )
			)
			( signal "M_J_DQ<62>"
				( objectStatus "@baseboard_fab2_lib.baseboard_fab2(sch_1):m_j_dq(62)" )
			)
			( signal "M_J_DQ<63>"
				( objectStatus "@baseboard_fab2_lib.baseboard_fab2(sch_1):m_j_dq(63)" )
			)
			( signal "M_J_DQS_DN<0>"
				( objectStatus "@baseboard_fab2_lib.baseboard_fab2(sch_1):m_j_dqs_dn(0)" )
			)
			( signal "M_J_DQS_DN<1>"
				( objectStatus "@baseboard_fab2_lib.baseboard_fab2(sch_1):m_j_dqs_dn(1)" )
			)
			( signal "M_J_DQS_DN<2>"
				( objectStatus "@baseboard_fab2_lib.baseboard_fab2(sch_1):m_j_dqs_dn(2)" )
			)
			( signal "M_J_DQS_DN<3>"
				( objectStatus "@baseboard_fab2_lib.baseboard_fab2(sch_1):m_j_dqs_dn(3)" )
			)
			( signal "M_J_DQS_DN<4>"
				( objectStatus "@baseboard_fab2_lib.baseboard_fab2(sch_1):m_j_dqs_dn(4)" )
			)
			( signal "M_J_DQS_DN<5>"
				( objectStatus "@baseboard_fab2_lib.baseboard_fab2(sch_1):m_j_dqs_dn(5)" )
			)
			( signal "M_J_DQS_DN<6>"
				( objectStatus "@baseboard_fab2_lib.baseboard_fab2(sch_1):m_j_dqs_dn(6)" )
			)
			( signal "M_J_DQS_DN<7>"
				( objectStatus "@baseboard_fab2_lib.baseboard_fab2(sch_1):m_j_dqs_dn(7)" )
			)
			( signal "M_J_DQS_DN<8>"
				( objectStatus "@baseboard_fab2_lib.baseboard_fab2(sch_1):m_j_dqs_dn(8)" )
			)
			( signal "M_J_DQS_DN<9>"
				( objectStatus "@baseboard_fab2_lib.baseboard_fab2(sch_1):m_j_dqs_dn(9)" )
			)
			( signal "M_J_DQS_DN<10>"
				( objectStatus "@baseboard_fab2_lib.baseboard_fab2(sch_1):m_j_dqs_dn(10)" )
			)
			( signal "M_J_DQS_DN<11>"
				( objectStatus "@baseboard_fab2_lib.baseboard_fab2(sch_1):m_j_dqs_dn(11)" )
			)
			( signal "M_J_DQS_DN<12>"
				( objectStatus "@baseboard_fab2_lib.baseboard_fab2(sch_1):m_j_dqs_dn(12)" )
			)
			( signal "M_J_DQS_DN<13>"
				( objectStatus "@baseboard_fab2_lib.baseboard_fab2(sch_1):m_j_dqs_dn(13)" )
			)
			( signal "M_J_DQS_DN<14>"
				( objectStatus "@baseboard_fab2_lib.baseboard_fab2(sch_1):m_j_dqs_dn(14)" )
			)
			( signal "M_J_DQS_DN<15>"
				( objectStatus "@baseboard_fab2_lib.baseboard_fab2(sch_1):m_j_dqs_dn(15)" )
			)
			( signal "M_J_DQS_DN<16>"
				( objectStatus "@baseboard_fab2_lib.baseboard_fab2(sch_1):m_j_dqs_dn(16)" )
			)
			( signal "M_J_DQS_DN<17>"
				( objectStatus "@baseboard_fab2_lib.baseboard_fab2(sch_1):m_j_dqs_dn(17)" )
			)
			( signal "M_J_DQS_DP<0>"
				( objectStatus "@baseboard_fab2_lib.baseboard_fab2(sch_1):m_j_dqs_dp(0)" )
			)
			( signal "M_J_DQS_DP<1>"
				( objectStatus "@baseboard_fab2_lib.baseboard_fab2(sch_1):m_j_dqs_dp(1)" )
			)
			( signal "M_J_DQS_DP<2>"
				( objectStatus "@baseboard_fab2_lib.baseboard_fab2(sch_1):m_j_dqs_dp(2)" )
			)
			( signal "M_J_DQS_DP<3>"
				( objectStatus "@baseboard_fab2_lib.baseboard_fab2(sch_1):m_j_dqs_dp(3)" )
			)
			( signal "M_J_DQS_DP<4>"
				( objectStatus "@baseboard_fab2_lib.baseboard_fab2(sch_1):m_j_dqs_dp(4)" )
			)
			( signal "M_J_DQS_DP<5>"
				( objectStatus "@baseboard_fab2_lib.baseboard_fab2(sch_1):m_j_dqs_dp(5)" )
			)
			( signal "M_J_DQS_DP<6>"
				( objectStatus "@baseboard_fab2_lib.baseboard_fab2(sch_1):m_j_dqs_dp(6)" )
			)
			( signal "M_J_DQS_DP<7>"
				( objectStatus "@baseboard_fab2_lib.baseboard_fab2(sch_1):m_j_dqs_dp(7)" )
			)
			( signal "M_J_DQS_DP<8>"
				( objectStatus "@baseboard_fab2_lib.baseboard_fab2(sch_1):m_j_dqs_dp(8)" )
			)
			( signal "M_J_DQS_DP<9>"
				( objectStatus "@baseboard_fab2_lib.baseboard_fab2(sch_1):m_j_dqs_dp(9)" )
			)
			( signal "M_J_DQS_DP<10>"
				( objectStatus "@baseboard_fab2_lib.baseboard_fab2(sch_1):m_j_dqs_dp(10)" )
			)
			( signal "M_J_DQS_DP<11>"
				( objectStatus "@baseboard_fab2_lib.baseboard_fab2(sch_1):m_j_dqs_dp(11)" )
			)
			( signal "M_J_DQS_DP<12>"
				( objectStatus "@baseboard_fab2_lib.baseboard_fab2(sch_1):m_j_dqs_dp(12)" )
			)
			( signal "M_J_DQS_DP<13>"
				( objectStatus "@baseboard_fab2_lib.baseboard_fab2(sch_1):m_j_dqs_dp(13)" )
			)
			( signal "M_J_DQS_DP<14>"
				( objectStatus "@baseboard_fab2_lib.baseboard_fab2(sch_1):m_j_dqs_dp(14)" )
			)
			( signal "M_J_DQS_DP<15>"
				( objectStatus "@baseboard_fab2_lib.baseboard_fab2(sch_1):m_j_dqs_dp(15)" )
			)
			( signal "M_J_DQS_DP<16>"
				( objectStatus "@baseboard_fab2_lib.baseboard_fab2(sch_1):m_j_dqs_dp(16)" )
			)
			( signal "M_J_DQS_DP<17>"
				( objectStatus "@baseboard_fab2_lib.baseboard_fab2(sch_1):m_j_dqs_dp(17)" )
			)
			( signal "M_J_ECC<0>"
				( objectStatus "@baseboard_fab2_lib.baseboard_fab2(sch_1):m_j_ecc(0)" )
			)
			( signal "M_J_ECC<1>"
				( objectStatus "@baseboard_fab2_lib.baseboard_fab2(sch_1):m_j_ecc(1)" )
			)
			( signal "M_J_ECC<2>"
				( objectStatus "@baseboard_fab2_lib.baseboard_fab2(sch_1):m_j_ecc(2)" )
			)
			( signal "M_J_ECC<3>"
				( objectStatus "@baseboard_fab2_lib.baseboard_fab2(sch_1):m_j_ecc(3)" )
			)
			( signal "M_J_ECC<4>"
				( objectStatus "@baseboard_fab2_lib.baseboard_fab2(sch_1):m_j_ecc(4)" )
			)
			( signal "M_J_ECC<5>"
				( objectStatus "@baseboard_fab2_lib.baseboard_fab2(sch_1):m_j_ecc(5)" )
			)
			( signal "M_J_ECC<6>"
				( objectStatus "@baseboard_fab2_lib.baseboard_fab2(sch_1):m_j_ecc(6)" )
			)
			( signal "M_J_ECC<7>"
				( objectStatus "@baseboard_fab2_lib.baseboard_fab2(sch_1):m_j_ecc(7)" )
			)
			( signal "M_J_MA<0>"
				( objectStatus "@baseboard_fab2_lib.baseboard_fab2(sch_1):m_j_ma(0)" )
			)
			( signal "M_J_MA<1>"
				( objectStatus "@baseboard_fab2_lib.baseboard_fab2(sch_1):m_j_ma(1)" )
			)
			( signal "M_J_MA<2>"
				( objectStatus "@baseboard_fab2_lib.baseboard_fab2(sch_1):m_j_ma(2)" )
			)
			( signal "M_J_MA<3>"
				( objectStatus "@baseboard_fab2_lib.baseboard_fab2(sch_1):m_j_ma(3)" )
			)
			( signal "M_J_MA<4>"
				( objectStatus "@baseboard_fab2_lib.baseboard_fab2(sch_1):m_j_ma(4)" )
			)
			( signal "M_J_MA<5>"
				( objectStatus "@baseboard_fab2_lib.baseboard_fab2(sch_1):m_j_ma(5)" )
			)
			( signal "M_J_MA<6>"
				( objectStatus "@baseboard_fab2_lib.baseboard_fab2(sch_1):m_j_ma(6)" )
			)
			( signal "M_J_MA<7>"
				( objectStatus "@baseboard_fab2_lib.baseboard_fab2(sch_1):m_j_ma(7)" )
			)
			( signal "M_J_MA<8>"
				( objectStatus "@baseboard_fab2_lib.baseboard_fab2(sch_1):m_j_ma(8)" )
			)
			( signal "M_J_MA<9>"
				( objectStatus "@baseboard_fab2_lib.baseboard_fab2(sch_1):m_j_ma(9)" )
			)
			( signal "M_J_MA<10>"
				( objectStatus "@baseboard_fab2_lib.baseboard_fab2(sch_1):m_j_ma(10)" )
			)
			( signal "M_J_MA<11>"
				( objectStatus "@baseboard_fab2_lib.baseboard_fab2(sch_1):m_j_ma(11)" )
			)
			( signal "M_J_MA<12>"
				( objectStatus "@baseboard_fab2_lib.baseboard_fab2(sch_1):m_j_ma(12)" )
			)
			( signal "M_J_MA<13>"
				( objectStatus "@baseboard_fab2_lib.baseboard_fab2(sch_1):m_j_ma(13)" )
			)
			( signal "M_J_MA<14>"
				( objectStatus "@baseboard_fab2_lib.baseboard_fab2(sch_1):m_j_ma(14)" )
			)
			( signal "M_J_MA<15>"
				( objectStatus "@baseboard_fab2_lib.baseboard_fab2(sch_1):m_j_ma(15)" )
			)
			( signal "M_J_MA<16>"
				( objectStatus "@baseboard_fab2_lib.baseboard_fab2(sch_1):m_j_ma(16)" )
			)
			( signal "M_J_MA<17>"
				( objectStatus "@baseboard_fab2_lib.baseboard_fab2(sch_1):m_j_ma(17)" )
			)
			( signal "M_J_ODT<0>"
				( objectStatus "@baseboard_fab2_lib.baseboard_fab2(sch_1):m_j_odt(0)" )
			)
			( signal "M_J_ODT<1>"
				( objectStatus "@baseboard_fab2_lib.baseboard_fab2(sch_1):m_j_odt(1)" )
			)
			( signal "M_J_ODT<2>"
				( objectStatus "@baseboard_fab2_lib.baseboard_fab2(sch_1):m_j_odt(2)" )
			)
			( signal "M_J_ODT<3>"
				( objectStatus "@baseboard_fab2_lib.baseboard_fab2(sch_1):m_j_odt(3)" )
			)
			( signal "M_J_PAR"
				( objectStatus "@baseboard_fab2_lib.baseboard_fab2(sch_1):m_j_par" )
			)
			( signal "M_K_ACT_N"
				( objectStatus "@baseboard_fab2_lib.baseboard_fab2(sch_1):m_k_act_n" )
			)
			( signal "M_K_ALERT_N"
				( objectStatus "@baseboard_fab2_lib.baseboard_fab2(sch_1):m_k_alert_n" )
			)
			( signal "M_K_BA<0>"
				( objectStatus "@baseboard_fab2_lib.baseboard_fab2(sch_1):m_k_ba(0)" )
			)
			( signal "M_K_BA<1>"
				( objectStatus "@baseboard_fab2_lib.baseboard_fab2(sch_1):m_k_ba(1)" )
			)
			( signal "M_K_BG<0>"
				( objectStatus "@baseboard_fab2_lib.baseboard_fab2(sch_1):m_k_bg(0)" )
			)
			( signal "M_K_BG<1>"
				( objectStatus "@baseboard_fab2_lib.baseboard_fab2(sch_1):m_k_bg(1)" )
			)
			( signal "M_K_C<2>"
				( objectStatus "@baseboard_fab2_lib.baseboard_fab2(sch_1):m_k_c(2)" )
			)
			( signal "M_K_CKE<0>"
				( objectStatus "@baseboard_fab2_lib.baseboard_fab2(sch_1):m_k_cke(0)" )
			)
			( signal "M_K_CKE<1>"
				( objectStatus "@baseboard_fab2_lib.baseboard_fab2(sch_1):m_k_cke(1)" )
			)
			( signal "M_K_CKE<2>"
				( objectStatus "@baseboard_fab2_lib.baseboard_fab2(sch_1):m_k_cke(2)" )
			)
			( signal "M_K_CKE<3>"
				( objectStatus "@baseboard_fab2_lib.baseboard_fab2(sch_1):m_k_cke(3)" )
			)
			( signal "M_K_CLK_DN<0>"
				( objectStatus "@baseboard_fab2_lib.baseboard_fab2(sch_1):m_k_clk_dn(0)" )
			)
			( signal "M_K_CLK_DN<1>"
				( objectStatus "@baseboard_fab2_lib.baseboard_fab2(sch_1):m_k_clk_dn(1)" )
			)
			( signal "M_K_CLK_DN<2>"
				( objectStatus "@baseboard_fab2_lib.baseboard_fab2(sch_1):m_k_clk_dn(2)" )
			)
			( signal "M_K_CLK_DN<3>"
				( objectStatus "@baseboard_fab2_lib.baseboard_fab2(sch_1):m_k_clk_dn(3)" )
			)
			( signal "M_K_CLK_DP<0>"
				( objectStatus "@baseboard_fab2_lib.baseboard_fab2(sch_1):m_k_clk_dp(0)" )
			)
			( signal "M_K_CLK_DP<1>"
				( objectStatus "@baseboard_fab2_lib.baseboard_fab2(sch_1):m_k_clk_dp(1)" )
			)
			( signal "M_K_CLK_DP<2>"
				( objectStatus "@baseboard_fab2_lib.baseboard_fab2(sch_1):m_k_clk_dp(2)" )
			)
			( signal "M_K_CLK_DP<3>"
				( objectStatus "@baseboard_fab2_lib.baseboard_fab2(sch_1):m_k_clk_dp(3)" )
			)
			( signal "M_K_CS_N<0>"
				( objectStatus "@baseboard_fab2_lib.baseboard_fab2(sch_1):m_k_cs_n(0)" )
			)
			( signal "M_K_CS_N<1>"
				( objectStatus "@baseboard_fab2_lib.baseboard_fab2(sch_1):m_k_cs_n(1)" )
			)
			( signal "M_K_CS_N<2>"
				( objectStatus "@baseboard_fab2_lib.baseboard_fab2(sch_1):m_k_cs_n(2)" )
			)
			( signal "M_K_CS_N<3>"
				( objectStatus "@baseboard_fab2_lib.baseboard_fab2(sch_1):m_k_cs_n(3)" )
			)
			( signal "M_K_CS_N<4>"
				( objectStatus "@baseboard_fab2_lib.baseboard_fab2(sch_1):m_k_cs_n(4)" )
			)
			( signal "M_K_CS_N<5>"
				( objectStatus "@baseboard_fab2_lib.baseboard_fab2(sch_1):m_k_cs_n(5)" )
			)
			( signal "M_K_CS_N<6>"
				( objectStatus "@baseboard_fab2_lib.baseboard_fab2(sch_1):m_k_cs_n(6)" )
			)
			( signal "M_K_CS_N<7>"
				( objectStatus "@baseboard_fab2_lib.baseboard_fab2(sch_1):m_k_cs_n(7)" )
			)
			( signal "M_K_DQ<0>"
				( objectStatus "@baseboard_fab2_lib.baseboard_fab2(sch_1):m_k_dq(0)" )
			)
			( signal "M_K_DQ<1>"
				( objectStatus "@baseboard_fab2_lib.baseboard_fab2(sch_1):m_k_dq(1)" )
			)
			( signal "M_K_DQ<2>"
				( objectStatus "@baseboard_fab2_lib.baseboard_fab2(sch_1):m_k_dq(2)" )
			)
			( signal "M_K_DQ<3>"
				( objectStatus "@baseboard_fab2_lib.baseboard_fab2(sch_1):m_k_dq(3)" )
			)
			( signal "M_K_DQ<4>"
				( objectStatus "@baseboard_fab2_lib.baseboard_fab2(sch_1):m_k_dq(4)" )
			)
			( signal "M_K_DQ<5>"
				( objectStatus "@baseboard_fab2_lib.baseboard_fab2(sch_1):m_k_dq(5)" )
			)
			( signal "M_K_DQ<6>"
				( objectStatus "@baseboard_fab2_lib.baseboard_fab2(sch_1):m_k_dq(6)" )
			)
			( signal "M_K_DQ<7>"
				( objectStatus "@baseboard_fab2_lib.baseboard_fab2(sch_1):m_k_dq(7)" )
			)
			( signal "M_K_DQ<8>"
				( objectStatus "@baseboard_fab2_lib.baseboard_fab2(sch_1):m_k_dq(8)" )
			)
			( signal "M_K_DQ<9>"
				( objectStatus "@baseboard_fab2_lib.baseboard_fab2(sch_1):m_k_dq(9)" )
			)
			( signal "M_K_DQ<10>"
				( objectStatus "@baseboard_fab2_lib.baseboard_fab2(sch_1):m_k_dq(10)" )
			)
			( signal "M_K_DQ<11>"
				( objectStatus "@baseboard_fab2_lib.baseboard_fab2(sch_1):m_k_dq(11)" )
			)
			( signal "M_K_DQ<12>"
				( objectStatus "@baseboard_fab2_lib.baseboard_fab2(sch_1):m_k_dq(12)" )
			)
			( signal "M_K_DQ<13>"
				( objectStatus "@baseboard_fab2_lib.baseboard_fab2(sch_1):m_k_dq(13)" )
			)
			( signal "M_K_DQ<14>"
				( objectStatus "@baseboard_fab2_lib.baseboard_fab2(sch_1):m_k_dq(14)" )
			)
			( signal "M_K_DQ<15>"
				( objectStatus "@baseboard_fab2_lib.baseboard_fab2(sch_1):m_k_dq(15)" )
			)
			( signal "M_K_DQ<16>"
				( objectStatus "@baseboard_fab2_lib.baseboard_fab2(sch_1):m_k_dq(16)" )
			)
			( signal "M_K_DQ<17>"
				( objectStatus "@baseboard_fab2_lib.baseboard_fab2(sch_1):m_k_dq(17)" )
			)
			( signal "M_K_DQ<18>"
				( objectStatus "@baseboard_fab2_lib.baseboard_fab2(sch_1):m_k_dq(18)" )
			)
			( signal "M_K_DQ<19>"
				( objectStatus "@baseboard_fab2_lib.baseboard_fab2(sch_1):m_k_dq(19)" )
			)
			( signal "M_K_DQ<20>"
				( objectStatus "@baseboard_fab2_lib.baseboard_fab2(sch_1):m_k_dq(20)" )
			)
			( signal "M_K_DQ<21>"
				( objectStatus "@baseboard_fab2_lib.baseboard_fab2(sch_1):m_k_dq(21)" )
			)
			( signal "M_K_DQ<22>"
				( objectStatus "@baseboard_fab2_lib.baseboard_fab2(sch_1):m_k_dq(22)" )
			)
			( signal "M_K_DQ<23>"
				( objectStatus "@baseboard_fab2_lib.baseboard_fab2(sch_1):m_k_dq(23)" )
			)
			( signal "M_K_DQ<24>"
				( objectStatus "@baseboard_fab2_lib.baseboard_fab2(sch_1):m_k_dq(24)" )
			)
			( signal "M_K_DQ<25>"
				( objectStatus "@baseboard_fab2_lib.baseboard_fab2(sch_1):m_k_dq(25)" )
			)
			( signal "M_K_DQ<26>"
				( objectStatus "@baseboard_fab2_lib.baseboard_fab2(sch_1):m_k_dq(26)" )
			)
			( signal "M_K_DQ<27>"
				( objectStatus "@baseboard_fab2_lib.baseboard_fab2(sch_1):m_k_dq(27)" )
			)
			( signal "M_K_DQ<28>"
				( objectStatus "@baseboard_fab2_lib.baseboard_fab2(sch_1):m_k_dq(28)" )
			)
			( signal "M_K_DQ<29>"
				( objectStatus "@baseboard_fab2_lib.baseboard_fab2(sch_1):m_k_dq(29)" )
			)
			( signal "M_K_DQ<30>"
				( objectStatus "@baseboard_fab2_lib.baseboard_fab2(sch_1):m_k_dq(30)" )
			)
			( signal "M_K_DQ<31>"
				( objectStatus "@baseboard_fab2_lib.baseboard_fab2(sch_1):m_k_dq(31)" )
			)
			( signal "M_K_DQ<32>"
				( objectStatus "@baseboard_fab2_lib.baseboard_fab2(sch_1):m_k_dq(32)" )
			)
			( signal "M_K_DQ<33>"
				( objectStatus "@baseboard_fab2_lib.baseboard_fab2(sch_1):m_k_dq(33)" )
			)
			( signal "M_K_DQ<34>"
				( objectStatus "@baseboard_fab2_lib.baseboard_fab2(sch_1):m_k_dq(34)" )
			)
			( signal "M_K_DQ<35>"
				( objectStatus "@baseboard_fab2_lib.baseboard_fab2(sch_1):m_k_dq(35)" )
			)
			( signal "M_K_DQ<36>"
				( objectStatus "@baseboard_fab2_lib.baseboard_fab2(sch_1):m_k_dq(36)" )
			)
			( signal "M_K_DQ<37>"
				( objectStatus "@baseboard_fab2_lib.baseboard_fab2(sch_1):m_k_dq(37)" )
			)
			( signal "M_K_DQ<38>"
				( objectStatus "@baseboard_fab2_lib.baseboard_fab2(sch_1):m_k_dq(38)" )
			)
			( signal "M_K_DQ<39>"
				( objectStatus "@baseboard_fab2_lib.baseboard_fab2(sch_1):m_k_dq(39)" )
			)
			( signal "M_K_DQ<40>"
				( objectStatus "@baseboard_fab2_lib.baseboard_fab2(sch_1):m_k_dq(40)" )
			)
			( signal "M_K_DQ<41>"
				( objectStatus "@baseboard_fab2_lib.baseboard_fab2(sch_1):m_k_dq(41)" )
			)
			( signal "M_K_DQ<42>"
				( objectStatus "@baseboard_fab2_lib.baseboard_fab2(sch_1):m_k_dq(42)" )
			)
			( signal "M_K_DQ<43>"
				( objectStatus "@baseboard_fab2_lib.baseboard_fab2(sch_1):m_k_dq(43)" )
			)
			( signal "M_K_DQ<44>"
				( objectStatus "@baseboard_fab2_lib.baseboard_fab2(sch_1):m_k_dq(44)" )
			)
			( signal "M_K_DQ<45>"
				( objectStatus "@baseboard_fab2_lib.baseboard_fab2(sch_1):m_k_dq(45)" )
			)
			( signal "M_K_DQ<46>"
				( objectStatus "@baseboard_fab2_lib.baseboard_fab2(sch_1):m_k_dq(46)" )
			)
			( signal "M_K_DQ<47>"
				( objectStatus "@baseboard_fab2_lib.baseboard_fab2(sch_1):m_k_dq(47)" )
			)
			( signal "M_K_DQ<48>"
				( objectStatus "@baseboard_fab2_lib.baseboard_fab2(sch_1):m_k_dq(48)" )
			)
			( signal "M_K_DQ<49>"
				( objectStatus "@baseboard_fab2_lib.baseboard_fab2(sch_1):m_k_dq(49)" )
			)
			( signal "M_K_DQ<50>"
				( objectStatus "@baseboard_fab2_lib.baseboard_fab2(sch_1):m_k_dq(50)" )
			)
			( signal "M_K_DQ<51>"
				( objectStatus "@baseboard_fab2_lib.baseboard_fab2(sch_1):m_k_dq(51)" )
			)
			( signal "M_K_DQ<52>"
				( objectStatus "@baseboard_fab2_lib.baseboard_fab2(sch_1):m_k_dq(52)" )
			)
			( signal "M_K_DQ<53>"
				( objectStatus "@baseboard_fab2_lib.baseboard_fab2(sch_1):m_k_dq(53)" )
			)
			( signal "M_K_DQ<54>"
				( objectStatus "@baseboard_fab2_lib.baseboard_fab2(sch_1):m_k_dq(54)" )
			)
			( signal "M_K_DQ<55>"
				( objectStatus "@baseboard_fab2_lib.baseboard_fab2(sch_1):m_k_dq(55)" )
			)
			( signal "M_K_DQ<56>"
				( objectStatus "@baseboard_fab2_lib.baseboard_fab2(sch_1):m_k_dq(56)" )
			)
			( signal "M_K_DQ<57>"
				( objectStatus "@baseboard_fab2_lib.baseboard_fab2(sch_1):m_k_dq(57)" )
			)
			( signal "M_K_DQ<58>"
				( objectStatus "@baseboard_fab2_lib.baseboard_fab2(sch_1):m_k_dq(58)" )
			)
			( signal "M_K_DQ<59>"
				( objectStatus "@baseboard_fab2_lib.baseboard_fab2(sch_1):m_k_dq(59)" )
			)
			( signal "M_K_DQ<60>"
				( objectStatus "@baseboard_fab2_lib.baseboard_fab2(sch_1):m_k_dq(60)" )
			)
			( signal "M_K_DQ<61>"
				( objectStatus "@baseboard_fab2_lib.baseboard_fab2(sch_1):m_k_dq(61)" )
			)
			( signal "M_K_DQ<62>"
				( objectStatus "@baseboard_fab2_lib.baseboard_fab2(sch_1):m_k_dq(62)" )
			)
			( signal "M_K_DQ<63>"
				( objectStatus "@baseboard_fab2_lib.baseboard_fab2(sch_1):m_k_dq(63)" )
			)
			( signal "M_K_DQS_DN<0>"
				( objectStatus "@baseboard_fab2_lib.baseboard_fab2(sch_1):m_k_dqs_dn(0)" )
			)
			( signal "M_K_DQS_DN<1>"
				( objectStatus "@baseboard_fab2_lib.baseboard_fab2(sch_1):m_k_dqs_dn(1)" )
			)
			( signal "M_K_DQS_DN<2>"
				( objectStatus "@baseboard_fab2_lib.baseboard_fab2(sch_1):m_k_dqs_dn(2)" )
			)
			( signal "M_K_DQS_DN<3>"
				( objectStatus "@baseboard_fab2_lib.baseboard_fab2(sch_1):m_k_dqs_dn(3)" )
			)
			( signal "M_K_DQS_DN<4>"
				( objectStatus "@baseboard_fab2_lib.baseboard_fab2(sch_1):m_k_dqs_dn(4)" )
			)
			( signal "M_K_DQS_DN<5>"
				( objectStatus "@baseboard_fab2_lib.baseboard_fab2(sch_1):m_k_dqs_dn(5)" )
			)
			( signal "M_K_DQS_DN<6>"
				( objectStatus "@baseboard_fab2_lib.baseboard_fab2(sch_1):m_k_dqs_dn(6)" )
			)
			( signal "M_K_DQS_DN<7>"
				( objectStatus "@baseboard_fab2_lib.baseboard_fab2(sch_1):m_k_dqs_dn(7)" )
			)
			( signal "M_K_DQS_DN<8>"
				( objectStatus "@baseboard_fab2_lib.baseboard_fab2(sch_1):m_k_dqs_dn(8)" )
			)
			( signal "M_K_DQS_DN<9>"
				( objectStatus "@baseboard_fab2_lib.baseboard_fab2(sch_1):m_k_dqs_dn(9)" )
			)
			( signal "M_K_DQS_DN<10>"
				( objectStatus "@baseboard_fab2_lib.baseboard_fab2(sch_1):m_k_dqs_dn(10)" )
			)
			( signal "M_K_DQS_DN<11>"
				( objectStatus "@baseboard_fab2_lib.baseboard_fab2(sch_1):m_k_dqs_dn(11)" )
			)
			( signal "M_K_DQS_DN<12>"
				( objectStatus "@baseboard_fab2_lib.baseboard_fab2(sch_1):m_k_dqs_dn(12)" )
			)
			( signal "M_K_DQS_DN<13>"
				( objectStatus "@baseboard_fab2_lib.baseboard_fab2(sch_1):m_k_dqs_dn(13)" )
			)
			( signal "M_K_DQS_DN<14>"
				( objectStatus "@baseboard_fab2_lib.baseboard_fab2(sch_1):m_k_dqs_dn(14)" )
			)
			( signal "M_K_DQS_DN<15>"
				( objectStatus "@baseboard_fab2_lib.baseboard_fab2(sch_1):m_k_dqs_dn(15)" )
			)
			( signal "M_K_DQS_DN<16>"
				( objectStatus "@baseboard_fab2_lib.baseboard_fab2(sch_1):m_k_dqs_dn(16)" )
			)
			( signal "M_K_DQS_DN<17>"
				( objectStatus "@baseboard_fab2_lib.baseboard_fab2(sch_1):m_k_dqs_dn(17)" )
			)
			( signal "M_K_DQS_DP<0>"
				( objectStatus "@baseboard_fab2_lib.baseboard_fab2(sch_1):m_k_dqs_dp(0)" )
			)
			( signal "M_K_DQS_DP<1>"
				( objectStatus "@baseboard_fab2_lib.baseboard_fab2(sch_1):m_k_dqs_dp(1)" )
			)
			( signal "M_K_DQS_DP<2>"
				( objectStatus "@baseboard_fab2_lib.baseboard_fab2(sch_1):m_k_dqs_dp(2)" )
			)
			( signal "M_K_DQS_DP<3>"
				( objectStatus "@baseboard_fab2_lib.baseboard_fab2(sch_1):m_k_dqs_dp(3)" )
			)
			( signal "M_K_DQS_DP<4>"
				( objectStatus "@baseboard_fab2_lib.baseboard_fab2(sch_1):m_k_dqs_dp(4)" )
			)
			( signal "M_K_DQS_DP<5>"
				( objectStatus "@baseboard_fab2_lib.baseboard_fab2(sch_1):m_k_dqs_dp(5)" )
			)
			( signal "M_K_DQS_DP<6>"
				( objectStatus "@baseboard_fab2_lib.baseboard_fab2(sch_1):m_k_dqs_dp(6)" )
			)
			( signal "M_K_DQS_DP<7>"
				( objectStatus "@baseboard_fab2_lib.baseboard_fab2(sch_1):m_k_dqs_dp(7)" )
			)
			( signal "M_K_DQS_DP<8>"
				( objectStatus "@baseboard_fab2_lib.baseboard_fab2(sch_1):m_k_dqs_dp(8)" )
			)
			( signal "M_K_DQS_DP<9>"
				( objectStatus "@baseboard_fab2_lib.baseboard_fab2(sch_1):m_k_dqs_dp(9)" )
			)
			( signal "M_K_DQS_DP<10>"
				( objectStatus "@baseboard_fab2_lib.baseboard_fab2(sch_1):m_k_dqs_dp(10)" )
			)
			( signal "M_K_DQS_DP<11>"
				( objectStatus "@baseboard_fab2_lib.baseboard_fab2(sch_1):m_k_dqs_dp(11)" )
			)
			( signal "M_K_DQS_DP<12>"
				( objectStatus "@baseboard_fab2_lib.baseboard_fab2(sch_1):m_k_dqs_dp(12)" )
			)
			( signal "M_K_DQS_DP<13>"
				( objectStatus "@baseboard_fab2_lib.baseboard_fab2(sch_1):m_k_dqs_dp(13)" )
			)
			( signal "M_K_DQS_DP<14>"
				( objectStatus "@baseboard_fab2_lib.baseboard_fab2(sch_1):m_k_dqs_dp(14)" )
			)
			( signal "M_K_DQS_DP<15>"
				( objectStatus "@baseboard_fab2_lib.baseboard_fab2(sch_1):m_k_dqs_dp(15)" )
			)
			( signal "M_K_DQS_DP<16>"
				( objectStatus "@baseboard_fab2_lib.baseboard_fab2(sch_1):m_k_dqs_dp(16)" )
			)
			( signal "M_K_DQS_DP<17>"
				( objectStatus "@baseboard_fab2_lib.baseboard_fab2(sch_1):m_k_dqs_dp(17)" )
			)
			( signal "M_K_ECC<0>"
				( objectStatus "@baseboard_fab2_lib.baseboard_fab2(sch_1):m_k_ecc(0)" )
			)
			( signal "M_K_ECC<1>"
				( objectStatus "@baseboard_fab2_lib.baseboard_fab2(sch_1):m_k_ecc(1)" )
			)
			( signal "M_K_ECC<2>"
				( objectStatus "@baseboard_fab2_lib.baseboard_fab2(sch_1):m_k_ecc(2)" )
			)
			( signal "M_K_ECC<3>"
				( objectStatus "@baseboard_fab2_lib.baseboard_fab2(sch_1):m_k_ecc(3)" )
			)
			( signal "M_K_ECC<4>"
				( objectStatus "@baseboard_fab2_lib.baseboard_fab2(sch_1):m_k_ecc(4)" )
			)
			( signal "M_K_ECC<5>"
				( objectStatus "@baseboard_fab2_lib.baseboard_fab2(sch_1):m_k_ecc(5)" )
			)
			( signal "M_K_ECC<6>"
				( objectStatus "@baseboard_fab2_lib.baseboard_fab2(sch_1):m_k_ecc(6)" )
			)
			( signal "M_K_ECC<7>"
				( objectStatus "@baseboard_fab2_lib.baseboard_fab2(sch_1):m_k_ecc(7)" )
			)
			( signal "M_K_MA<0>"
				( objectStatus "@baseboard_fab2_lib.baseboard_fab2(sch_1):m_k_ma(0)" )
			)
			( signal "M_K_MA<1>"
				( objectStatus "@baseboard_fab2_lib.baseboard_fab2(sch_1):m_k_ma(1)" )
			)
			( signal "M_K_MA<2>"
				( objectStatus "@baseboard_fab2_lib.baseboard_fab2(sch_1):m_k_ma(2)" )
			)
			( signal "M_K_MA<3>"
				( objectStatus "@baseboard_fab2_lib.baseboard_fab2(sch_1):m_k_ma(3)" )
			)
			( signal "M_K_MA<4>"
				( objectStatus "@baseboard_fab2_lib.baseboard_fab2(sch_1):m_k_ma(4)" )
			)
			( signal "M_K_MA<5>"
				( objectStatus "@baseboard_fab2_lib.baseboard_fab2(sch_1):m_k_ma(5)" )
			)
			( signal "M_K_MA<6>"
				( objectStatus "@baseboard_fab2_lib.baseboard_fab2(sch_1):m_k_ma(6)" )
			)
			( signal "M_K_MA<7>"
				( objectStatus "@baseboard_fab2_lib.baseboard_fab2(sch_1):m_k_ma(7)" )
			)
			( signal "M_K_MA<8>"
				( objectStatus "@baseboard_fab2_lib.baseboard_fab2(sch_1):m_k_ma(8)" )
			)
			( signal "M_K_MA<9>"
				( objectStatus "@baseboard_fab2_lib.baseboard_fab2(sch_1):m_k_ma(9)" )
			)
			( signal "M_K_MA<10>"
				( objectStatus "@baseboard_fab2_lib.baseboard_fab2(sch_1):m_k_ma(10)" )
			)
			( signal "M_K_MA<11>"
				( objectStatus "@baseboard_fab2_lib.baseboard_fab2(sch_1):m_k_ma(11)" )
			)
			( signal "M_K_MA<12>"
				( objectStatus "@baseboard_fab2_lib.baseboard_fab2(sch_1):m_k_ma(12)" )
			)
			( signal "M_K_MA<13>"
				( objectStatus "@baseboard_fab2_lib.baseboard_fab2(sch_1):m_k_ma(13)" )
			)
			( signal "M_K_MA<14>"
				( objectStatus "@baseboard_fab2_lib.baseboard_fab2(sch_1):m_k_ma(14)" )
			)
			( signal "M_K_MA<15>"
				( objectStatus "@baseboard_fab2_lib.baseboard_fab2(sch_1):m_k_ma(15)" )
			)
			( signal "M_K_MA<16>"
				( objectStatus "@baseboard_fab2_lib.baseboard_fab2(sch_1):m_k_ma(16)" )
			)
			( signal "M_K_MA<17>"
				( objectStatus "@baseboard_fab2_lib.baseboard_fab2(sch_1):m_k_ma(17)" )
			)
			( signal "M_K_ODT<0>"
				( objectStatus "@baseboard_fab2_lib.baseboard_fab2(sch_1):m_k_odt(0)" )
			)
			( signal "M_K_ODT<1>"
				( objectStatus "@baseboard_fab2_lib.baseboard_fab2(sch_1):m_k_odt(1)" )
			)
			( signal "M_K_ODT<2>"
				( objectStatus "@baseboard_fab2_lib.baseboard_fab2(sch_1):m_k_odt(2)" )
			)
			( signal "M_K_ODT<3>"
				( objectStatus "@baseboard_fab2_lib.baseboard_fab2(sch_1):m_k_odt(3)" )
			)
			( signal "M_K_PAR"
				( objectStatus "@baseboard_fab2_lib.baseboard_fab2(sch_1):m_k_par" )
			)
			( signal "M_L_ACT_N"
				( objectStatus "@baseboard_fab2_lib.baseboard_fab2(sch_1):m_l_act_n" )
			)
			( signal "M_L_ALERT_N"
				( objectStatus "@baseboard_fab2_lib.baseboard_fab2(sch_1):m_l_alert_n" )
			)
			( signal "M_L_BA<0>"
				( objectStatus "@baseboard_fab2_lib.baseboard_fab2(sch_1):m_l_ba(0)" )
			)
			( signal "M_L_BA<1>"
				( objectStatus "@baseboard_fab2_lib.baseboard_fab2(sch_1):m_l_ba(1)" )
			)
			( signal "M_L_BG<0>"
				( objectStatus "@baseboard_fab2_lib.baseboard_fab2(sch_1):m_l_bg(0)" )
			)
			( signal "M_L_BG<1>"
				( objectStatus "@baseboard_fab2_lib.baseboard_fab2(sch_1):m_l_bg(1)" )
			)
			( signal "M_L_C<2>"
				( objectStatus "@baseboard_fab2_lib.baseboard_fab2(sch_1):m_l_c(2)" )
			)
			( signal "M_L_CKE<0>"
				( objectStatus "@baseboard_fab2_lib.baseboard_fab2(sch_1):m_l_cke(0)" )
			)
			( signal "M_L_CKE<1>"
				( objectStatus "@baseboard_fab2_lib.baseboard_fab2(sch_1):m_l_cke(1)" )
			)
			( signal "M_L_CKE<2>"
				( objectStatus "@baseboard_fab2_lib.baseboard_fab2(sch_1):m_l_cke(2)" )
			)
			( signal "M_L_CKE<3>"
				( objectStatus "@baseboard_fab2_lib.baseboard_fab2(sch_1):m_l_cke(3)" )
			)
			( signal "M_L_CLK_DN<0>"
				( objectStatus "@baseboard_fab2_lib.baseboard_fab2(sch_1):m_l_clk_dn(0)" )
			)
			( signal "M_L_CLK_DN<1>"
				( objectStatus "@baseboard_fab2_lib.baseboard_fab2(sch_1):m_l_clk_dn(1)" )
			)
			( signal "M_L_CLK_DN<2>"
				( objectStatus "@baseboard_fab2_lib.baseboard_fab2(sch_1):m_l_clk_dn(2)" )
			)
			( signal "M_L_CLK_DN<3>"
				( objectStatus "@baseboard_fab2_lib.baseboard_fab2(sch_1):m_l_clk_dn(3)" )
			)
			( signal "M_L_CLK_DP<0>"
				( objectStatus "@baseboard_fab2_lib.baseboard_fab2(sch_1):m_l_clk_dp(0)" )
			)
			( signal "M_L_CLK_DP<1>"
				( objectStatus "@baseboard_fab2_lib.baseboard_fab2(sch_1):m_l_clk_dp(1)" )
			)
			( signal "M_L_CLK_DP<2>"
				( objectStatus "@baseboard_fab2_lib.baseboard_fab2(sch_1):m_l_clk_dp(2)" )
			)
			( signal "M_L_CLK_DP<3>"
				( objectStatus "@baseboard_fab2_lib.baseboard_fab2(sch_1):m_l_clk_dp(3)" )
			)
			( signal "M_L_CS_N<0>"
				( objectStatus "@baseboard_fab2_lib.baseboard_fab2(sch_1):m_l_cs_n(0)" )
			)
			( signal "M_L_CS_N<1>"
				( objectStatus "@baseboard_fab2_lib.baseboard_fab2(sch_1):m_l_cs_n(1)" )
			)
			( signal "M_L_CS_N<2>"
				( objectStatus "@baseboard_fab2_lib.baseboard_fab2(sch_1):m_l_cs_n(2)" )
			)
			( signal "M_L_CS_N<3>"
				( objectStatus "@baseboard_fab2_lib.baseboard_fab2(sch_1):m_l_cs_n(3)" )
			)
			( signal "M_L_CS_N<4>"
				( objectStatus "@baseboard_fab2_lib.baseboard_fab2(sch_1):m_l_cs_n(4)" )
			)
			( signal "M_L_CS_N<5>"
				( objectStatus "@baseboard_fab2_lib.baseboard_fab2(sch_1):m_l_cs_n(5)" )
			)
			( signal "M_L_CS_N<6>"
				( objectStatus "@baseboard_fab2_lib.baseboard_fab2(sch_1):m_l_cs_n(6)" )
			)
			( signal "M_L_CS_N<7>"
				( objectStatus "@baseboard_fab2_lib.baseboard_fab2(sch_1):m_l_cs_n(7)" )
			)
			( signal "M_L_DQ<0>"
				( objectStatus "@baseboard_fab2_lib.baseboard_fab2(sch_1):m_l_dq(0)" )
			)
			( signal "M_L_DQ<1>"
				( objectStatus "@baseboard_fab2_lib.baseboard_fab2(sch_1):m_l_dq(1)" )
			)
			( signal "M_L_DQ<2>"
				( objectStatus "@baseboard_fab2_lib.baseboard_fab2(sch_1):m_l_dq(2)" )
			)
			( signal "M_L_DQ<3>"
				( objectStatus "@baseboard_fab2_lib.baseboard_fab2(sch_1):m_l_dq(3)" )
			)
			( signal "M_L_DQ<4>"
				( objectStatus "@baseboard_fab2_lib.baseboard_fab2(sch_1):m_l_dq(4)" )
			)
			( signal "M_L_DQ<5>"
				( objectStatus "@baseboard_fab2_lib.baseboard_fab2(sch_1):m_l_dq(5)" )
			)
			( signal "M_L_DQ<6>"
				( objectStatus "@baseboard_fab2_lib.baseboard_fab2(sch_1):m_l_dq(6)" )
			)
			( signal "M_L_DQ<7>"
				( objectStatus "@baseboard_fab2_lib.baseboard_fab2(sch_1):m_l_dq(7)" )
			)
			( signal "M_L_DQ<8>"
				( objectStatus "@baseboard_fab2_lib.baseboard_fab2(sch_1):m_l_dq(8)" )
			)
			( signal "M_L_DQ<9>"
				( objectStatus "@baseboard_fab2_lib.baseboard_fab2(sch_1):m_l_dq(9)" )
			)
			( signal "M_L_DQ<10>"
				( objectStatus "@baseboard_fab2_lib.baseboard_fab2(sch_1):m_l_dq(10)" )
			)
			( signal "M_L_DQ<11>"
				( objectStatus "@baseboard_fab2_lib.baseboard_fab2(sch_1):m_l_dq(11)" )
			)
			( signal "M_L_DQ<12>"
				( objectStatus "@baseboard_fab2_lib.baseboard_fab2(sch_1):m_l_dq(12)" )
			)
			( signal "M_L_DQ<13>"
				( objectStatus "@baseboard_fab2_lib.baseboard_fab2(sch_1):m_l_dq(13)" )
			)
			( signal "M_L_DQ<14>"
				( objectStatus "@baseboard_fab2_lib.baseboard_fab2(sch_1):m_l_dq(14)" )
			)
			( signal "M_L_DQ<15>"
				( objectStatus "@baseboard_fab2_lib.baseboard_fab2(sch_1):m_l_dq(15)" )
			)
			( signal "M_L_DQ<16>"
				( objectStatus "@baseboard_fab2_lib.baseboard_fab2(sch_1):m_l_dq(16)" )
			)
			( signal "M_L_DQ<17>"
				( objectStatus "@baseboard_fab2_lib.baseboard_fab2(sch_1):m_l_dq(17)" )
			)
			( signal "M_L_DQ<18>"
				( objectStatus "@baseboard_fab2_lib.baseboard_fab2(sch_1):m_l_dq(18)" )
			)
			( signal "M_L_DQ<19>"
				( objectStatus "@baseboard_fab2_lib.baseboard_fab2(sch_1):m_l_dq(19)" )
			)
			( signal "M_L_DQ<20>"
				( objectStatus "@baseboard_fab2_lib.baseboard_fab2(sch_1):m_l_dq(20)" )
			)
			( signal "M_L_DQ<21>"
				( objectStatus "@baseboard_fab2_lib.baseboard_fab2(sch_1):m_l_dq(21)" )
			)
			( signal "M_L_DQ<22>"
				( objectStatus "@baseboard_fab2_lib.baseboard_fab2(sch_1):m_l_dq(22)" )
			)
			( signal "M_L_DQ<23>"
				( objectStatus "@baseboard_fab2_lib.baseboard_fab2(sch_1):m_l_dq(23)" )
			)
			( signal "M_L_DQ<24>"
				( objectStatus "@baseboard_fab2_lib.baseboard_fab2(sch_1):m_l_dq(24)" )
			)
			( signal "M_L_DQ<25>"
				( objectStatus "@baseboard_fab2_lib.baseboard_fab2(sch_1):m_l_dq(25)" )
			)
			( signal "M_L_DQ<26>"
				( objectStatus "@baseboard_fab2_lib.baseboard_fab2(sch_1):m_l_dq(26)" )
			)
			( signal "M_L_DQ<27>"
				( objectStatus "@baseboard_fab2_lib.baseboard_fab2(sch_1):m_l_dq(27)" )
			)
			( signal "M_L_DQ<28>"
				( objectStatus "@baseboard_fab2_lib.baseboard_fab2(sch_1):m_l_dq(28)" )
			)
			( signal "M_L_DQ<29>"
				( objectStatus "@baseboard_fab2_lib.baseboard_fab2(sch_1):m_l_dq(29)" )
			)
			( signal "M_L_DQ<30>"
				( objectStatus "@baseboard_fab2_lib.baseboard_fab2(sch_1):m_l_dq(30)" )
			)
			( signal "M_L_DQ<31>"
				( objectStatus "@baseboard_fab2_lib.baseboard_fab2(sch_1):m_l_dq(31)" )
			)
			( signal "M_L_DQ<32>"
				( objectStatus "@baseboard_fab2_lib.baseboard_fab2(sch_1):m_l_dq(32)" )
			)
			( signal "M_L_DQ<33>"
				( objectStatus "@baseboard_fab2_lib.baseboard_fab2(sch_1):m_l_dq(33)" )
			)
			( signal "M_L_DQ<34>"
				( objectStatus "@baseboard_fab2_lib.baseboard_fab2(sch_1):m_l_dq(34)" )
			)
			( signal "M_L_DQ<35>"
				( objectStatus "@baseboard_fab2_lib.baseboard_fab2(sch_1):m_l_dq(35)" )
			)
			( signal "M_L_DQ<36>"
				( objectStatus "@baseboard_fab2_lib.baseboard_fab2(sch_1):m_l_dq(36)" )
			)
			( signal "M_L_DQ<37>"
				( objectStatus "@baseboard_fab2_lib.baseboard_fab2(sch_1):m_l_dq(37)" )
			)
			( signal "M_L_DQ<38>"
				( objectStatus "@baseboard_fab2_lib.baseboard_fab2(sch_1):m_l_dq(38)" )
			)
			( signal "M_L_DQ<39>"
				( objectStatus "@baseboard_fab2_lib.baseboard_fab2(sch_1):m_l_dq(39)" )
			)
			( signal "M_L_DQ<40>"
				( objectStatus "@baseboard_fab2_lib.baseboard_fab2(sch_1):m_l_dq(40)" )
			)
			( signal "M_L_DQ<41>"
				( objectStatus "@baseboard_fab2_lib.baseboard_fab2(sch_1):m_l_dq(41)" )
			)
			( signal "M_L_DQ<42>"
				( objectStatus "@baseboard_fab2_lib.baseboard_fab2(sch_1):m_l_dq(42)" )
			)
			( signal "M_L_DQ<43>"
				( objectStatus "@baseboard_fab2_lib.baseboard_fab2(sch_1):m_l_dq(43)" )
			)
			( signal "M_L_DQ<44>"
				( objectStatus "@baseboard_fab2_lib.baseboard_fab2(sch_1):m_l_dq(44)" )
			)
			( signal "M_L_DQ<45>"
				( objectStatus "@baseboard_fab2_lib.baseboard_fab2(sch_1):m_l_dq(45)" )
			)
			( signal "M_L_DQ<46>"
				( objectStatus "@baseboard_fab2_lib.baseboard_fab2(sch_1):m_l_dq(46)" )
			)
			( signal "M_L_DQ<47>"
				( objectStatus "@baseboard_fab2_lib.baseboard_fab2(sch_1):m_l_dq(47)" )
			)
			( signal "M_L_DQ<48>"
				( objectStatus "@baseboard_fab2_lib.baseboard_fab2(sch_1):m_l_dq(48)" )
			)
			( signal "M_L_DQ<49>"
				( objectStatus "@baseboard_fab2_lib.baseboard_fab2(sch_1):m_l_dq(49)" )
			)
			( signal "M_L_DQ<50>"
				( objectStatus "@baseboard_fab2_lib.baseboard_fab2(sch_1):m_l_dq(50)" )
			)
			( signal "M_L_DQ<51>"
				( objectStatus "@baseboard_fab2_lib.baseboard_fab2(sch_1):m_l_dq(51)" )
			)
			( signal "M_L_DQ<52>"
				( objectStatus "@baseboard_fab2_lib.baseboard_fab2(sch_1):m_l_dq(52)" )
			)
			( signal "M_L_DQ<53>"
				( objectStatus "@baseboard_fab2_lib.baseboard_fab2(sch_1):m_l_dq(53)" )
			)
			( signal "M_L_DQ<54>"
				( objectStatus "@baseboard_fab2_lib.baseboard_fab2(sch_1):m_l_dq(54)" )
			)
			( signal "M_L_DQ<55>"
				( objectStatus "@baseboard_fab2_lib.baseboard_fab2(sch_1):m_l_dq(55)" )
			)
			( signal "M_L_DQ<56>"
				( objectStatus "@baseboard_fab2_lib.baseboard_fab2(sch_1):m_l_dq(56)" )
			)
			( signal "M_L_DQ<57>"
				( objectStatus "@baseboard_fab2_lib.baseboard_fab2(sch_1):m_l_dq(57)" )
			)
			( signal "M_L_DQ<58>"
				( objectStatus "@baseboard_fab2_lib.baseboard_fab2(sch_1):m_l_dq(58)" )
			)
			( signal "M_L_DQ<59>"
				( objectStatus "@baseboard_fab2_lib.baseboard_fab2(sch_1):m_l_dq(59)" )
			)
			( signal "M_L_DQ<60>"
				( objectStatus "@baseboard_fab2_lib.baseboard_fab2(sch_1):m_l_dq(60)" )
			)
			( signal "M_L_DQ<61>"
				( objectStatus "@baseboard_fab2_lib.baseboard_fab2(sch_1):m_l_dq(61)" )
			)
			( signal "M_L_DQ<62>"
				( objectStatus "@baseboard_fab2_lib.baseboard_fab2(sch_1):m_l_dq(62)" )
			)
			( signal "M_L_DQ<63>"
				( objectStatus "@baseboard_fab2_lib.baseboard_fab2(sch_1):m_l_dq(63)" )
			)
			( signal "M_L_DQS_DN<0>"
				( objectStatus "@baseboard_fab2_lib.baseboard_fab2(sch_1):m_l_dqs_dn(0)" )
			)
			( signal "M_L_DQS_DN<1>"
				( objectStatus "@baseboard_fab2_lib.baseboard_fab2(sch_1):m_l_dqs_dn(1)" )
			)
			( signal "M_L_DQS_DN<2>"
				( objectStatus "@baseboard_fab2_lib.baseboard_fab2(sch_1):m_l_dqs_dn(2)" )
			)
			( signal "M_L_DQS_DN<3>"
				( objectStatus "@baseboard_fab2_lib.baseboard_fab2(sch_1):m_l_dqs_dn(3)" )
			)
			( signal "M_L_DQS_DN<4>"
				( objectStatus "@baseboard_fab2_lib.baseboard_fab2(sch_1):m_l_dqs_dn(4)" )
			)
			( signal "M_L_DQS_DN<5>"
				( objectStatus "@baseboard_fab2_lib.baseboard_fab2(sch_1):m_l_dqs_dn(5)" )
			)
			( signal "M_L_DQS_DN<6>"
				( objectStatus "@baseboard_fab2_lib.baseboard_fab2(sch_1):m_l_dqs_dn(6)" )
			)
			( signal "M_L_DQS_DN<7>"
				( objectStatus "@baseboard_fab2_lib.baseboard_fab2(sch_1):m_l_dqs_dn(7)" )
			)
			( signal "M_L_DQS_DN<8>"
				( objectStatus "@baseboard_fab2_lib.baseboard_fab2(sch_1):m_l_dqs_dn(8)" )
			)
			( signal "M_L_DQS_DN<9>"
				( objectStatus "@baseboard_fab2_lib.baseboard_fab2(sch_1):m_l_dqs_dn(9)" )
			)
			( signal "M_L_DQS_DN<10>"
				( objectStatus "@baseboard_fab2_lib.baseboard_fab2(sch_1):m_l_dqs_dn(10)" )
			)
			( signal "M_L_DQS_DN<11>"
				( objectStatus "@baseboard_fab2_lib.baseboard_fab2(sch_1):m_l_dqs_dn(11)" )
			)
			( signal "M_L_DQS_DN<12>"
				( objectStatus "@baseboard_fab2_lib.baseboard_fab2(sch_1):m_l_dqs_dn(12)" )
			)
			( signal "M_L_DQS_DN<13>"
				( objectStatus "@baseboard_fab2_lib.baseboard_fab2(sch_1):m_l_dqs_dn(13)" )
			)
			( signal "M_L_DQS_DN<14>"
				( objectStatus "@baseboard_fab2_lib.baseboard_fab2(sch_1):m_l_dqs_dn(14)" )
			)
			( signal "M_L_DQS_DN<15>"
				( objectStatus "@baseboard_fab2_lib.baseboard_fab2(sch_1):m_l_dqs_dn(15)" )
			)
			( signal "M_L_DQS_DN<16>"
				( objectStatus "@baseboard_fab2_lib.baseboard_fab2(sch_1):m_l_dqs_dn(16)" )
			)
			( signal "M_L_DQS_DN<17>"
				( objectStatus "@baseboard_fab2_lib.baseboard_fab2(sch_1):m_l_dqs_dn(17)" )
			)
			( signal "M_L_DQS_DP<0>"
				( objectStatus "@baseboard_fab2_lib.baseboard_fab2(sch_1):m_l_dqs_dp(0)" )
			)
			( signal "M_L_DQS_DP<1>"
				( objectStatus "@baseboard_fab2_lib.baseboard_fab2(sch_1):m_l_dqs_dp(1)" )
			)
			( signal "M_L_DQS_DP<2>"
				( objectStatus "@baseboard_fab2_lib.baseboard_fab2(sch_1):m_l_dqs_dp(2)" )
			)
			( signal "M_L_DQS_DP<3>"
				( objectStatus "@baseboard_fab2_lib.baseboard_fab2(sch_1):m_l_dqs_dp(3)" )
			)
			( signal "M_L_DQS_DP<4>"
				( objectStatus "@baseboard_fab2_lib.baseboard_fab2(sch_1):m_l_dqs_dp(4)" )
			)
			( signal "M_L_DQS_DP<5>"
				( objectStatus "@baseboard_fab2_lib.baseboard_fab2(sch_1):m_l_dqs_dp(5)" )
			)
			( signal "M_L_DQS_DP<6>"
				( objectStatus "@baseboard_fab2_lib.baseboard_fab2(sch_1):m_l_dqs_dp(6)" )
			)
			( signal "M_L_DQS_DP<7>"
				( objectStatus "@baseboard_fab2_lib.baseboard_fab2(sch_1):m_l_dqs_dp(7)" )
			)
			( signal "M_L_DQS_DP<8>"
				( objectStatus "@baseboard_fab2_lib.baseboard_fab2(sch_1):m_l_dqs_dp(8)" )
			)
			( signal "M_L_DQS_DP<9>"
				( objectStatus "@baseboard_fab2_lib.baseboard_fab2(sch_1):m_l_dqs_dp(9)" )
			)
			( signal "M_L_DQS_DP<10>"
				( objectStatus "@baseboard_fab2_lib.baseboard_fab2(sch_1):m_l_dqs_dp(10)" )
			)
			( signal "M_L_DQS_DP<11>"
				( objectStatus "@baseboard_fab2_lib.baseboard_fab2(sch_1):m_l_dqs_dp(11)" )
			)
			( signal "M_L_DQS_DP<12>"
				( objectStatus "@baseboard_fab2_lib.baseboard_fab2(sch_1):m_l_dqs_dp(12)" )
			)
			( signal "M_L_DQS_DP<13>"
				( objectStatus "@baseboard_fab2_lib.baseboard_fab2(sch_1):m_l_dqs_dp(13)" )
			)
			( signal "M_L_DQS_DP<14>"
				( objectStatus "@baseboard_fab2_lib.baseboard_fab2(sch_1):m_l_dqs_dp(14)" )
			)
			( signal "M_L_DQS_DP<15>"
				( objectStatus "@baseboard_fab2_lib.baseboard_fab2(sch_1):m_l_dqs_dp(15)" )
			)
			( signal "M_L_DQS_DP<16>"
				( objectStatus "@baseboard_fab2_lib.baseboard_fab2(sch_1):m_l_dqs_dp(16)" )
			)
			( signal "M_L_DQS_DP<17>"
				( objectStatus "@baseboard_fab2_lib.baseboard_fab2(sch_1):m_l_dqs_dp(17)" )
			)
			( signal "M_L_ECC<0>"
				( objectStatus "@baseboard_fab2_lib.baseboard_fab2(sch_1):m_l_ecc(0)" )
			)
			( signal "M_L_ECC<1>"
				( objectStatus "@baseboard_fab2_lib.baseboard_fab2(sch_1):m_l_ecc(1)" )
			)
			( signal "M_L_ECC<2>"
				( objectStatus "@baseboard_fab2_lib.baseboard_fab2(sch_1):m_l_ecc(2)" )
			)
			( signal "M_L_ECC<3>"
				( objectStatus "@baseboard_fab2_lib.baseboard_fab2(sch_1):m_l_ecc(3)" )
			)
			( signal "M_L_ECC<4>"
				( objectStatus "@baseboard_fab2_lib.baseboard_fab2(sch_1):m_l_ecc(4)" )
			)
			( signal "M_L_ECC<5>"
				( objectStatus "@baseboard_fab2_lib.baseboard_fab2(sch_1):m_l_ecc(5)" )
			)
			( signal "M_L_ECC<6>"
				( objectStatus "@baseboard_fab2_lib.baseboard_fab2(sch_1):m_l_ecc(6)" )
			)
			( signal "M_L_ECC<7>"
				( objectStatus "@baseboard_fab2_lib.baseboard_fab2(sch_1):m_l_ecc(7)" )
			)
			( signal "M_L_MA<0>"
				( objectStatus "@baseboard_fab2_lib.baseboard_fab2(sch_1):m_l_ma(0)" )
			)
			( signal "M_L_MA<1>"
				( objectStatus "@baseboard_fab2_lib.baseboard_fab2(sch_1):m_l_ma(1)" )
			)
			( signal "M_L_MA<2>"
				( objectStatus "@baseboard_fab2_lib.baseboard_fab2(sch_1):m_l_ma(2)" )
			)
			( signal "M_L_MA<3>"
				( objectStatus "@baseboard_fab2_lib.baseboard_fab2(sch_1):m_l_ma(3)" )
			)
			( signal "M_L_MA<4>"
				( objectStatus "@baseboard_fab2_lib.baseboard_fab2(sch_1):m_l_ma(4)" )
			)
			( signal "M_L_MA<5>"
				( objectStatus "@baseboard_fab2_lib.baseboard_fab2(sch_1):m_l_ma(5)" )
			)
			( signal "M_L_MA<6>"
				( objectStatus "@baseboard_fab2_lib.baseboard_fab2(sch_1):m_l_ma(6)" )
			)
			( signal "M_L_MA<7>"
				( objectStatus "@baseboard_fab2_lib.baseboard_fab2(sch_1):m_l_ma(7)" )
			)
			( signal "M_L_MA<8>"
				( objectStatus "@baseboard_fab2_lib.baseboard_fab2(sch_1):m_l_ma(8)" )
			)
			( signal "M_L_MA<9>"
				( objectStatus "@baseboard_fab2_lib.baseboard_fab2(sch_1):m_l_ma(9)" )
			)
			( signal "M_L_MA<10>"
				( objectStatus "@baseboard_fab2_lib.baseboard_fab2(sch_1):m_l_ma(10)" )
			)
			( signal "M_L_MA<11>"
				( objectStatus "@baseboard_fab2_lib.baseboard_fab2(sch_1):m_l_ma(11)" )
			)
			( signal "M_L_MA<12>"
				( objectStatus "@baseboard_fab2_lib.baseboard_fab2(sch_1):m_l_ma(12)" )
			)
			( signal "M_L_MA<13>"
				( objectStatus "@baseboard_fab2_lib.baseboard_fab2(sch_1):m_l_ma(13)" )
			)
			( signal "M_L_MA<14>"
				( objectStatus "@baseboard_fab2_lib.baseboard_fab2(sch_1):m_l_ma(14)" )
			)
			( signal "M_L_MA<15>"
				( objectStatus "@baseboard_fab2_lib.baseboard_fab2(sch_1):m_l_ma(15)" )
			)
			( signal "M_L_MA<16>"
				( objectStatus "@baseboard_fab2_lib.baseboard_fab2(sch_1):m_l_ma(16)" )
			)
			( signal "M_L_MA<17>"
				( objectStatus "@baseboard_fab2_lib.baseboard_fab2(sch_1):m_l_ma(17)" )
			)
			( signal "M_L_ODT<0>"
				( objectStatus "@baseboard_fab2_lib.baseboard_fab2(sch_1):m_l_odt(0)" )
			)
			( signal "M_L_ODT<1>"
				( objectStatus "@baseboard_fab2_lib.baseboard_fab2(sch_1):m_l_odt(1)" )
			)
			( signal "M_L_ODT<2>"
				( objectStatus "@baseboard_fab2_lib.baseboard_fab2(sch_1):m_l_odt(2)" )
			)
			( signal "M_L_ODT<3>"
				( objectStatus "@baseboard_fab2_lib.baseboard_fab2(sch_1):m_l_odt(3)" )
			)
			( signal "M_L_PAR"
				( objectStatus "@baseboard_fab2_lib.baseboard_fab2(sch_1):m_l_par" )
			)
			( signal "M_M_ACT_N"
				( objectStatus "@baseboard_fab2_lib.baseboard_fab2(sch_1):m_m_act_n" )
			)
			( signal "M_M_ALERT_N"
				( objectStatus "@baseboard_fab2_lib.baseboard_fab2(sch_1):m_m_alert_n" )
			)
			( signal "M_M_BA<0>"
				( objectStatus "@baseboard_fab2_lib.baseboard_fab2(sch_1):m_m_ba(0)" )
			)
			( signal "M_M_BA<1>"
				( objectStatus "@baseboard_fab2_lib.baseboard_fab2(sch_1):m_m_ba(1)" )
			)
			( signal "M_M_BG<0>"
				( objectStatus "@baseboard_fab2_lib.baseboard_fab2(sch_1):m_m_bg(0)" )
			)
			( signal "M_M_BG<1>"
				( objectStatus "@baseboard_fab2_lib.baseboard_fab2(sch_1):m_m_bg(1)" )
			)
			( signal "M_M_C<2>"
				( objectStatus "@baseboard_fab2_lib.baseboard_fab2(sch_1):m_m_c(2)" )
			)
			( signal "M_M_CKE<0>"
				( objectStatus "@baseboard_fab2_lib.baseboard_fab2(sch_1):m_m_cke(0)" )
			)
			( signal "M_M_CKE<1>"
				( objectStatus "@baseboard_fab2_lib.baseboard_fab2(sch_1):m_m_cke(1)" )
			)
			( signal "M_M_CKE<2>"
				( objectStatus "@baseboard_fab2_lib.baseboard_fab2(sch_1):m_m_cke(2)" )
			)
			( signal "M_M_CKE<3>"
				( objectStatus "@baseboard_fab2_lib.baseboard_fab2(sch_1):m_m_cke(3)" )
			)
			( signal "M_M_CLK_DN<0>"
				( objectStatus "@baseboard_fab2_lib.baseboard_fab2(sch_1):m_m_clk_dn(0)" )
			)
			( signal "M_M_CLK_DN<1>"
				( objectStatus "@baseboard_fab2_lib.baseboard_fab2(sch_1):m_m_clk_dn(1)" )
			)
			( signal "M_M_CLK_DN<2>"
				( objectStatus "@baseboard_fab2_lib.baseboard_fab2(sch_1):m_m_clk_dn(2)" )
			)
			( signal "M_M_CLK_DN<3>"
				( objectStatus "@baseboard_fab2_lib.baseboard_fab2(sch_1):m_m_clk_dn(3)" )
			)
			( signal "M_M_CLK_DP<0>"
				( objectStatus "@baseboard_fab2_lib.baseboard_fab2(sch_1):m_m_clk_dp(0)" )
			)
			( signal "M_M_CLK_DP<1>"
				( objectStatus "@baseboard_fab2_lib.baseboard_fab2(sch_1):m_m_clk_dp(1)" )
			)
			( signal "M_M_CLK_DP<2>"
				( objectStatus "@baseboard_fab2_lib.baseboard_fab2(sch_1):m_m_clk_dp(2)" )
			)
			( signal "M_M_CLK_DP<3>"
				( objectStatus "@baseboard_fab2_lib.baseboard_fab2(sch_1):m_m_clk_dp(3)" )
			)
			( signal "M_M_CS_N<0>"
				( objectStatus "@baseboard_fab2_lib.baseboard_fab2(sch_1):m_m_cs_n(0)" )
			)
			( signal "M_M_CS_N<1>"
				( objectStatus "@baseboard_fab2_lib.baseboard_fab2(sch_1):m_m_cs_n(1)" )
			)
			( signal "M_M_CS_N<2>"
				( objectStatus "@baseboard_fab2_lib.baseboard_fab2(sch_1):m_m_cs_n(2)" )
			)
			( signal "M_M_CS_N<3>"
				( objectStatus "@baseboard_fab2_lib.baseboard_fab2(sch_1):m_m_cs_n(3)" )
			)
			( signal "M_M_CS_N<4>"
				( objectStatus "@baseboard_fab2_lib.baseboard_fab2(sch_1):m_m_cs_n(4)" )
			)
			( signal "M_M_CS_N<5>"
				( objectStatus "@baseboard_fab2_lib.baseboard_fab2(sch_1):m_m_cs_n(5)" )
			)
			( signal "M_M_CS_N<6>"
				( objectStatus "@baseboard_fab2_lib.baseboard_fab2(sch_1):m_m_cs_n(6)" )
			)
			( signal "M_M_CS_N<7>"
				( objectStatus "@baseboard_fab2_lib.baseboard_fab2(sch_1):m_m_cs_n(7)" )
			)
			( signal "M_M_DQ<0>"
				( objectStatus "@baseboard_fab2_lib.baseboard_fab2(sch_1):m_m_dq(0)" )
			)
			( signal "M_M_DQ<1>"
				( objectStatus "@baseboard_fab2_lib.baseboard_fab2(sch_1):m_m_dq(1)" )
			)
			( signal "M_M_DQ<2>"
				( objectStatus "@baseboard_fab2_lib.baseboard_fab2(sch_1):m_m_dq(2)" )
			)
			( signal "M_M_DQ<3>"
				( objectStatus "@baseboard_fab2_lib.baseboard_fab2(sch_1):m_m_dq(3)" )
			)
			( signal "M_M_DQ<4>"
				( objectStatus "@baseboard_fab2_lib.baseboard_fab2(sch_1):m_m_dq(4)" )
			)
			( signal "M_M_DQ<5>"
				( objectStatus "@baseboard_fab2_lib.baseboard_fab2(sch_1):m_m_dq(5)" )
			)
			( signal "M_M_DQ<6>"
				( objectStatus "@baseboard_fab2_lib.baseboard_fab2(sch_1):m_m_dq(6)" )
			)
			( signal "M_M_DQ<7>"
				( objectStatus "@baseboard_fab2_lib.baseboard_fab2(sch_1):m_m_dq(7)" )
			)
			( signal "M_M_DQ<8>"
				( objectStatus "@baseboard_fab2_lib.baseboard_fab2(sch_1):m_m_dq(8)" )
			)
			( signal "M_M_DQ<9>"
				( objectStatus "@baseboard_fab2_lib.baseboard_fab2(sch_1):m_m_dq(9)" )
			)
			( signal "M_M_DQ<10>"
				( objectStatus "@baseboard_fab2_lib.baseboard_fab2(sch_1):m_m_dq(10)" )
			)
			( signal "M_M_DQ<11>"
				( objectStatus "@baseboard_fab2_lib.baseboard_fab2(sch_1):m_m_dq(11)" )
			)
			( signal "M_M_DQ<12>"
				( objectStatus "@baseboard_fab2_lib.baseboard_fab2(sch_1):m_m_dq(12)" )
			)
			( signal "M_M_DQ<13>"
				( objectStatus "@baseboard_fab2_lib.baseboard_fab2(sch_1):m_m_dq(13)" )
			)
			( signal "M_M_DQ<14>"
				( objectStatus "@baseboard_fab2_lib.baseboard_fab2(sch_1):m_m_dq(14)" )
			)
			( signal "M_M_DQ<15>"
				( objectStatus "@baseboard_fab2_lib.baseboard_fab2(sch_1):m_m_dq(15)" )
			)
			( signal "M_M_DQ<16>"
				( objectStatus "@baseboard_fab2_lib.baseboard_fab2(sch_1):m_m_dq(16)" )
			)
			( signal "M_M_DQ<17>"
				( objectStatus "@baseboard_fab2_lib.baseboard_fab2(sch_1):m_m_dq(17)" )
			)
			( signal "M_M_DQ<18>"
				( objectStatus "@baseboard_fab2_lib.baseboard_fab2(sch_1):m_m_dq(18)" )
			)
			( signal "M_M_DQ<19>"
				( objectStatus "@baseboard_fab2_lib.baseboard_fab2(sch_1):m_m_dq(19)" )
			)
			( signal "M_M_DQ<20>"
				( objectStatus "@baseboard_fab2_lib.baseboard_fab2(sch_1):m_m_dq(20)" )
			)
			( signal "M_M_DQ<21>"
				( objectStatus "@baseboard_fab2_lib.baseboard_fab2(sch_1):m_m_dq(21)" )
			)
			( signal "M_M_DQ<22>"
				( objectStatus "@baseboard_fab2_lib.baseboard_fab2(sch_1):m_m_dq(22)" )
			)
			( signal "M_M_DQ<23>"
				( objectStatus "@baseboard_fab2_lib.baseboard_fab2(sch_1):m_m_dq(23)" )
			)
			( signal "M_M_DQ<24>"
				( objectStatus "@baseboard_fab2_lib.baseboard_fab2(sch_1):m_m_dq(24)" )
			)
			( signal "M_M_DQ<25>"
				( objectStatus "@baseboard_fab2_lib.baseboard_fab2(sch_1):m_m_dq(25)" )
			)
			( signal "M_M_DQ<26>"
				( objectStatus "@baseboard_fab2_lib.baseboard_fab2(sch_1):m_m_dq(26)" )
			)
			( signal "M_M_DQ<27>"
				( objectStatus "@baseboard_fab2_lib.baseboard_fab2(sch_1):m_m_dq(27)" )
			)
			( signal "M_M_DQ<28>"
				( objectStatus "@baseboard_fab2_lib.baseboard_fab2(sch_1):m_m_dq(28)" )
			)
			( signal "M_M_DQ<29>"
				( objectStatus "@baseboard_fab2_lib.baseboard_fab2(sch_1):m_m_dq(29)" )
			)
			( signal "M_M_DQ<30>"
				( objectStatus "@baseboard_fab2_lib.baseboard_fab2(sch_1):m_m_dq(30)" )
			)
			( signal "M_M_DQ<31>"
				( objectStatus "@baseboard_fab2_lib.baseboard_fab2(sch_1):m_m_dq(31)" )
			)
			( signal "M_M_DQ<32>"
				( objectStatus "@baseboard_fab2_lib.baseboard_fab2(sch_1):m_m_dq(32)" )
			)
			( signal "M_M_DQ<33>"
				( objectStatus "@baseboard_fab2_lib.baseboard_fab2(sch_1):m_m_dq(33)" )
			)
			( signal "M_M_DQ<34>"
				( objectStatus "@baseboard_fab2_lib.baseboard_fab2(sch_1):m_m_dq(34)" )
			)
			( signal "M_M_DQ<35>"
				( objectStatus "@baseboard_fab2_lib.baseboard_fab2(sch_1):m_m_dq(35)" )
			)
			( signal "M_M_DQ<36>"
				( objectStatus "@baseboard_fab2_lib.baseboard_fab2(sch_1):m_m_dq(36)" )
			)
			( signal "M_M_DQ<37>"
				( objectStatus "@baseboard_fab2_lib.baseboard_fab2(sch_1):m_m_dq(37)" )
			)
			( signal "M_M_DQ<38>"
				( objectStatus "@baseboard_fab2_lib.baseboard_fab2(sch_1):m_m_dq(38)" )
			)
			( signal "M_M_DQ<39>"
				( objectStatus "@baseboard_fab2_lib.baseboard_fab2(sch_1):m_m_dq(39)" )
			)
			( signal "M_M_DQ<40>"
				( objectStatus "@baseboard_fab2_lib.baseboard_fab2(sch_1):m_m_dq(40)" )
			)
			( signal "M_M_DQ<41>"
				( objectStatus "@baseboard_fab2_lib.baseboard_fab2(sch_1):m_m_dq(41)" )
			)
			( signal "M_M_DQ<42>"
				( objectStatus "@baseboard_fab2_lib.baseboard_fab2(sch_1):m_m_dq(42)" )
			)
			( signal "M_M_DQ<43>"
				( objectStatus "@baseboard_fab2_lib.baseboard_fab2(sch_1):m_m_dq(43)" )
			)
			( signal "M_M_DQ<44>"
				( objectStatus "@baseboard_fab2_lib.baseboard_fab2(sch_1):m_m_dq(44)" )
			)
			( signal "M_M_DQ<45>"
				( objectStatus "@baseboard_fab2_lib.baseboard_fab2(sch_1):m_m_dq(45)" )
			)
			( signal "M_M_DQ<46>"
				( objectStatus "@baseboard_fab2_lib.baseboard_fab2(sch_1):m_m_dq(46)" )
			)
			( signal "M_M_DQ<47>"
				( objectStatus "@baseboard_fab2_lib.baseboard_fab2(sch_1):m_m_dq(47)" )
			)
			( signal "M_M_DQ<48>"
				( objectStatus "@baseboard_fab2_lib.baseboard_fab2(sch_1):m_m_dq(48)" )
			)
			( signal "M_M_DQ<49>"
				( objectStatus "@baseboard_fab2_lib.baseboard_fab2(sch_1):m_m_dq(49)" )
			)
			( signal "M_M_DQ<50>"
				( objectStatus "@baseboard_fab2_lib.baseboard_fab2(sch_1):m_m_dq(50)" )
			)
			( signal "M_M_DQ<51>"
				( objectStatus "@baseboard_fab2_lib.baseboard_fab2(sch_1):m_m_dq(51)" )
			)
			( signal "M_M_DQ<52>"
				( objectStatus "@baseboard_fab2_lib.baseboard_fab2(sch_1):m_m_dq(52)" )
			)
			( signal "M_M_DQ<53>"
				( objectStatus "@baseboard_fab2_lib.baseboard_fab2(sch_1):m_m_dq(53)" )
			)
			( signal "M_M_DQ<54>"
				( objectStatus "@baseboard_fab2_lib.baseboard_fab2(sch_1):m_m_dq(54)" )
			)
			( signal "M_M_DQ<55>"
				( objectStatus "@baseboard_fab2_lib.baseboard_fab2(sch_1):m_m_dq(55)" )
			)
			( signal "M_M_DQ<56>"
				( objectStatus "@baseboard_fab2_lib.baseboard_fab2(sch_1):m_m_dq(56)" )
			)
			( signal "M_M_DQ<57>"
				( objectStatus "@baseboard_fab2_lib.baseboard_fab2(sch_1):m_m_dq(57)" )
			)
			( signal "M_M_DQ<58>"
				( objectStatus "@baseboard_fab2_lib.baseboard_fab2(sch_1):m_m_dq(58)" )
			)
			( signal "M_M_DQ<59>"
				( objectStatus "@baseboard_fab2_lib.baseboard_fab2(sch_1):m_m_dq(59)" )
			)
			( signal "M_M_DQ<60>"
				( objectStatus "@baseboard_fab2_lib.baseboard_fab2(sch_1):m_m_dq(60)" )
			)
			( signal "M_M_DQ<61>"
				( objectStatus "@baseboard_fab2_lib.baseboard_fab2(sch_1):m_m_dq(61)" )
			)
			( signal "M_M_DQ<62>"
				( objectStatus "@baseboard_fab2_lib.baseboard_fab2(sch_1):m_m_dq(62)" )
			)
			( signal "M_M_DQ<63>"
				( objectStatus "@baseboard_fab2_lib.baseboard_fab2(sch_1):m_m_dq(63)" )
			)
			( signal "M_M_DQS_DN<0>"
				( objectStatus "@baseboard_fab2_lib.baseboard_fab2(sch_1):m_m_dqs_dn(0)" )
			)
			( signal "M_M_DQS_DN<1>"
				( objectStatus "@baseboard_fab2_lib.baseboard_fab2(sch_1):m_m_dqs_dn(1)" )
			)
			( signal "M_M_DQS_DN<2>"
				( objectStatus "@baseboard_fab2_lib.baseboard_fab2(sch_1):m_m_dqs_dn(2)" )
			)
			( signal "M_M_DQS_DN<3>"
				( objectStatus "@baseboard_fab2_lib.baseboard_fab2(sch_1):m_m_dqs_dn(3)" )
			)
			( signal "M_M_DQS_DN<4>"
				( objectStatus "@baseboard_fab2_lib.baseboard_fab2(sch_1):m_m_dqs_dn(4)" )
			)
			( signal "M_M_DQS_DN<5>"
				( objectStatus "@baseboard_fab2_lib.baseboard_fab2(sch_1):m_m_dqs_dn(5)" )
			)
			( signal "M_M_DQS_DN<6>"
				( objectStatus "@baseboard_fab2_lib.baseboard_fab2(sch_1):m_m_dqs_dn(6)" )
			)
			( signal "M_M_DQS_DN<7>"
				( objectStatus "@baseboard_fab2_lib.baseboard_fab2(sch_1):m_m_dqs_dn(7)" )
			)
			( signal "M_M_DQS_DN<8>"
				( objectStatus "@baseboard_fab2_lib.baseboard_fab2(sch_1):m_m_dqs_dn(8)" )
			)
			( signal "M_M_DQS_DN<9>"
				( objectStatus "@baseboard_fab2_lib.baseboard_fab2(sch_1):m_m_dqs_dn(9)" )
			)
			( signal "M_M_DQS_DN<10>"
				( objectStatus "@baseboard_fab2_lib.baseboard_fab2(sch_1):m_m_dqs_dn(10)" )
			)
			( signal "M_M_DQS_DN<11>"
				( objectStatus "@baseboard_fab2_lib.baseboard_fab2(sch_1):m_m_dqs_dn(11)" )
			)
			( signal "M_M_DQS_DN<12>"
				( objectStatus "@baseboard_fab2_lib.baseboard_fab2(sch_1):m_m_dqs_dn(12)" )
			)
			( signal "M_M_DQS_DN<13>"
				( objectStatus "@baseboard_fab2_lib.baseboard_fab2(sch_1):m_m_dqs_dn(13)" )
			)
			( signal "M_M_DQS_DN<14>"
				( objectStatus "@baseboard_fab2_lib.baseboard_fab2(sch_1):m_m_dqs_dn(14)" )
			)
			( signal "M_M_DQS_DN<15>"
				( objectStatus "@baseboard_fab2_lib.baseboard_fab2(sch_1):m_m_dqs_dn(15)" )
			)
			( signal "M_M_DQS_DN<16>"
				( objectStatus "@baseboard_fab2_lib.baseboard_fab2(sch_1):m_m_dqs_dn(16)" )
			)
			( signal "M_M_DQS_DN<17>"
				( objectStatus "@baseboard_fab2_lib.baseboard_fab2(sch_1):m_m_dqs_dn(17)" )
			)
			( signal "M_M_DQS_DP<0>"
				( objectStatus "@baseboard_fab2_lib.baseboard_fab2(sch_1):m_m_dqs_dp(0)" )
			)
			( signal "M_M_DQS_DP<1>"
				( objectStatus "@baseboard_fab2_lib.baseboard_fab2(sch_1):m_m_dqs_dp(1)" )
			)
			( signal "M_M_DQS_DP<2>"
				( objectStatus "@baseboard_fab2_lib.baseboard_fab2(sch_1):m_m_dqs_dp(2)" )
			)
			( signal "M_M_DQS_DP<3>"
				( objectStatus "@baseboard_fab2_lib.baseboard_fab2(sch_1):m_m_dqs_dp(3)" )
			)
			( signal "M_M_DQS_DP<4>"
				( objectStatus "@baseboard_fab2_lib.baseboard_fab2(sch_1):m_m_dqs_dp(4)" )
			)
			( signal "M_M_DQS_DP<5>"
				( objectStatus "@baseboard_fab2_lib.baseboard_fab2(sch_1):m_m_dqs_dp(5)" )
			)
			( signal "M_M_DQS_DP<6>"
				( objectStatus "@baseboard_fab2_lib.baseboard_fab2(sch_1):m_m_dqs_dp(6)" )
			)
			( signal "M_M_DQS_DP<7>"
				( objectStatus "@baseboard_fab2_lib.baseboard_fab2(sch_1):m_m_dqs_dp(7)" )
			)
			( signal "M_M_DQS_DP<8>"
				( objectStatus "@baseboard_fab2_lib.baseboard_fab2(sch_1):m_m_dqs_dp(8)" )
			)
			( signal "M_M_DQS_DP<9>"
				( objectStatus "@baseboard_fab2_lib.baseboard_fab2(sch_1):m_m_dqs_dp(9)" )
			)
			( signal "M_M_DQS_DP<10>"
				( objectStatus "@baseboard_fab2_lib.baseboard_fab2(sch_1):m_m_dqs_dp(10)" )
			)
			( signal "M_M_DQS_DP<11>"
				( objectStatus "@baseboard_fab2_lib.baseboard_fab2(sch_1):m_m_dqs_dp(11)" )
			)
			( signal "M_M_DQS_DP<12>"
				( objectStatus "@baseboard_fab2_lib.baseboard_fab2(sch_1):m_m_dqs_dp(12)" )
			)
			( signal "M_M_DQS_DP<13>"
				( objectStatus "@baseboard_fab2_lib.baseboard_fab2(sch_1):m_m_dqs_dp(13)" )
			)
			( signal "M_M_DQS_DP<14>"
				( objectStatus "@baseboard_fab2_lib.baseboard_fab2(sch_1):m_m_dqs_dp(14)" )
			)
			( signal "M_M_DQS_DP<15>"
				( objectStatus "@baseboard_fab2_lib.baseboard_fab2(sch_1):m_m_dqs_dp(15)" )
			)
			( signal "M_M_DQS_DP<16>"
				( objectStatus "@baseboard_fab2_lib.baseboard_fab2(sch_1):m_m_dqs_dp(16)" )
			)
			( signal "M_M_DQS_DP<17>"
				( objectStatus "@baseboard_fab2_lib.baseboard_fab2(sch_1):m_m_dqs_dp(17)" )
			)
			( signal "M_M_ECC<0>"
				( objectStatus "@baseboard_fab2_lib.baseboard_fab2(sch_1):m_m_ecc(0)" )
			)
			( signal "M_M_ECC<1>"
				( objectStatus "@baseboard_fab2_lib.baseboard_fab2(sch_1):m_m_ecc(1)" )
			)
			( signal "M_M_ECC<2>"
				( objectStatus "@baseboard_fab2_lib.baseboard_fab2(sch_1):m_m_ecc(2)" )
			)
			( signal "M_M_ECC<3>"
				( objectStatus "@baseboard_fab2_lib.baseboard_fab2(sch_1):m_m_ecc(3)" )
			)
			( signal "M_M_ECC<4>"
				( objectStatus "@baseboard_fab2_lib.baseboard_fab2(sch_1):m_m_ecc(4)" )
			)
			( signal "M_M_ECC<5>"
				( objectStatus "@baseboard_fab2_lib.baseboard_fab2(sch_1):m_m_ecc(5)" )
			)
			( signal "M_M_ECC<6>"
				( objectStatus "@baseboard_fab2_lib.baseboard_fab2(sch_1):m_m_ecc(6)" )
			)
			( signal "M_M_ECC<7>"
				( objectStatus "@baseboard_fab2_lib.baseboard_fab2(sch_1):m_m_ecc(7)" )
			)
			( signal "M_M_MA<0>"
				( objectStatus "@baseboard_fab2_lib.baseboard_fab2(sch_1):m_m_ma(0)" )
			)
			( signal "M_M_MA<1>"
				( objectStatus "@baseboard_fab2_lib.baseboard_fab2(sch_1):m_m_ma(1)" )
			)
			( signal "M_M_MA<2>"
				( objectStatus "@baseboard_fab2_lib.baseboard_fab2(sch_1):m_m_ma(2)" )
			)
			( signal "M_M_MA<3>"
				( objectStatus "@baseboard_fab2_lib.baseboard_fab2(sch_1):m_m_ma(3)" )
			)
			( signal "M_M_MA<4>"
				( objectStatus "@baseboard_fab2_lib.baseboard_fab2(sch_1):m_m_ma(4)" )
			)
			( signal "M_M_MA<5>"
				( objectStatus "@baseboard_fab2_lib.baseboard_fab2(sch_1):m_m_ma(5)" )
			)
			( signal "M_M_MA<6>"
				( objectStatus "@baseboard_fab2_lib.baseboard_fab2(sch_1):m_m_ma(6)" )
			)
			( signal "M_M_MA<7>"
				( objectStatus "@baseboard_fab2_lib.baseboard_fab2(sch_1):m_m_ma(7)" )
			)
			( signal "M_M_MA<8>"
				( objectStatus "@baseboard_fab2_lib.baseboard_fab2(sch_1):m_m_ma(8)" )
			)
			( signal "M_M_MA<9>"
				( objectStatus "@baseboard_fab2_lib.baseboard_fab2(sch_1):m_m_ma(9)" )
			)
			( signal "M_M_MA<10>"
				( objectStatus "@baseboard_fab2_lib.baseboard_fab2(sch_1):m_m_ma(10)" )
			)
			( signal "M_M_MA<11>"
				( objectStatus "@baseboard_fab2_lib.baseboard_fab2(sch_1):m_m_ma(11)" )
			)
			( signal "M_M_MA<12>"
				( objectStatus "@baseboard_fab2_lib.baseboard_fab2(sch_1):m_m_ma(12)" )
			)
			( signal "M_M_MA<13>"
				( objectStatus "@baseboard_fab2_lib.baseboard_fab2(sch_1):m_m_ma(13)" )
			)
			( signal "M_M_MA<14>"
				( objectStatus "@baseboard_fab2_lib.baseboard_fab2(sch_1):m_m_ma(14)" )
			)
			( signal "M_M_MA<15>"
				( objectStatus "@baseboard_fab2_lib.baseboard_fab2(sch_1):m_m_ma(15)" )
			)
			( signal "M_M_MA<16>"
				( objectStatus "@baseboard_fab2_lib.baseboard_fab2(sch_1):m_m_ma(16)" )
			)
			( signal "M_M_MA<17>"
				( objectStatus "@baseboard_fab2_lib.baseboard_fab2(sch_1):m_m_ma(17)" )
			)
			( signal "M_M_ODT<0>"
				( objectStatus "@baseboard_fab2_lib.baseboard_fab2(sch_1):m_m_odt(0)" )
			)
			( signal "M_M_ODT<1>"
				( objectStatus "@baseboard_fab2_lib.baseboard_fab2(sch_1):m_m_odt(1)" )
			)
			( signal "M_M_ODT<2>"
				( objectStatus "@baseboard_fab2_lib.baseboard_fab2(sch_1):m_m_odt(2)" )
			)
			( signal "M_M_ODT<3>"
				( objectStatus "@baseboard_fab2_lib.baseboard_fab2(sch_1):m_m_odt(3)" )
			)
			( signal "M_M_PAR"
				( objectStatus "@baseboard_fab2_lib.baseboard_fab2(sch_1):m_m_par" )
			)
			( signal "CLK_100M_CPU1_PE_REFCLK_DN"
				( objectStatus "@baseboard_fab2_lib.baseboard_fab2(sch_1):clk_100m_cpu1_pe_refclk_dn" )
			)
			( signal "CLK_100M_CPU1_PE_REFCLK_DP"
				( objectStatus "@baseboard_fab2_lib.baseboard_fab2(sch_1):clk_100m_cpu1_pe_refclk_dp" )
			)
			( signal "CLK_156M_OSC_CPU1_HFI_DN"
				( objectStatus "@baseboard_fab2_lib.baseboard_fab2(sch_1):clk_156m_osc_cpu1_hfi_dn" )
			)
			( signal "CLK_156M_OSC_CPU1_HFI_DP"
				( objectStatus "@baseboard_fab2_lib.baseboard_fab2(sch_1):clk_156m_osc_cpu1_hfi_dp" )
			)
			( signal "JTAG_MCP_CPU1_TDI"
				( objectStatus "@baseboard_fab2_lib.baseboard_fab2(sch_1):jtag_mcp_cpu1_tdi" )
			)
			( signal "JTAG_MCP_CPU1_TDO"
				( objectStatus "@baseboard_fab2_lib.baseboard_fab2(sch_1):jtag_mcp_cpu1_tdo" )
			)
			( signal "RST_CD_CPU1_POR_N"
				( objectStatus "@baseboard_fab2_lib.baseboard_fab2(sch_1):rst_cd_cpu1_por_n" )
			)
			( signal "TP_CD_HFI1_CPU1_I2CDAT"
				( objectStatus "@baseboard_fab2_lib.baseboard_fab2(sch_1):tp_cd_hfi1_cpu1_i2cdat" )
			)
			( signal "TP_CD_HFI1_CPU1_I2CLK"
				( objectStatus "@baseboard_fab2_lib.baseboard_fab2(sch_1):tp_cd_hfi1_cpu1_i2clk" )
			)
			( signal "TP_CD_HFI1_CPU1_INT_N"
				( objectStatus "@baseboard_fab2_lib.baseboard_fab2(sch_1):tp_cd_hfi1_cpu1_int_n" )
			)
			( signal "TP_CD_HFI1_CPU1_LED_N"
				( objectStatus "@baseboard_fab2_lib.baseboard_fab2(sch_1):tp_cd_hfi1_cpu1_led_n" )
			)
			( signal "TP_CD_HFI1_CPU1_MODPRST_N"
				( objectStatus "@baseboard_fab2_lib.baseboard_fab2(sch_1):tp_cd_hfi1_cpu1_modprst_n" )
			)
			( signal "TP_CD_HFI1_CPU1_RESET_N"
				( objectStatus "@baseboard_fab2_lib.baseboard_fab2(sch_1):tp_cd_hfi1_cpu1_reset_n" )
			)
			( signal "TP_CPU1_DMI_RX_DN0"
				( objectStatus "@baseboard_fab2_lib.baseboard_fab2(sch_1):tp_cpu1_dmi_rx_dn0" )
			)
			( signal "TP_CPU1_DMI_RX_DN1"
				( objectStatus "@baseboard_fab2_lib.baseboard_fab2(sch_1):tp_cpu1_dmi_rx_dn1" )
			)
			( signal "TP_CPU1_DMI_RX_DN2"
				( objectStatus "@baseboard_fab2_lib.baseboard_fab2(sch_1):tp_cpu1_dmi_rx_dn2" )
			)
			( signal "TP_CPU1_DMI_RX_DN3"
				( objectStatus "@baseboard_fab2_lib.baseboard_fab2(sch_1):tp_cpu1_dmi_rx_dn3" )
			)
			( signal "TP_CPU1_DMI_RX_DP0"
				( objectStatus "@baseboard_fab2_lib.baseboard_fab2(sch_1):tp_cpu1_dmi_rx_dp0" )
			)
			( signal "TP_CPU1_DMI_RX_DP1"
				( objectStatus "@baseboard_fab2_lib.baseboard_fab2(sch_1):tp_cpu1_dmi_rx_dp1" )
			)
			( signal "TP_CPU1_DMI_RX_DP2"
				( objectStatus "@baseboard_fab2_lib.baseboard_fab2(sch_1):tp_cpu1_dmi_rx_dp2" )
			)
			( signal "TP_CPU1_DMI_RX_DP3"
				( objectStatus "@baseboard_fab2_lib.baseboard_fab2(sch_1):tp_cpu1_dmi_rx_dp3" )
			)
			( signal "TP_CPU1_DMI_TX_DN0"
				( objectStatus "@baseboard_fab2_lib.baseboard_fab2(sch_1):tp_cpu1_dmi_tx_dn0" )
			)
			( signal "TP_CPU1_DMI_TX_DN1"
				( objectStatus "@baseboard_fab2_lib.baseboard_fab2(sch_1):tp_cpu1_dmi_tx_dn1" )
			)
			( signal "TP_CPU1_DMI_TX_DN2"
				( objectStatus "@baseboard_fab2_lib.baseboard_fab2(sch_1):tp_cpu1_dmi_tx_dn2" )
			)
			( signal "TP_CPU1_DMI_TX_DN3"
				( objectStatus "@baseboard_fab2_lib.baseboard_fab2(sch_1):tp_cpu1_dmi_tx_dn3" )
			)
			( signal "TP_CPU1_DMI_TX_DP0"
				( objectStatus "@baseboard_fab2_lib.baseboard_fab2(sch_1):tp_cpu1_dmi_tx_dp0" )
			)
			( signal "TP_CPU1_DMI_TX_DP1"
				( objectStatus "@baseboard_fab2_lib.baseboard_fab2(sch_1):tp_cpu1_dmi_tx_dp1" )
			)
			( signal "TP_CPU1_DMI_TX_DP2"
				( objectStatus "@baseboard_fab2_lib.baseboard_fab2(sch_1):tp_cpu1_dmi_tx_dp2" )
			)
			( signal "TP_CPU1_DMI_TX_DP3"
				( objectStatus "@baseboard_fab2_lib.baseboard_fab2(sch_1):tp_cpu1_dmi_tx_dp3" )
			)
			( signal "TP_CPU1_RSVD_172"
				( objectStatus "@baseboard_fab2_lib.baseboard_fab2(sch_1):tp_cpu1_rsvd_172" )
			)
			( signal "TP_CPU1_RSVD_173"
				( objectStatus "@baseboard_fab2_lib.baseboard_fab2(sch_1):tp_cpu1_rsvd_173" )
			)
			( signal "TP_CPU1_RSVD_174"
				( objectStatus "@baseboard_fab2_lib.baseboard_fab2(sch_1):tp_cpu1_rsvd_174" )
			)
			( signal "TP_CPU1_RSVD_175"
				( objectStatus "@baseboard_fab2_lib.baseboard_fab2(sch_1):tp_cpu1_rsvd_175" )
			)
			( signal "TP_CPU1_RSVD_176"
				( objectStatus "@baseboard_fab2_lib.baseboard_fab2(sch_1):tp_cpu1_rsvd_176" )
			)
			( signal "TP_CPU1_RSVD_177"
				( objectStatus "@baseboard_fab2_lib.baseboard_fab2(sch_1):tp_cpu1_rsvd_177" )
			)
			( signal "TP_CPU1_RSVD_178"
				( objectStatus "@baseboard_fab2_lib.baseboard_fab2(sch_1):tp_cpu1_rsvd_178" )
			)
			( signal "TP_CPU1_RSVD_179"
				( objectStatus "@baseboard_fab2_lib.baseboard_fab2(sch_1):tp_cpu1_rsvd_179" )
			)
			( signal "TP_CPU1_RSVD_180"
				( objectStatus "@baseboard_fab2_lib.baseboard_fab2(sch_1):tp_cpu1_rsvd_180" )
			)
			( signal "TP_CPU1_RSVD_181"
				( objectStatus "@baseboard_fab2_lib.baseboard_fab2(sch_1):tp_cpu1_rsvd_181" )
			)
			( signal "TP_CPU1_RSVD_182"
				( objectStatus "@baseboard_fab2_lib.baseboard_fab2(sch_1):tp_cpu1_rsvd_182" )
			)
			( signal "TP_CPU1_RSVD_183"
				( objectStatus "@baseboard_fab2_lib.baseboard_fab2(sch_1):tp_cpu1_rsvd_183" )
			)
			( signal "TP_CPU1_RSVD_184"
				( objectStatus "@baseboard_fab2_lib.baseboard_fab2(sch_1):tp_cpu1_rsvd_184" )
			)
			( signal "TP_CPU1_RSVD_186"
				( objectStatus "@baseboard_fab2_lib.baseboard_fab2(sch_1):tp_cpu1_rsvd_186" )
			)
			( signal "TP_CPU1_RSVD_189"
				( objectStatus "@baseboard_fab2_lib.baseboard_fab2(sch_1):tp_cpu1_rsvd_189" )
			)
			( signal "TP_CPU1_RSVD_190"
				( objectStatus "@baseboard_fab2_lib.baseboard_fab2(sch_1):tp_cpu1_rsvd_190" )
			)
			( signal "TP_FM_CPU1_CD_HFI0_MODPRST_N"
				( objectStatus "@baseboard_fab2_lib.baseboard_fab2(sch_1):tp_fm_cpu1_cd_hfi0_modprst_n" )
			)
			( signal "TP_IRQ_CPU1_CD_HFI0_N"
				( objectStatus "@baseboard_fab2_lib.baseboard_fab2(sch_1):tp_irq_cpu1_cd_hfi0_n" )
			)
			( signal "TP_LED_CPU1_CD_HFI0_N"
				( objectStatus "@baseboard_fab2_lib.baseboard_fab2(sch_1):tp_led_cpu1_cd_hfi0_n" )
			)
			( signal "TP_RST_CPU1_CD_HFI0_N"
				( objectStatus "@baseboard_fab2_lib.baseboard_fab2(sch_1):tp_rst_cpu1_cd_hfi0_n" )
			)
			( signal "TP_SMB_CPU1_CD_HFI0_I2CCLK"
				( objectStatus "@baseboard_fab2_lib.baseboard_fab2(sch_1):tp_smb_cpu1_cd_hfi0_i2cclk" )
			)
			( signal "TP_SMB_CPU1_CD_HFI0_I2CDAT"
				( objectStatus "@baseboard_fab2_lib.baseboard_fab2(sch_1):tp_smb_cpu1_cd_hfi0_i2cdat" )
			)
			( signal "TP_P3E_CPU1_PE1_MP_RXN<0>"
				( objectStatus "@baseboard_fab2_lib.baseboard_fab2(sch_1):tp_p3e_cpu1_pe1_mp_rxn(0)" )
			)
			( signal "TP_P3E_CPU1_PE1_MP_RXN<1>"
				( objectStatus "@baseboard_fab2_lib.baseboard_fab2(sch_1):tp_p3e_cpu1_pe1_mp_rxn(1)" )
			)
			( signal "TP_P3E_CPU1_PE1_MP_RXN<2>"
				( objectStatus "@baseboard_fab2_lib.baseboard_fab2(sch_1):tp_p3e_cpu1_pe1_mp_rxn(2)" )
			)
			( signal "TP_P3E_CPU1_PE1_MP_RXN<3>"
				( objectStatus "@baseboard_fab2_lib.baseboard_fab2(sch_1):tp_p3e_cpu1_pe1_mp_rxn(3)" )
			)
			( signal "TP_P3E_CPU1_PE1_MP_RXN<4>"
				( objectStatus "@baseboard_fab2_lib.baseboard_fab2(sch_1):tp_p3e_cpu1_pe1_mp_rxn(4)" )
			)
			( signal "TP_P3E_CPU1_PE1_MP_RXN<5>"
				( objectStatus "@baseboard_fab2_lib.baseboard_fab2(sch_1):tp_p3e_cpu1_pe1_mp_rxn(5)" )
			)
			( signal "TP_P3E_CPU1_PE1_MP_RXN<6>"
				( objectStatus "@baseboard_fab2_lib.baseboard_fab2(sch_1):tp_p3e_cpu1_pe1_mp_rxn(6)" )
			)
			( signal "TP_P3E_CPU1_PE1_MP_RXN<7>"
				( objectStatus "@baseboard_fab2_lib.baseboard_fab2(sch_1):tp_p3e_cpu1_pe1_mp_rxn(7)" )
			)
			( signal "TP_P3E_CPU1_PE1_MP_RXP<0>"
				( objectStatus "@baseboard_fab2_lib.baseboard_fab2(sch_1):tp_p3e_cpu1_pe1_mp_rxp(0)" )
			)
			( signal "TP_P3E_CPU1_PE1_MP_RXP<1>"
				( objectStatus "@baseboard_fab2_lib.baseboard_fab2(sch_1):tp_p3e_cpu1_pe1_mp_rxp(1)" )
			)
			( signal "TP_P3E_CPU1_PE1_MP_RXP<2>"
				( objectStatus "@baseboard_fab2_lib.baseboard_fab2(sch_1):tp_p3e_cpu1_pe1_mp_rxp(2)" )
			)
			( signal "TP_P3E_CPU1_PE1_MP_RXP<3>"
				( objectStatus "@baseboard_fab2_lib.baseboard_fab2(sch_1):tp_p3e_cpu1_pe1_mp_rxp(3)" )
			)
			( signal "TP_P3E_CPU1_PE1_MP_RXP<4>"
				( objectStatus "@baseboard_fab2_lib.baseboard_fab2(sch_1):tp_p3e_cpu1_pe1_mp_rxp(4)" )
			)
			( signal "TP_P3E_CPU1_PE1_MP_RXP<5>"
				( objectStatus "@baseboard_fab2_lib.baseboard_fab2(sch_1):tp_p3e_cpu1_pe1_mp_rxp(5)" )
			)
			( signal "TP_P3E_CPU1_PE1_MP_RXP<6>"
				( objectStatus "@baseboard_fab2_lib.baseboard_fab2(sch_1):tp_p3e_cpu1_pe1_mp_rxp(6)" )
			)
			( signal "TP_P3E_CPU1_PE1_MP_RXP<7>"
				( objectStatus "@baseboard_fab2_lib.baseboard_fab2(sch_1):tp_p3e_cpu1_pe1_mp_rxp(7)" )
			)
			( signal "TP_P3E_CPU1_PE1_MP_TXN<0>"
				( objectStatus "@baseboard_fab2_lib.baseboard_fab2(sch_1):tp_p3e_cpu1_pe1_mp_txn(0)" )
			)
			( signal "TP_P3E_CPU1_PE1_MP_TXN<1>"
				( objectStatus "@baseboard_fab2_lib.baseboard_fab2(sch_1):tp_p3e_cpu1_pe1_mp_txn(1)" )
			)
			( signal "TP_P3E_CPU1_PE1_MP_TXN<2>"
				( objectStatus "@baseboard_fab2_lib.baseboard_fab2(sch_1):tp_p3e_cpu1_pe1_mp_txn(2)" )
			)
			( signal "TP_P3E_CPU1_PE1_MP_TXN<3>"
				( objectStatus "@baseboard_fab2_lib.baseboard_fab2(sch_1):tp_p3e_cpu1_pe1_mp_txn(3)" )
			)
			( signal "TP_P3E_CPU1_PE1_MP_TXN<4>"
				( objectStatus "@baseboard_fab2_lib.baseboard_fab2(sch_1):tp_p3e_cpu1_pe1_mp_txn(4)" )
			)
			( signal "TP_P3E_CPU1_PE1_MP_TXN<5>"
				( objectStatus "@baseboard_fab2_lib.baseboard_fab2(sch_1):tp_p3e_cpu1_pe1_mp_txn(5)" )
			)
			( signal "TP_P3E_CPU1_PE1_MP_TXN<6>"
				( objectStatus "@baseboard_fab2_lib.baseboard_fab2(sch_1):tp_p3e_cpu1_pe1_mp_txn(6)" )
			)
			( signal "TP_P3E_CPU1_PE1_MP_TXN<7>"
				( objectStatus "@baseboard_fab2_lib.baseboard_fab2(sch_1):tp_p3e_cpu1_pe1_mp_txn(7)" )
			)
			( signal "TP_P3E_CPU1_PE1_MP_TXP<0>"
				( objectStatus "@baseboard_fab2_lib.baseboard_fab2(sch_1):tp_p3e_cpu1_pe1_mp_txp(0)" )
			)
			( signal "TP_P3E_CPU1_PE1_MP_TXP<1>"
				( objectStatus "@baseboard_fab2_lib.baseboard_fab2(sch_1):tp_p3e_cpu1_pe1_mp_txp(1)" )
			)
			( signal "TP_P3E_CPU1_PE1_MP_TXP<2>"
				( objectStatus "@baseboard_fab2_lib.baseboard_fab2(sch_1):tp_p3e_cpu1_pe1_mp_txp(2)" )
			)
			( signal "TP_P3E_CPU1_PE1_MP_TXP<3>"
				( objectStatus "@baseboard_fab2_lib.baseboard_fab2(sch_1):tp_p3e_cpu1_pe1_mp_txp(3)" )
			)
			( signal "TP_P3E_CPU1_PE1_MP_TXP<4>"
				( objectStatus "@baseboard_fab2_lib.baseboard_fab2(sch_1):tp_p3e_cpu1_pe1_mp_txp(4)" )
			)
			( signal "TP_P3E_CPU1_PE1_MP_TXP<5>"
				( objectStatus "@baseboard_fab2_lib.baseboard_fab2(sch_1):tp_p3e_cpu1_pe1_mp_txp(5)" )
			)
			( signal "TP_P3E_CPU1_PE1_MP_TXP<6>"
				( objectStatus "@baseboard_fab2_lib.baseboard_fab2(sch_1):tp_p3e_cpu1_pe1_mp_txp(6)" )
			)
			( signal "TP_P3E_CPU1_PE1_MP_TXP<7>"
				( objectStatus "@baseboard_fab2_lib.baseboard_fab2(sch_1):tp_p3e_cpu1_pe1_mp_txp(7)" )
			)
			( signal "TP_P3E_CPU1_PE1_RSR3_RXN<8>"
				( objectStatus "@baseboard_fab2_lib.baseboard_fab2(sch_1):tp_p3e_cpu1_pe1_rsr3_rxn(8)" )
			)
			( signal "TP_P3E_CPU1_PE1_RSR3_RXN<9>"
				( objectStatus "@baseboard_fab2_lib.baseboard_fab2(sch_1):tp_p3e_cpu1_pe1_rsr3_rxn(9)" )
			)
			( signal "TP_P3E_CPU1_PE1_RSR3_RXN<10>"
				( objectStatus "@baseboard_fab2_lib.baseboard_fab2(sch_1):tp_p3e_cpu1_pe1_rsr3_rxn(10)" )
			)
			( signal "TP_P3E_CPU1_PE1_RSR3_RXN<11>"
				( objectStatus "@baseboard_fab2_lib.baseboard_fab2(sch_1):tp_p3e_cpu1_pe1_rsr3_rxn(11)" )
			)
			( signal "TP_P3E_CPU1_PE1_RSR3_RXN<12>"
				( objectStatus "@baseboard_fab2_lib.baseboard_fab2(sch_1):tp_p3e_cpu1_pe1_rsr3_rxn(12)" )
			)
			( signal "TP_P3E_CPU1_PE1_RSR3_RXN<13>"
				( objectStatus "@baseboard_fab2_lib.baseboard_fab2(sch_1):tp_p3e_cpu1_pe1_rsr3_rxn(13)" )
			)
			( signal "TP_P3E_CPU1_PE1_RSR3_RXN<14>"
				( objectStatus "@baseboard_fab2_lib.baseboard_fab2(sch_1):tp_p3e_cpu1_pe1_rsr3_rxn(14)" )
			)
			( signal "TP_P3E_CPU1_PE1_RSR3_RXN<15>"
				( objectStatus "@baseboard_fab2_lib.baseboard_fab2(sch_1):tp_p3e_cpu1_pe1_rsr3_rxn(15)" )
			)
			( signal "TP_P3E_CPU1_PE1_RSR3_RXP<8>"
				( objectStatus "@baseboard_fab2_lib.baseboard_fab2(sch_1):tp_p3e_cpu1_pe1_rsr3_rxp(8)" )
			)
			( signal "TP_P3E_CPU1_PE1_RSR3_RXP<9>"
				( objectStatus "@baseboard_fab2_lib.baseboard_fab2(sch_1):tp_p3e_cpu1_pe1_rsr3_rxp(9)" )
			)
			( signal "TP_P3E_CPU1_PE1_RSR3_RXP<10>"
				( objectStatus "@baseboard_fab2_lib.baseboard_fab2(sch_1):tp_p3e_cpu1_pe1_rsr3_rxp(10)" )
			)
			( signal "TP_P3E_CPU1_PE1_RSR3_RXP<11>"
				( objectStatus "@baseboard_fab2_lib.baseboard_fab2(sch_1):tp_p3e_cpu1_pe1_rsr3_rxp(11)" )
			)
			( signal "TP_P3E_CPU1_PE1_RSR3_RXP<12>"
				( objectStatus "@baseboard_fab2_lib.baseboard_fab2(sch_1):tp_p3e_cpu1_pe1_rsr3_rxp(12)" )
			)
			( signal "TP_P3E_CPU1_PE1_RSR3_RXP<13>"
				( objectStatus "@baseboard_fab2_lib.baseboard_fab2(sch_1):tp_p3e_cpu1_pe1_rsr3_rxp(13)" )
			)
			( signal "TP_P3E_CPU1_PE1_RSR3_RXP<14>"
				( objectStatus "@baseboard_fab2_lib.baseboard_fab2(sch_1):tp_p3e_cpu1_pe1_rsr3_rxp(14)" )
			)
			( signal "TP_P3E_CPU1_PE1_RSR3_RXP<15>"
				( objectStatus "@baseboard_fab2_lib.baseboard_fab2(sch_1):tp_p3e_cpu1_pe1_rsr3_rxp(15)" )
			)
			( signal "TP_P3E_CPU1_PE1_RSR3_TXN<8>"
				( objectStatus "@baseboard_fab2_lib.baseboard_fab2(sch_1):tp_p3e_cpu1_pe1_rsr3_txn(8)" )
			)
			( signal "TP_P3E_CPU1_PE1_RSR3_TXN<9>"
				( objectStatus "@baseboard_fab2_lib.baseboard_fab2(sch_1):tp_p3e_cpu1_pe1_rsr3_txn(9)" )
			)
			( signal "TP_P3E_CPU1_PE1_RSR3_TXN<10>"
				( objectStatus "@baseboard_fab2_lib.baseboard_fab2(sch_1):tp_p3e_cpu1_pe1_rsr3_txn(10)" )
			)
			( signal "TP_P3E_CPU1_PE1_RSR3_TXN<11>"
				( objectStatus "@baseboard_fab2_lib.baseboard_fab2(sch_1):tp_p3e_cpu1_pe1_rsr3_txn(11)" )
			)
			( signal "TP_P3E_CPU1_PE1_RSR3_TXN<12>"
				( objectStatus "@baseboard_fab2_lib.baseboard_fab2(sch_1):tp_p3e_cpu1_pe1_rsr3_txn(12)" )
			)
			( signal "TP_P3E_CPU1_PE1_RSR3_TXN<13>"
				( objectStatus "@baseboard_fab2_lib.baseboard_fab2(sch_1):tp_p3e_cpu1_pe1_rsr3_txn(13)" )
			)
			( signal "TP_P3E_CPU1_PE1_RSR3_TXN<14>"
				( objectStatus "@baseboard_fab2_lib.baseboard_fab2(sch_1):tp_p3e_cpu1_pe1_rsr3_txn(14)" )
			)
			( signal "TP_P3E_CPU1_PE1_RSR3_TXN<15>"
				( objectStatus "@baseboard_fab2_lib.baseboard_fab2(sch_1):tp_p3e_cpu1_pe1_rsr3_txn(15)" )
			)
			( signal "TP_P3E_CPU1_PE1_RSR3_TXP<8>"
				( objectStatus "@baseboard_fab2_lib.baseboard_fab2(sch_1):tp_p3e_cpu1_pe1_rsr3_txp(8)" )
			)
			( signal "TP_P3E_CPU1_PE1_RSR3_TXP<9>"
				( objectStatus "@baseboard_fab2_lib.baseboard_fab2(sch_1):tp_p3e_cpu1_pe1_rsr3_txp(9)" )
			)
			( signal "TP_P3E_CPU1_PE1_RSR3_TXP<10>"
				( objectStatus "@baseboard_fab2_lib.baseboard_fab2(sch_1):tp_p3e_cpu1_pe1_rsr3_txp(10)" )
			)
			( signal "TP_P3E_CPU1_PE1_RSR3_TXP<11>"
				( objectStatus "@baseboard_fab2_lib.baseboard_fab2(sch_1):tp_p3e_cpu1_pe1_rsr3_txp(11)" )
			)
			( signal "TP_P3E_CPU1_PE1_RSR3_TXP<12>"
				( objectStatus "@baseboard_fab2_lib.baseboard_fab2(sch_1):tp_p3e_cpu1_pe1_rsr3_txp(12)" )
			)
			( signal "TP_P3E_CPU1_PE1_RSR3_TXP<13>"
				( objectStatus "@baseboard_fab2_lib.baseboard_fab2(sch_1):tp_p3e_cpu1_pe1_rsr3_txp(13)" )
			)
			( signal "TP_P3E_CPU1_PE1_RSR3_TXP<14>"
				( objectStatus "@baseboard_fab2_lib.baseboard_fab2(sch_1):tp_p3e_cpu1_pe1_rsr3_txp(14)" )
			)
			( signal "TP_P3E_CPU1_PE1_RSR3_TXP<15>"
				( objectStatus "@baseboard_fab2_lib.baseboard_fab2(sch_1):tp_p3e_cpu1_pe1_rsr3_txp(15)" )
			)
			( signal "TP_P3E_CPU1_PE2_RSR_RXN<0>"
				( objectStatus "@baseboard_fab2_lib.baseboard_fab2(sch_1):tp_p3e_cpu1_pe2_rsr_rxn(0)" )
			)
			( signal "TP_P3E_CPU1_PE2_RSR_RXN<1>"
				( objectStatus "@baseboard_fab2_lib.baseboard_fab2(sch_1):tp_p3e_cpu1_pe2_rsr_rxn(1)" )
			)
			( signal "TP_P3E_CPU1_PE2_RSR_RXN<2>"
				( objectStatus "@baseboard_fab2_lib.baseboard_fab2(sch_1):tp_p3e_cpu1_pe2_rsr_rxn(2)" )
			)
			( signal "TP_P3E_CPU1_PE2_RSR_RXN<3>"
				( objectStatus "@baseboard_fab2_lib.baseboard_fab2(sch_1):tp_p3e_cpu1_pe2_rsr_rxn(3)" )
			)
			( signal "TP_P3E_CPU1_PE2_RSR_RXN<4>"
				( objectStatus "@baseboard_fab2_lib.baseboard_fab2(sch_1):tp_p3e_cpu1_pe2_rsr_rxn(4)" )
			)
			( signal "TP_P3E_CPU1_PE2_RSR_RXN<5>"
				( objectStatus "@baseboard_fab2_lib.baseboard_fab2(sch_1):tp_p3e_cpu1_pe2_rsr_rxn(5)" )
			)
			( signal "TP_P3E_CPU1_PE2_RSR_RXN<6>"
				( objectStatus "@baseboard_fab2_lib.baseboard_fab2(sch_1):tp_p3e_cpu1_pe2_rsr_rxn(6)" )
			)
			( signal "TP_P3E_CPU1_PE2_RSR_RXN<7>"
				( objectStatus "@baseboard_fab2_lib.baseboard_fab2(sch_1):tp_p3e_cpu1_pe2_rsr_rxn(7)" )
			)
			( signal "TP_P3E_CPU1_PE2_RSR_RXN<8>"
				( objectStatus "@baseboard_fab2_lib.baseboard_fab2(sch_1):tp_p3e_cpu1_pe2_rsr_rxn(8)" )
			)
			( signal "TP_P3E_CPU1_PE2_RSR_RXN<9>"
				( objectStatus "@baseboard_fab2_lib.baseboard_fab2(sch_1):tp_p3e_cpu1_pe2_rsr_rxn(9)" )
			)
			( signal "TP_P3E_CPU1_PE2_RSR_RXN<10>"
				( objectStatus "@baseboard_fab2_lib.baseboard_fab2(sch_1):tp_p3e_cpu1_pe2_rsr_rxn(10)" )
			)
			( signal "TP_P3E_CPU1_PE2_RSR_RXN<11>"
				( objectStatus "@baseboard_fab2_lib.baseboard_fab2(sch_1):tp_p3e_cpu1_pe2_rsr_rxn(11)" )
			)
			( signal "TP_P3E_CPU1_PE2_RSR_RXN<12>"
				( objectStatus "@baseboard_fab2_lib.baseboard_fab2(sch_1):tp_p3e_cpu1_pe2_rsr_rxn(12)" )
			)
			( signal "TP_P3E_CPU1_PE2_RSR_RXN<13>"
				( objectStatus "@baseboard_fab2_lib.baseboard_fab2(sch_1):tp_p3e_cpu1_pe2_rsr_rxn(13)" )
			)
			( signal "TP_P3E_CPU1_PE2_RSR_RXN<14>"
				( objectStatus "@baseboard_fab2_lib.baseboard_fab2(sch_1):tp_p3e_cpu1_pe2_rsr_rxn(14)" )
			)
			( signal "TP_P3E_CPU1_PE2_RSR_RXN<15>"
				( objectStatus "@baseboard_fab2_lib.baseboard_fab2(sch_1):tp_p3e_cpu1_pe2_rsr_rxn(15)" )
			)
			( signal "TP_P3E_CPU1_PE2_RSR_RXP<0>"
				( objectStatus "@baseboard_fab2_lib.baseboard_fab2(sch_1):tp_p3e_cpu1_pe2_rsr_rxp(0)" )
			)
			( signal "TP_P3E_CPU1_PE2_RSR_RXP<1>"
				( objectStatus "@baseboard_fab2_lib.baseboard_fab2(sch_1):tp_p3e_cpu1_pe2_rsr_rxp(1)" )
			)
			( signal "TP_P3E_CPU1_PE2_RSR_RXP<2>"
				( objectStatus "@baseboard_fab2_lib.baseboard_fab2(sch_1):tp_p3e_cpu1_pe2_rsr_rxp(2)" )
			)
			( signal "TP_P3E_CPU1_PE2_RSR_RXP<3>"
				( objectStatus "@baseboard_fab2_lib.baseboard_fab2(sch_1):tp_p3e_cpu1_pe2_rsr_rxp(3)" )
			)
			( signal "TP_P3E_CPU1_PE2_RSR_RXP<4>"
				( objectStatus "@baseboard_fab2_lib.baseboard_fab2(sch_1):tp_p3e_cpu1_pe2_rsr_rxp(4)" )
			)
			( signal "TP_P3E_CPU1_PE2_RSR_RXP<5>"
				( objectStatus "@baseboard_fab2_lib.baseboard_fab2(sch_1):tp_p3e_cpu1_pe2_rsr_rxp(5)" )
			)
			( signal "TP_P3E_CPU1_PE2_RSR_RXP<6>"
				( objectStatus "@baseboard_fab2_lib.baseboard_fab2(sch_1):tp_p3e_cpu1_pe2_rsr_rxp(6)" )
			)
			( signal "TP_P3E_CPU1_PE2_RSR_RXP<7>"
				( objectStatus "@baseboard_fab2_lib.baseboard_fab2(sch_1):tp_p3e_cpu1_pe2_rsr_rxp(7)" )
			)
			( signal "TP_P3E_CPU1_PE2_RSR_RXP<8>"
				( objectStatus "@baseboard_fab2_lib.baseboard_fab2(sch_1):tp_p3e_cpu1_pe2_rsr_rxp(8)" )
			)
			( signal "TP_P3E_CPU1_PE2_RSR_RXP<9>"
				( objectStatus "@baseboard_fab2_lib.baseboard_fab2(sch_1):tp_p3e_cpu1_pe2_rsr_rxp(9)" )
			)
			( signal "TP_P3E_CPU1_PE2_RSR_RXP<10>"
				( objectStatus "@baseboard_fab2_lib.baseboard_fab2(sch_1):tp_p3e_cpu1_pe2_rsr_rxp(10)" )
			)
			( signal "TP_P3E_CPU1_PE2_RSR_RXP<11>"
				( objectStatus "@baseboard_fab2_lib.baseboard_fab2(sch_1):tp_p3e_cpu1_pe2_rsr_rxp(11)" )
			)
			( signal "TP_P3E_CPU1_PE2_RSR_RXP<12>"
				( objectStatus "@baseboard_fab2_lib.baseboard_fab2(sch_1):tp_p3e_cpu1_pe2_rsr_rxp(12)" )
			)
			( signal "TP_P3E_CPU1_PE2_RSR_RXP<13>"
				( objectStatus "@baseboard_fab2_lib.baseboard_fab2(sch_1):tp_p3e_cpu1_pe2_rsr_rxp(13)" )
			)
			( signal "TP_P3E_CPU1_PE2_RSR_RXP<14>"
				( objectStatus "@baseboard_fab2_lib.baseboard_fab2(sch_1):tp_p3e_cpu1_pe2_rsr_rxp(14)" )
			)
			( signal "TP_P3E_CPU1_PE2_RSR_RXP<15>"
				( objectStatus "@baseboard_fab2_lib.baseboard_fab2(sch_1):tp_p3e_cpu1_pe2_rsr_rxp(15)" )
			)
			( signal "TP_P3E_CPU1_PE2_RSR_TXN<0>"
				( objectStatus "@baseboard_fab2_lib.baseboard_fab2(sch_1):tp_p3e_cpu1_pe2_rsr_txn(0)" )
			)
			( signal "TP_P3E_CPU1_PE2_RSR_TXN<1>"
				( objectStatus "@baseboard_fab2_lib.baseboard_fab2(sch_1):tp_p3e_cpu1_pe2_rsr_txn(1)" )
			)
			( signal "TP_P3E_CPU1_PE2_RSR_TXN<2>"
				( objectStatus "@baseboard_fab2_lib.baseboard_fab2(sch_1):tp_p3e_cpu1_pe2_rsr_txn(2)" )
			)
			( signal "TP_P3E_CPU1_PE2_RSR_TXN<3>"
				( objectStatus "@baseboard_fab2_lib.baseboard_fab2(sch_1):tp_p3e_cpu1_pe2_rsr_txn(3)" )
			)
			( signal "TP_P3E_CPU1_PE2_RSR_TXN<4>"
				( objectStatus "@baseboard_fab2_lib.baseboard_fab2(sch_1):tp_p3e_cpu1_pe2_rsr_txn(4)" )
			)
			( signal "TP_P3E_CPU1_PE2_RSR_TXN<5>"
				( objectStatus "@baseboard_fab2_lib.baseboard_fab2(sch_1):tp_p3e_cpu1_pe2_rsr_txn(5)" )
			)
			( signal "TP_P3E_CPU1_PE2_RSR_TXN<6>"
				( objectStatus "@baseboard_fab2_lib.baseboard_fab2(sch_1):tp_p3e_cpu1_pe2_rsr_txn(6)" )
			)
			( signal "TP_P3E_CPU1_PE2_RSR_TXN<7>"
				( objectStatus "@baseboard_fab2_lib.baseboard_fab2(sch_1):tp_p3e_cpu1_pe2_rsr_txn(7)" )
			)
			( signal "TP_P3E_CPU1_PE2_RSR_TXN<8>"
				( objectStatus "@baseboard_fab2_lib.baseboard_fab2(sch_1):tp_p3e_cpu1_pe2_rsr_txn(8)" )
			)
			( signal "TP_P3E_CPU1_PE2_RSR_TXN<9>"
				( objectStatus "@baseboard_fab2_lib.baseboard_fab2(sch_1):tp_p3e_cpu1_pe2_rsr_txn(9)" )
			)
			( signal "TP_P3E_CPU1_PE2_RSR_TXN<10>"
				( objectStatus "@baseboard_fab2_lib.baseboard_fab2(sch_1):tp_p3e_cpu1_pe2_rsr_txn(10)" )
			)
			( signal "TP_P3E_CPU1_PE2_RSR_TXN<11>"
				( objectStatus "@baseboard_fab2_lib.baseboard_fab2(sch_1):tp_p3e_cpu1_pe2_rsr_txn(11)" )
			)
			( signal "TP_P3E_CPU1_PE2_RSR_TXN<12>"
				( objectStatus "@baseboard_fab2_lib.baseboard_fab2(sch_1):tp_p3e_cpu1_pe2_rsr_txn(12)" )
			)
			( signal "TP_P3E_CPU1_PE2_RSR_TXN<13>"
				( objectStatus "@baseboard_fab2_lib.baseboard_fab2(sch_1):tp_p3e_cpu1_pe2_rsr_txn(13)" )
			)
			( signal "TP_P3E_CPU1_PE2_RSR_TXN<14>"
				( objectStatus "@baseboard_fab2_lib.baseboard_fab2(sch_1):tp_p3e_cpu1_pe2_rsr_txn(14)" )
			)
			( signal "TP_P3E_CPU1_PE2_RSR_TXN<15>"
				( objectStatus "@baseboard_fab2_lib.baseboard_fab2(sch_1):tp_p3e_cpu1_pe2_rsr_txn(15)" )
			)
			( signal "TP_P3E_CPU1_PE2_RSR_TXP<0>"
				( objectStatus "@baseboard_fab2_lib.baseboard_fab2(sch_1):tp_p3e_cpu1_pe2_rsr_txp(0)" )
			)
			( signal "TP_P3E_CPU1_PE2_RSR_TXP<1>"
				( objectStatus "@baseboard_fab2_lib.baseboard_fab2(sch_1):tp_p3e_cpu1_pe2_rsr_txp(1)" )
			)
			( signal "TP_P3E_CPU1_PE2_RSR_TXP<2>"
				( objectStatus "@baseboard_fab2_lib.baseboard_fab2(sch_1):tp_p3e_cpu1_pe2_rsr_txp(2)" )
			)
			( signal "TP_P3E_CPU1_PE2_RSR_TXP<3>"
				( objectStatus "@baseboard_fab2_lib.baseboard_fab2(sch_1):tp_p3e_cpu1_pe2_rsr_txp(3)" )
			)
			( signal "TP_P3E_CPU1_PE2_RSR_TXP<4>"
				( objectStatus "@baseboard_fab2_lib.baseboard_fab2(sch_1):tp_p3e_cpu1_pe2_rsr_txp(4)" )
			)
			( signal "TP_P3E_CPU1_PE2_RSR_TXP<5>"
				( objectStatus "@baseboard_fab2_lib.baseboard_fab2(sch_1):tp_p3e_cpu1_pe2_rsr_txp(5)" )
			)
			( signal "TP_P3E_CPU1_PE2_RSR_TXP<6>"
				( objectStatus "@baseboard_fab2_lib.baseboard_fab2(sch_1):tp_p3e_cpu1_pe2_rsr_txp(6)" )
			)
			( signal "TP_P3E_CPU1_PE2_RSR_TXP<7>"
				( objectStatus "@baseboard_fab2_lib.baseboard_fab2(sch_1):tp_p3e_cpu1_pe2_rsr_txp(7)" )
			)
			( signal "TP_P3E_CPU1_PE2_RSR_TXP<8>"
				( objectStatus "@baseboard_fab2_lib.baseboard_fab2(sch_1):tp_p3e_cpu1_pe2_rsr_txp(8)" )
			)
			( signal "TP_P3E_CPU1_PE2_RSR_TXP<9>"
				( objectStatus "@baseboard_fab2_lib.baseboard_fab2(sch_1):tp_p3e_cpu1_pe2_rsr_txp(9)" )
			)
			( signal "TP_P3E_CPU1_PE2_RSR_TXP<10>"
				( objectStatus "@baseboard_fab2_lib.baseboard_fab2(sch_1):tp_p3e_cpu1_pe2_rsr_txp(10)" )
			)
			( signal "TP_P3E_CPU1_PE2_RSR_TXP<11>"
				( objectStatus "@baseboard_fab2_lib.baseboard_fab2(sch_1):tp_p3e_cpu1_pe2_rsr_txp(11)" )
			)
			( signal "TP_P3E_CPU1_PE2_RSR_TXP<12>"
				( objectStatus "@baseboard_fab2_lib.baseboard_fab2(sch_1):tp_p3e_cpu1_pe2_rsr_txp(12)" )
			)
			( signal "TP_P3E_CPU1_PE2_RSR_TXP<13>"
				( objectStatus "@baseboard_fab2_lib.baseboard_fab2(sch_1):tp_p3e_cpu1_pe2_rsr_txp(13)" )
			)
			( signal "TP_P3E_CPU1_PE2_RSR_TXP<14>"
				( objectStatus "@baseboard_fab2_lib.baseboard_fab2(sch_1):tp_p3e_cpu1_pe2_rsr_txp(14)" )
			)
			( signal "TP_P3E_CPU1_PE2_RSR_TXP<15>"
				( objectStatus "@baseboard_fab2_lib.baseboard_fab2(sch_1):tp_p3e_cpu1_pe2_rsr_txp(15)" )
			)
			( signal "P3E_CPU1_PE3_MP_RXN<0>"
				( objectStatus "@baseboard_fab2_lib.baseboard_fab2(sch_1):p3e_cpu1_pe3_mp_rxn(0)" )
			)
			( signal "P3E_CPU1_PE3_MP_RXN<1>"
				( objectStatus "@baseboard_fab2_lib.baseboard_fab2(sch_1):p3e_cpu1_pe3_mp_rxn(1)" )
			)
			( signal "P3E_CPU1_PE3_MP_RXN<2>"
				( objectStatus "@baseboard_fab2_lib.baseboard_fab2(sch_1):p3e_cpu1_pe3_mp_rxn(2)" )
			)
			( signal "P3E_CPU1_PE3_MP_RXN<3>"
				( objectStatus "@baseboard_fab2_lib.baseboard_fab2(sch_1):p3e_cpu1_pe3_mp_rxn(3)" )
			)
			( signal "P3E_CPU1_PE3_MP_RXN<4>"
				( objectStatus "@baseboard_fab2_lib.baseboard_fab2(sch_1):p3e_cpu1_pe3_mp_rxn(4)" )
			)
			( signal "P3E_CPU1_PE3_MP_RXN<5>"
				( objectStatus "@baseboard_fab2_lib.baseboard_fab2(sch_1):p3e_cpu1_pe3_mp_rxn(5)" )
			)
			( signal "P3E_CPU1_PE3_MP_RXN<6>"
				( objectStatus "@baseboard_fab2_lib.baseboard_fab2(sch_1):p3e_cpu1_pe3_mp_rxn(6)" )
			)
			( signal "P3E_CPU1_PE3_MP_RXN<7>"
				( objectStatus "@baseboard_fab2_lib.baseboard_fab2(sch_1):p3e_cpu1_pe3_mp_rxn(7)" )
			)
			( signal "P3E_CPU1_PE3_MP_RXN<8>"
				( objectStatus "@baseboard_fab2_lib.baseboard_fab2(sch_1):p3e_cpu1_pe3_mp_rxn(8)" )
			)
			( signal "P3E_CPU1_PE3_MP_RXN<9>"
				( objectStatus "@baseboard_fab2_lib.baseboard_fab2(sch_1):p3e_cpu1_pe3_mp_rxn(9)" )
			)
			( signal "P3E_CPU1_PE3_MP_RXN<10>"
				( objectStatus "@baseboard_fab2_lib.baseboard_fab2(sch_1):p3e_cpu1_pe3_mp_rxn(10)" )
			)
			( signal "P3E_CPU1_PE3_MP_RXN<11>"
				( objectStatus "@baseboard_fab2_lib.baseboard_fab2(sch_1):p3e_cpu1_pe3_mp_rxn(11)" )
			)
			( signal "P3E_CPU1_PE3_MP_RXN<12>"
				( objectStatus "@baseboard_fab2_lib.baseboard_fab2(sch_1):p3e_cpu1_pe3_mp_rxn(12)" )
			)
			( signal "P3E_CPU1_PE3_MP_RXN<13>"
				( objectStatus "@baseboard_fab2_lib.baseboard_fab2(sch_1):p3e_cpu1_pe3_mp_rxn(13)" )
			)
			( signal "P3E_CPU1_PE3_MP_RXN<14>"
				( objectStatus "@baseboard_fab2_lib.baseboard_fab2(sch_1):p3e_cpu1_pe3_mp_rxn(14)" )
			)
			( signal "P3E_CPU1_PE3_MP_RXN<15>"
				( objectStatus "@baseboard_fab2_lib.baseboard_fab2(sch_1):p3e_cpu1_pe3_mp_rxn(15)" )
			)
			( signal "P3E_CPU1_PE3_MP_RXP<0>"
				( objectStatus "@baseboard_fab2_lib.baseboard_fab2(sch_1):p3e_cpu1_pe3_mp_rxp(0)" )
			)
			( signal "P3E_CPU1_PE3_MP_RXP<1>"
				( objectStatus "@baseboard_fab2_lib.baseboard_fab2(sch_1):p3e_cpu1_pe3_mp_rxp(1)" )
			)
			( signal "P3E_CPU1_PE3_MP_RXP<2>"
				( objectStatus "@baseboard_fab2_lib.baseboard_fab2(sch_1):p3e_cpu1_pe3_mp_rxp(2)" )
			)
			( signal "P3E_CPU1_PE3_MP_RXP<3>"
				( objectStatus "@baseboard_fab2_lib.baseboard_fab2(sch_1):p3e_cpu1_pe3_mp_rxp(3)" )
			)
			( signal "P3E_CPU1_PE3_MP_RXP<4>"
				( objectStatus "@baseboard_fab2_lib.baseboard_fab2(sch_1):p3e_cpu1_pe3_mp_rxp(4)" )
			)
			( signal "P3E_CPU1_PE3_MP_RXP<5>"
				( objectStatus "@baseboard_fab2_lib.baseboard_fab2(sch_1):p3e_cpu1_pe3_mp_rxp(5)" )
			)
			( signal "P3E_CPU1_PE3_MP_RXP<6>"
				( objectStatus "@baseboard_fab2_lib.baseboard_fab2(sch_1):p3e_cpu1_pe3_mp_rxp(6)" )
			)
			( signal "P3E_CPU1_PE3_MP_RXP<7>"
				( objectStatus "@baseboard_fab2_lib.baseboard_fab2(sch_1):p3e_cpu1_pe3_mp_rxp(7)" )
			)
			( signal "P3E_CPU1_PE3_MP_RXP<8>"
				( objectStatus "@baseboard_fab2_lib.baseboard_fab2(sch_1):p3e_cpu1_pe3_mp_rxp(8)" )
			)
			( signal "P3E_CPU1_PE3_MP_RXP<9>"
				( objectStatus "@baseboard_fab2_lib.baseboard_fab2(sch_1):p3e_cpu1_pe3_mp_rxp(9)" )
			)
			( signal "P3E_CPU1_PE3_MP_RXP<10>"
				( objectStatus "@baseboard_fab2_lib.baseboard_fab2(sch_1):p3e_cpu1_pe3_mp_rxp(10)" )
			)
			( signal "P3E_CPU1_PE3_MP_RXP<11>"
				( objectStatus "@baseboard_fab2_lib.baseboard_fab2(sch_1):p3e_cpu1_pe3_mp_rxp(11)" )
			)
			( signal "P3E_CPU1_PE3_MP_RXP<12>"
				( objectStatus "@baseboard_fab2_lib.baseboard_fab2(sch_1):p3e_cpu1_pe3_mp_rxp(12)" )
			)
			( signal "P3E_CPU1_PE3_MP_RXP<13>"
				( objectStatus "@baseboard_fab2_lib.baseboard_fab2(sch_1):p3e_cpu1_pe3_mp_rxp(13)" )
			)
			( signal "P3E_CPU1_PE3_MP_RXP<14>"
				( objectStatus "@baseboard_fab2_lib.baseboard_fab2(sch_1):p3e_cpu1_pe3_mp_rxp(14)" )
			)
			( signal "P3E_CPU1_PE3_MP_RXP<15>"
				( objectStatus "@baseboard_fab2_lib.baseboard_fab2(sch_1):p3e_cpu1_pe3_mp_rxp(15)" )
			)
			( signal "P3E_CPU1_PE3_MP_TXN<0>"
				( objectStatus "@baseboard_fab2_lib.baseboard_fab2(sch_1):p3e_cpu1_pe3_mp_txn(0)" )
			)
			( signal "P3E_CPU1_PE3_MP_TXN<1>"
				( objectStatus "@baseboard_fab2_lib.baseboard_fab2(sch_1):p3e_cpu1_pe3_mp_txn(1)" )
			)
			( signal "P3E_CPU1_PE3_MP_TXN<2>"
				( objectStatus "@baseboard_fab2_lib.baseboard_fab2(sch_1):p3e_cpu1_pe3_mp_txn(2)" )
			)
			( signal "P3E_CPU1_PE3_MP_TXN<3>"
				( objectStatus "@baseboard_fab2_lib.baseboard_fab2(sch_1):p3e_cpu1_pe3_mp_txn(3)" )
			)
			( signal "P3E_CPU1_PE3_MP_TXN<4>"
				( objectStatus "@baseboard_fab2_lib.baseboard_fab2(sch_1):p3e_cpu1_pe3_mp_txn(4)" )
			)
			( signal "P3E_CPU1_PE3_MP_TXN<5>"
				( objectStatus "@baseboard_fab2_lib.baseboard_fab2(sch_1):p3e_cpu1_pe3_mp_txn(5)" )
			)
			( signal "P3E_CPU1_PE3_MP_TXN<6>"
				( objectStatus "@baseboard_fab2_lib.baseboard_fab2(sch_1):p3e_cpu1_pe3_mp_txn(6)" )
			)
			( signal "P3E_CPU1_PE3_MP_TXN<7>"
				( objectStatus "@baseboard_fab2_lib.baseboard_fab2(sch_1):p3e_cpu1_pe3_mp_txn(7)" )
			)
			( signal "P3E_CPU1_PE3_MP_TXN<8>"
				( objectStatus "@baseboard_fab2_lib.baseboard_fab2(sch_1):p3e_cpu1_pe3_mp_txn(8)" )
			)
			( signal "P3E_CPU1_PE3_MP_TXN<9>"
				( objectStatus "@baseboard_fab2_lib.baseboard_fab2(sch_1):p3e_cpu1_pe3_mp_txn(9)" )
			)
			( signal "P3E_CPU1_PE3_MP_TXN<10>"
				( objectStatus "@baseboard_fab2_lib.baseboard_fab2(sch_1):p3e_cpu1_pe3_mp_txn(10)" )
			)
			( signal "P3E_CPU1_PE3_MP_TXN<11>"
				( objectStatus "@baseboard_fab2_lib.baseboard_fab2(sch_1):p3e_cpu1_pe3_mp_txn(11)" )
			)
			( signal "P3E_CPU1_PE3_MP_TXN<12>"
				( objectStatus "@baseboard_fab2_lib.baseboard_fab2(sch_1):p3e_cpu1_pe3_mp_txn(12)" )
			)
			( signal "P3E_CPU1_PE3_MP_TXN<13>"
				( objectStatus "@baseboard_fab2_lib.baseboard_fab2(sch_1):p3e_cpu1_pe3_mp_txn(13)" )
			)
			( signal "P3E_CPU1_PE3_MP_TXN<14>"
				( objectStatus "@baseboard_fab2_lib.baseboard_fab2(sch_1):p3e_cpu1_pe3_mp_txn(14)" )
			)
			( signal "P3E_CPU1_PE3_MP_TXN<15>"
				( objectStatus "@baseboard_fab2_lib.baseboard_fab2(sch_1):p3e_cpu1_pe3_mp_txn(15)" )
			)
			( signal "P3E_CPU1_PE3_MP_TXP<0>"
				( objectStatus "@baseboard_fab2_lib.baseboard_fab2(sch_1):p3e_cpu1_pe3_mp_txp(0)" )
			)
			( signal "P3E_CPU1_PE3_MP_TXP<1>"
				( objectStatus "@baseboard_fab2_lib.baseboard_fab2(sch_1):p3e_cpu1_pe3_mp_txp(1)" )
			)
			( signal "P3E_CPU1_PE3_MP_TXP<2>"
				( objectStatus "@baseboard_fab2_lib.baseboard_fab2(sch_1):p3e_cpu1_pe3_mp_txp(2)" )
			)
			( signal "P3E_CPU1_PE3_MP_TXP<3>"
				( objectStatus "@baseboard_fab2_lib.baseboard_fab2(sch_1):p3e_cpu1_pe3_mp_txp(3)" )
			)
			( signal "P3E_CPU1_PE3_MP_TXP<4>"
				( objectStatus "@baseboard_fab2_lib.baseboard_fab2(sch_1):p3e_cpu1_pe3_mp_txp(4)" )
			)
			( signal "P3E_CPU1_PE3_MP_TXP<5>"
				( objectStatus "@baseboard_fab2_lib.baseboard_fab2(sch_1):p3e_cpu1_pe3_mp_txp(5)" )
			)
			( signal "P3E_CPU1_PE3_MP_TXP<6>"
				( objectStatus "@baseboard_fab2_lib.baseboard_fab2(sch_1):p3e_cpu1_pe3_mp_txp(6)" )
			)
			( signal "P3E_CPU1_PE3_MP_TXP<7>"
				( objectStatus "@baseboard_fab2_lib.baseboard_fab2(sch_1):p3e_cpu1_pe3_mp_txp(7)" )
			)
			( signal "P3E_CPU1_PE3_MP_TXP<8>"
				( objectStatus "@baseboard_fab2_lib.baseboard_fab2(sch_1):p3e_cpu1_pe3_mp_txp(8)" )
			)
			( signal "P3E_CPU1_PE3_MP_TXP<9>"
				( objectStatus "@baseboard_fab2_lib.baseboard_fab2(sch_1):p3e_cpu1_pe3_mp_txp(9)" )
			)
			( signal "P3E_CPU1_PE3_MP_TXP<10>"
				( objectStatus "@baseboard_fab2_lib.baseboard_fab2(sch_1):p3e_cpu1_pe3_mp_txp(10)" )
			)
			( signal "P3E_CPU1_PE3_MP_TXP<11>"
				( objectStatus "@baseboard_fab2_lib.baseboard_fab2(sch_1):p3e_cpu1_pe3_mp_txp(11)" )
			)
			( signal "P3E_CPU1_PE3_MP_TXP<12>"
				( objectStatus "@baseboard_fab2_lib.baseboard_fab2(sch_1):p3e_cpu1_pe3_mp_txp(12)" )
			)
			( signal "P3E_CPU1_PE3_MP_TXP<13>"
				( objectStatus "@baseboard_fab2_lib.baseboard_fab2(sch_1):p3e_cpu1_pe3_mp_txp(13)" )
			)
			( signal "P3E_CPU1_PE3_MP_TXP<14>"
				( objectStatus "@baseboard_fab2_lib.baseboard_fab2(sch_1):p3e_cpu1_pe3_mp_txp(14)" )
			)
			( signal "P3E_CPU1_PE3_MP_TXP<15>"
				( objectStatus "@baseboard_fab2_lib.baseboard_fab2(sch_1):p3e_cpu1_pe3_mp_txp(15)" )
			)
			( signal "TP_CPU1_UPI2_RSVD_CA12"
				( objectStatus "@baseboard_fab2_lib.baseboard_fab2(sch_1):tp_cpu1_upi2_rsvd_ca12" )
			)
			( signal "TP_CPU1_UPI2_RSVD_CB11"
				( objectStatus "@baseboard_fab2_lib.baseboard_fab2(sch_1):tp_cpu1_upi2_rsvd_cb11" )
			)
			( signal "TP_CPU1_UPI2_RSVD_CC10"
				( objectStatus "@baseboard_fab2_lib.baseboard_fab2(sch_1):tp_cpu1_upi2_rsvd_cc10" )
			)
			( signal "TP_CPU1_UPI2_RSVD_CC12"
				( objectStatus "@baseboard_fab2_lib.baseboard_fab2(sch_1):tp_cpu1_upi2_rsvd_cc12" )
			)
			( signal "TP_CPU1_UPI2_RSVD_CD11"
				( objectStatus "@baseboard_fab2_lib.baseboard_fab2(sch_1):tp_cpu1_upi2_rsvd_cd11" )
			)
			( signal "TP_CPU1_UPI2_RSVD_CE12"
				( objectStatus "@baseboard_fab2_lib.baseboard_fab2(sch_1):tp_cpu1_upi2_rsvd_ce12" )
			)
			( signal "TP_CPU1_UPI2_RSVD_CF11"
				( objectStatus "@baseboard_fab2_lib.baseboard_fab2(sch_1):tp_cpu1_upi2_rsvd_cf11" )
			)
			( signal "TP_CPU1_UPI2_RSVD_CF13"
				( objectStatus "@baseboard_fab2_lib.baseboard_fab2(sch_1):tp_cpu1_upi2_rsvd_cf13" )
			)
			( signal "TP_CPU1_UPI2_RSVD_CG12"
				( objectStatus "@baseboard_fab2_lib.baseboard_fab2(sch_1):tp_cpu1_upi2_rsvd_cg12" )
			)
			( signal "TP_CPU1_UPI2_RSVD_CH11"
				( objectStatus "@baseboard_fab2_lib.baseboard_fab2(sch_1):tp_cpu1_upi2_rsvd_ch11" )
			)
			( signal "TP_CPU1_UPI2_RSVD_CH13"
				( objectStatus "@baseboard_fab2_lib.baseboard_fab2(sch_1):tp_cpu1_upi2_rsvd_ch13" )
			)
			( signal "TP_CPU1_UPI2_RSVD_CJ14"
				( objectStatus "@baseboard_fab2_lib.baseboard_fab2(sch_1):tp_cpu1_upi2_rsvd_cj14" )
			)
			( signal "TP_CPU1_UPI2_RSVD_CK13"
				( objectStatus "@baseboard_fab2_lib.baseboard_fab2(sch_1):tp_cpu1_upi2_rsvd_ck13" )
			)
			( signal "TP_CPU1_UPI2_RSVD_CM13"
				( objectStatus "@baseboard_fab2_lib.baseboard_fab2(sch_1):tp_cpu1_upi2_rsvd_cm13" )
			)
			( signal "TP_CPU1_UPI2_RSVD_CR14"
				( objectStatus "@baseboard_fab2_lib.baseboard_fab2(sch_1):tp_cpu1_upi2_rsvd_cr14" )
			)
			( signal "TP_CPU1_UPI2_RSVD_CU14"
				( objectStatus "@baseboard_fab2_lib.baseboard_fab2(sch_1):tp_cpu1_upi2_rsvd_cu14" )
			)
			( signal "TP_CPU1_UPI2_RSVD_CV13"
				( objectStatus "@baseboard_fab2_lib.baseboard_fab2(sch_1):tp_cpu1_upi2_rsvd_cv13" )
			)
			( signal "TP_CPU1_UPI2_RSVD_CW14"
				( objectStatus "@baseboard_fab2_lib.baseboard_fab2(sch_1):tp_cpu1_upi2_rsvd_cw14" )
			)
			( signal "TP_CPU1_UPI2_RSVD_CW16"
				( objectStatus "@baseboard_fab2_lib.baseboard_fab2(sch_1):tp_cpu1_upi2_rsvd_cw16" )
			)
			( signal "TP_CPU1_UPI2_RSVD_DA16"
				( objectStatus "@baseboard_fab2_lib.baseboard_fab2(sch_1):tp_cpu1_upi2_rsvd_da16" )
			)
			( signal "TP_CPU1_UPI2_RSVD_DB15"
				( objectStatus "@baseboard_fab2_lib.baseboard_fab2(sch_1):tp_cpu1_upi2_rsvd_db15" )
			)
			( signal "TP_CPU1_UPI2_RSVD_DC16"
				( objectStatus "@baseboard_fab2_lib.baseboard_fab2(sch_1):tp_cpu1_upi2_rsvd_dc16" )
			)
			( signal "TP_CPU1_UPI2_RSVD_DD15"
				( objectStatus "@baseboard_fab2_lib.baseboard_fab2(sch_1):tp_cpu1_upi2_rsvd_dd15" )
			)
			( signal "TP_CPU1_UPI2_RSVD_DD17"
				( objectStatus "@baseboard_fab2_lib.baseboard_fab2(sch_1):tp_cpu1_upi2_rsvd_dd17" )
			)
			( signal "TP_CPU1_UPI2_RSVD_DE16"
				( objectStatus "@baseboard_fab2_lib.baseboard_fab2(sch_1):tp_cpu1_upi2_rsvd_de16" )
			)
			( signal "TP_CPU1_UPI2_RSVD_DF15"
				( objectStatus "@baseboard_fab2_lib.baseboard_fab2(sch_1):tp_cpu1_upi2_rsvd_df15" )
			)
			( signal "TP_CPU1_UPI2_RSVD_DF17"
				( objectStatus "@baseboard_fab2_lib.baseboard_fab2(sch_1):tp_cpu1_upi2_rsvd_df17" )
			)
			( signal "TP_CPU1_UPI2_RSVD_DG18"
				( objectStatus "@baseboard_fab2_lib.baseboard_fab2(sch_1):tp_cpu1_upi2_rsvd_dg18" )
			)
			( signal "TP_CPU1_UPI2_RSVD_DG20"
				( objectStatus "@baseboard_fab2_lib.baseboard_fab2(sch_1):tp_cpu1_upi2_rsvd_dg20" )
			)
			( signal "TP_CPU1_UPI2_RSVD_DH17"
				( objectStatus "@baseboard_fab2_lib.baseboard_fab2(sch_1):tp_cpu1_upi2_rsvd_dh17" )
			)
			( signal "TP_CPU1_UPI2_RSVD_DH19"
				( objectStatus "@baseboard_fab2_lib.baseboard_fab2(sch_1):tp_cpu1_upi2_rsvd_dh19" )
			)
			( signal "TP_CPU1_UPI2_RSVD_DJ18"
				( objectStatus "@baseboard_fab2_lib.baseboard_fab2(sch_1):tp_cpu1_upi2_rsvd_dj18" )
			)
			( signal "TP_CPU1_UPI2_RSVD_DJ20"
				( objectStatus "@baseboard_fab2_lib.baseboard_fab2(sch_1):tp_cpu1_upi2_rsvd_dj20" )
			)
			( signal "TP_CPU1_UPI2_RSVD_DK17"
				( objectStatus "@baseboard_fab2_lib.baseboard_fab2(sch_1):tp_cpu1_upi2_rsvd_dk17" )
			)
			( signal "TP_CPU1_UPI2_RSVD_DK19"
				( objectStatus "@baseboard_fab2_lib.baseboard_fab2(sch_1):tp_cpu1_upi2_rsvd_dk19" )
			)
			( signal "TP_CPU1_UPI2_RSVD_DL20"
				( objectStatus "@baseboard_fab2_lib.baseboard_fab2(sch_1):tp_cpu1_upi2_rsvd_dl20" )
			)
			( signal "TP_CPU1_UPI2_RSVD_DM21"
				( objectStatus "@baseboard_fab2_lib.baseboard_fab2(sch_1):tp_cpu1_upi2_rsvd_dm21" )
			)
			( signal "TP_CPU1_UPI2_RSVD_DN20"
				( objectStatus "@baseboard_fab2_lib.baseboard_fab2(sch_1):tp_cpu1_upi2_rsvd_dn20" )
			)
			( signal "TP_CPU1_UPI2_RSVD_DP21"
				( objectStatus "@baseboard_fab2_lib.baseboard_fab2(sch_1):tp_cpu1_upi2_rsvd_dp21" )
			)
			( signal "TP_CPU1_UPI2_RSVD_DT21"
				( objectStatus "@baseboard_fab2_lib.baseboard_fab2(sch_1):tp_cpu1_upi2_rsvd_dt21" )
			)
			( signal "CLK_100M_CPU1_RC_REFCLK1_DN"
				( objectStatus "@baseboard_fab2_lib.baseboard_fab2(sch_1):clk_100m_cpu1_rc_refclk1_dn" )
			)
			( signal "CLK_100M_CPU1_RC_REFCLK1_DP"
				( objectStatus "@baseboard_fab2_lib.baseboard_fab2(sch_1):clk_100m_cpu1_rc_refclk1_dp" )
			)
			( signal "TP_CPU1_RSVD_100"
				( objectStatus "@baseboard_fab2_lib.baseboard_fab2(sch_1):tp_cpu1_rsvd_100" )
			)
			( signal "TP_CPU1_RSVD_101"
				( objectStatus "@baseboard_fab2_lib.baseboard_fab2(sch_1):tp_cpu1_rsvd_101" )
			)
			( signal "TP_CPU1_RSVD_105"
				( objectStatus "@baseboard_fab2_lib.baseboard_fab2(sch_1):tp_cpu1_rsvd_105" )
			)
			( signal "TP_CPU1_RSVD_106"
				( objectStatus "@baseboard_fab2_lib.baseboard_fab2(sch_1):tp_cpu1_rsvd_106" )
			)
			( signal "TP_CPU1_RSVD_108"
				( objectStatus "@baseboard_fab2_lib.baseboard_fab2(sch_1):tp_cpu1_rsvd_108" )
			)
			( signal "TP_CPU1_RSVD_111"
				( objectStatus "@baseboard_fab2_lib.baseboard_fab2(sch_1):tp_cpu1_rsvd_111" )
			)
			( signal "TP_CPU1_RSVD_113"
				( objectStatus "@baseboard_fab2_lib.baseboard_fab2(sch_1):tp_cpu1_rsvd_113" )
			)
			( signal "TP_CPU1_RSVD_114"
				( objectStatus "@baseboard_fab2_lib.baseboard_fab2(sch_1):tp_cpu1_rsvd_114" )
			)
			( signal "TP_CPU1_RSVD_117"
				( objectStatus "@baseboard_fab2_lib.baseboard_fab2(sch_1):tp_cpu1_rsvd_117" )
			)
			( signal "TP_CPU1_RSVD_119"
				( objectStatus "@baseboard_fab2_lib.baseboard_fab2(sch_1):tp_cpu1_rsvd_119" )
			)
			( signal "TP_CPU1_RSVD_121"
				( objectStatus "@baseboard_fab2_lib.baseboard_fab2(sch_1):tp_cpu1_rsvd_121" )
			)
			( signal "TP_CPU1_RSVD_123"
				( objectStatus "@baseboard_fab2_lib.baseboard_fab2(sch_1):tp_cpu1_rsvd_123" )
			)
			( signal "TP_CPU1_RSVD_124"
				( objectStatus "@baseboard_fab2_lib.baseboard_fab2(sch_1):tp_cpu1_rsvd_124" )
			)
			( signal "TP_CPU1_RSVD_144"
				( objectStatus "@baseboard_fab2_lib.baseboard_fab2(sch_1):tp_cpu1_rsvd_144" )
			)
			( signal "TP_CPU1_RSVD_145"
				( objectStatus "@baseboard_fab2_lib.baseboard_fab2(sch_1):tp_cpu1_rsvd_145" )
			)
			( signal "TP_CPU1_RSVD_146"
				( objectStatus "@baseboard_fab2_lib.baseboard_fab2(sch_1):tp_cpu1_rsvd_146" )
			)
			( signal "TP_CPU1_RSVD_147"
				( objectStatus "@baseboard_fab2_lib.baseboard_fab2(sch_1):tp_cpu1_rsvd_147" )
			)
			( signal "TP_CPU1_RSVD_148"
				( objectStatus "@baseboard_fab2_lib.baseboard_fab2(sch_1):tp_cpu1_rsvd_148" )
			)
			( signal "TP_CPU1_RSVD_149"
				( objectStatus "@baseboard_fab2_lib.baseboard_fab2(sch_1):tp_cpu1_rsvd_149" )
			)
			( signal "TP_CPU1_RSVD_150"
				( objectStatus "@baseboard_fab2_lib.baseboard_fab2(sch_1):tp_cpu1_rsvd_150" )
			)
			( signal "TP_CPU1_RSVD_151"
				( objectStatus "@baseboard_fab2_lib.baseboard_fab2(sch_1):tp_cpu1_rsvd_151" )
			)
			( signal "TP_CPU1_RSVD_152"
				( objectStatus "@baseboard_fab2_lib.baseboard_fab2(sch_1):tp_cpu1_rsvd_152" )
			)
			( signal "TP_CPU1_RSVD_154"
				( objectStatus "@baseboard_fab2_lib.baseboard_fab2(sch_1):tp_cpu1_rsvd_154" )
			)
			( signal "TP_CPU1_RSVD_155"
				( objectStatus "@baseboard_fab2_lib.baseboard_fab2(sch_1):tp_cpu1_rsvd_155" )
			)
			( signal "TP_CPU1_RSVD_156"
				( objectStatus "@baseboard_fab2_lib.baseboard_fab2(sch_1):tp_cpu1_rsvd_156" )
			)
			( signal "TP_CPU1_RSVD_157"
				( objectStatus "@baseboard_fab2_lib.baseboard_fab2(sch_1):tp_cpu1_rsvd_157" )
			)
			( signal "TP_CPU1_RSVD_158"
				( objectStatus "@baseboard_fab2_lib.baseboard_fab2(sch_1):tp_cpu1_rsvd_158" )
			)
			( signal "TP_CPU1_RSVD_159"
				( objectStatus "@baseboard_fab2_lib.baseboard_fab2(sch_1):tp_cpu1_rsvd_159" )
			)
			( signal "TP_CPU1_RSVD_160"
				( objectStatus "@baseboard_fab2_lib.baseboard_fab2(sch_1):tp_cpu1_rsvd_160" )
			)
			( signal "TP_CPU1_RSVD_161"
				( objectStatus "@baseboard_fab2_lib.baseboard_fab2(sch_1):tp_cpu1_rsvd_161" )
			)
			( signal "TP_CPU1_RSVD_162"
				( objectStatus "@baseboard_fab2_lib.baseboard_fab2(sch_1):tp_cpu1_rsvd_162" )
			)
			( signal "TP_CPU1_RSVD_163"
				( objectStatus "@baseboard_fab2_lib.baseboard_fab2(sch_1):tp_cpu1_rsvd_163" )
			)
			( signal "TP_CPU1_RSVD_164"
				( objectStatus "@baseboard_fab2_lib.baseboard_fab2(sch_1):tp_cpu1_rsvd_164" )
			)
			( signal "TP_CPU1_RSVD_166"
				( objectStatus "@baseboard_fab2_lib.baseboard_fab2(sch_1):tp_cpu1_rsvd_166" )
			)
			( signal "TP_CPU1_RSVD_167"
				( objectStatus "@baseboard_fab2_lib.baseboard_fab2(sch_1):tp_cpu1_rsvd_167" )
			)
			( signal "TP_CPU1_RSVD_168"
				( objectStatus "@baseboard_fab2_lib.baseboard_fab2(sch_1):tp_cpu1_rsvd_168" )
			)
			( signal "TP_CPU1_RSVD_169"
				( objectStatus "@baseboard_fab2_lib.baseboard_fab2(sch_1):tp_cpu1_rsvd_169" )
			)
			( signal "TP_CPU1_RSVD_170"
				( objectStatus "@baseboard_fab2_lib.baseboard_fab2(sch_1):tp_cpu1_rsvd_170" )
			)
			( signal "TP_CPU1_RSVD_171"
				( objectStatus "@baseboard_fab2_lib.baseboard_fab2(sch_1):tp_cpu1_rsvd_171" )
			)
			( signal "TP_CPU1_RSVD_255"
				( objectStatus "@baseboard_fab2_lib.baseboard_fab2(sch_1):tp_cpu1_rsvd_255" )
			)
			( signal "TP_CPU1_RSVD_82"
				( objectStatus "@baseboard_fab2_lib.baseboard_fab2(sch_1):tp_cpu1_rsvd_82" )
			)
			( signal "TP_CPU1_RSVD_85"
				( objectStatus "@baseboard_fab2_lib.baseboard_fab2(sch_1):tp_cpu1_rsvd_85" )
			)
			( signal "TP_CPU1_RSVD_90"
				( objectStatus "@baseboard_fab2_lib.baseboard_fab2(sch_1):tp_cpu1_rsvd_90" )
			)
			( signal "TP_CPU1_RSVD_91"
				( objectStatus "@baseboard_fab2_lib.baseboard_fab2(sch_1):tp_cpu1_rsvd_91" )
			)
			( signal "TP_CPU1_RSVD_94"
				( objectStatus "@baseboard_fab2_lib.baseboard_fab2(sch_1):tp_cpu1_rsvd_94" )
			)
			( signal "TP_CPU1_RSVD_95"
				( objectStatus "@baseboard_fab2_lib.baseboard_fab2(sch_1):tp_cpu1_rsvd_95" )
			)
			( signal "TP_CPU1_RSVD_97"
				( objectStatus "@baseboard_fab2_lib.baseboard_fab2(sch_1):tp_cpu1_rsvd_97" )
			)
			( signal "TP_CPU1_RSVD_99"
				( objectStatus "@baseboard_fab2_lib.baseboard_fab2(sch_1):tp_cpu1_rsvd_99" )
			)
			( signal "TP_CPU1_TEST_10"
				( objectStatus "@baseboard_fab2_lib.baseboard_fab2(sch_1):tp_cpu1_test_10" )
			)
			( signal "TP_CPU1_TEST_6"
				( objectStatus "@baseboard_fab2_lib.baseboard_fab2(sch_1):tp_cpu1_test_6" )
			)
			( signal "TP_CPU1_TEST_7"
				( objectStatus "@baseboard_fab2_lib.baseboard_fab2(sch_1):tp_cpu1_test_7" )
			)
			( signal "TP_CPU1_TEST_8"
				( objectStatus "@baseboard_fab2_lib.baseboard_fab2(sch_1):tp_cpu1_test_8" )
			)
			( signal "TP_CPU1_TEST_9"
				( objectStatus "@baseboard_fab2_lib.baseboard_fab2(sch_1):tp_cpu1_test_9" )
			)
			( signal "PVCCIN_CPU1"
				( attribute "VOLTAGE" "2.0V"
					( Units "uVoltage" "V" 1.000000)
					( Status sAliasFlattened )
					( Origin gFrontEnd )
				)
				( objectStatus "@baseboard_fab2_lib.baseboard_fab2(sch_1):pvccin_cpu1" )
			)
			( signal "VSENSE_PMAX_CPU1"
				( objectStatus "@baseboard_fab2_lib.baseboard_fab2(sch_1):vsense_pmax_cpu1" )
			)
			( signal "VSENSE_PVCCIN_CPU1_SKT_VRTN"
				( objectStatus "@baseboard_fab2_lib.baseboard_fab2(sch_1):vsense_pvccin_cpu1_skt_vrtn" )
			)
			( signal "VSENSE_PVCCIN_CPU1_SKT_VSEN"
				( objectStatus "@baseboard_fab2_lib.baseboard_fab2(sch_1):vsense_pvccin_cpu1_skt_vsen" )
			)
			( signal "VSENSE_VCCINR2PMAX_CPU1"
				( objectStatus "@baseboard_fab2_lib.baseboard_fab2(sch_1):vsense_vccinr2pmax_cpu1" )
			)
			( signal "PVCCIOMCP_CPU1"
				( attribute "VOLTAGE" "+0.95V"
					( Units "uVoltage" "V" 1.000000)
					( Status sAliasFlattened )
					( Status sAliasConflict )
					( Origin gFrontEnd )
				)
				( objectStatus "@baseboard_fab2_lib.baseboard_fab2(sch_1):pvcciomcp_cpu1" )
			)
			( signal "PVDDQ_GHJ"
				( attribute "VOLTAGE" "1.2V"
					( Units "uVoltage" "V" 1.000000)
					( Status sAliasFlattened )
					( Origin gFrontEnd )
				)
				( objectStatus "@baseboard_fab2_lib.baseboard_fab2(sch_1):pvddq_ghj" )
			)
			( signal "PVDDQ_KLM"
				( attribute "VOLTAGE" "1.2V"
					( Units "uVoltage" "V" 1.000000)
					( Status sAliasFlattened )
					( Origin gFrontEnd )
				)
				( objectStatus "@baseboard_fab2_lib.baseboard_fab2(sch_1):pvddq_klm" )
			)
			( signal "PECI_SEL"
				( objectStatus "@baseboard_fab2_lib.baseboard_fab2(sch_1):peci_sel" )
			)
			( signal "PVPP_GHJ"
				( attribute "VOLTAGE" "2.5V"
					( Units "uVoltage" "V" 1.000000)
					( Status sAliasFlattened )
					( Origin gFrontEnd )
				)
				( objectStatus "@baseboard_fab2_lib.baseboard_fab2(sch_1):pvpp_ghj" )
			)
			( signal "PVSA_CPU1"
				( attribute "VOLTAGE" "1.1V"
					( Units "uVoltage" "V" 1.000000)
					( Status sAliasFlattened )
					( Origin gFrontEnd )
				)
				( objectStatus "@baseboard_fab2_lib.baseboard_fab2(sch_1):pvsa_cpu1" )
			)
			( signal "PD_CPU1_MCP01_DMON"
				( objectStatus "@baseboard_fab2_lib.baseboard_fab2(sch_1):pd_cpu1_mcp01_dmon" )
			)
			( signal "TP_CPU1_KTI2_AMONV"
				( objectStatus "@baseboard_fab2_lib.baseboard_fab2(sch_1):tp_cpu1_kti2_amonv" )
			)
			( signal "TP_CPU1_KTI2_DFX_DN"
				( objectStatus "@baseboard_fab2_lib.baseboard_fab2(sch_1):tp_cpu1_kti2_dfx_dn" )
			)
			( signal "TP_CPU1_RSVD_0"
				( objectStatus "@baseboard_fab2_lib.baseboard_fab2(sch_1):tp_cpu1_rsvd_0" )
			)
			( signal "TP_CPU1_RSVD_1"
				( objectStatus "@baseboard_fab2_lib.baseboard_fab2(sch_1):tp_cpu1_rsvd_1" )
			)
			( signal "TP_CPU1_RSVD_10"
				( objectStatus "@baseboard_fab2_lib.baseboard_fab2(sch_1):tp_cpu1_rsvd_10" )
			)
			( signal "TP_CPU1_RSVD_11"
				( objectStatus "@baseboard_fab2_lib.baseboard_fab2(sch_1):tp_cpu1_rsvd_11" )
			)
			( signal "TP_CPU1_RSVD_12"
				( objectStatus "@baseboard_fab2_lib.baseboard_fab2(sch_1):tp_cpu1_rsvd_12" )
			)
			( signal "TP_CPU1_RSVD_13"
				( objectStatus "@baseboard_fab2_lib.baseboard_fab2(sch_1):tp_cpu1_rsvd_13" )
			)
			( signal "TP_CPU1_RSVD_14"
				( objectStatus "@baseboard_fab2_lib.baseboard_fab2(sch_1):tp_cpu1_rsvd_14" )
			)
			( signal "TP_CPU1_RSVD_15"
				( objectStatus "@baseboard_fab2_lib.baseboard_fab2(sch_1):tp_cpu1_rsvd_15" )
			)
			( signal "TP_CPU1_RSVD_16"
				( objectStatus "@baseboard_fab2_lib.baseboard_fab2(sch_1):tp_cpu1_rsvd_16" )
			)
			( signal "TP_CPU1_RSVD_17"
				( objectStatus "@baseboard_fab2_lib.baseboard_fab2(sch_1):tp_cpu1_rsvd_17" )
			)
			( signal "TP_CPU1_RSVD_18"
				( objectStatus "@baseboard_fab2_lib.baseboard_fab2(sch_1):tp_cpu1_rsvd_18" )
			)
			( signal "TP_CPU1_RSVD_19"
				( objectStatus "@baseboard_fab2_lib.baseboard_fab2(sch_1):tp_cpu1_rsvd_19" )
			)
			( signal "TP_CPU1_RSVD_2"
				( objectStatus "@baseboard_fab2_lib.baseboard_fab2(sch_1):tp_cpu1_rsvd_2" )
			)
			( signal "TP_CPU1_RSVD_20"
				( objectStatus "@baseboard_fab2_lib.baseboard_fab2(sch_1):tp_cpu1_rsvd_20" )
			)
			( signal "TP_CPU1_RSVD_21"
				( objectStatus "@baseboard_fab2_lib.baseboard_fab2(sch_1):tp_cpu1_rsvd_21" )
			)
			( signal "TP_CPU1_RSVD_22"
				( objectStatus "@baseboard_fab2_lib.baseboard_fab2(sch_1):tp_cpu1_rsvd_22" )
			)
			( signal "TP_CPU1_RSVD_23"
				( objectStatus "@baseboard_fab2_lib.baseboard_fab2(sch_1):tp_cpu1_rsvd_23" )
			)
			( signal "TP_CPU1_RSVD_24"
				( objectStatus "@baseboard_fab2_lib.baseboard_fab2(sch_1):tp_cpu1_rsvd_24" )
			)
			( signal "TP_CPU1_RSVD_25"
				( objectStatus "@baseboard_fab2_lib.baseboard_fab2(sch_1):tp_cpu1_rsvd_25" )
			)
			( signal "TP_CPU1_RSVD_26"
				( objectStatus "@baseboard_fab2_lib.baseboard_fab2(sch_1):tp_cpu1_rsvd_26" )
			)
			( signal "TP_CPU1_RSVD_27"
				( objectStatus "@baseboard_fab2_lib.baseboard_fab2(sch_1):tp_cpu1_rsvd_27" )
			)
			( signal "TP_CPU1_RSVD_28"
				( objectStatus "@baseboard_fab2_lib.baseboard_fab2(sch_1):tp_cpu1_rsvd_28" )
			)
			( signal "TP_CPU1_RSVD_29"
				( objectStatus "@baseboard_fab2_lib.baseboard_fab2(sch_1):tp_cpu1_rsvd_29" )
			)
			( signal "TP_CPU1_RSVD_3"
				( objectStatus "@baseboard_fab2_lib.baseboard_fab2(sch_1):tp_cpu1_rsvd_3" )
			)
			( signal "TP_CPU1_RSVD_30"
				( objectStatus "@baseboard_fab2_lib.baseboard_fab2(sch_1):tp_cpu1_rsvd_30" )
			)
			( signal "TP_CPU1_RSVD_31"
				( objectStatus "@baseboard_fab2_lib.baseboard_fab2(sch_1):tp_cpu1_rsvd_31" )
			)
			( signal "TP_CPU1_RSVD_32"
				( objectStatus "@baseboard_fab2_lib.baseboard_fab2(sch_1):tp_cpu1_rsvd_32" )
			)
			( signal "TP_CPU1_RSVD_33"
				( objectStatus "@baseboard_fab2_lib.baseboard_fab2(sch_1):tp_cpu1_rsvd_33" )
			)
			( signal "TP_CPU1_RSVD_34"
				( objectStatus "@baseboard_fab2_lib.baseboard_fab2(sch_1):tp_cpu1_rsvd_34" )
			)
			( signal "TP_CPU1_RSVD_35"
				( objectStatus "@baseboard_fab2_lib.baseboard_fab2(sch_1):tp_cpu1_rsvd_35" )
			)
			( signal "TP_CPU1_RSVD_36"
				( objectStatus "@baseboard_fab2_lib.baseboard_fab2(sch_1):tp_cpu1_rsvd_36" )
			)
			( signal "TP_CPU1_RSVD_37"
				( objectStatus "@baseboard_fab2_lib.baseboard_fab2(sch_1):tp_cpu1_rsvd_37" )
			)
			( signal "TP_CPU1_RSVD_38"
				( objectStatus "@baseboard_fab2_lib.baseboard_fab2(sch_1):tp_cpu1_rsvd_38" )
			)
			( signal "TP_CPU1_RSVD_39"
				( objectStatus "@baseboard_fab2_lib.baseboard_fab2(sch_1):tp_cpu1_rsvd_39" )
			)
			( signal "TP_CPU1_RSVD_4"
				( objectStatus "@baseboard_fab2_lib.baseboard_fab2(sch_1):tp_cpu1_rsvd_4" )
			)
			( signal "TP_CPU1_RSVD_40"
				( objectStatus "@baseboard_fab2_lib.baseboard_fab2(sch_1):tp_cpu1_rsvd_40" )
			)
			( signal "TP_CPU1_RSVD_41"
				( objectStatus "@baseboard_fab2_lib.baseboard_fab2(sch_1):tp_cpu1_rsvd_41" )
			)
			( signal "TP_CPU1_RSVD_42"
				( objectStatus "@baseboard_fab2_lib.baseboard_fab2(sch_1):tp_cpu1_rsvd_42" )
			)
			( signal "TP_CPU1_RSVD_43"
				( objectStatus "@baseboard_fab2_lib.baseboard_fab2(sch_1):tp_cpu1_rsvd_43" )
			)
			( signal "TP_CPU1_RSVD_44"
				( objectStatus "@baseboard_fab2_lib.baseboard_fab2(sch_1):tp_cpu1_rsvd_44" )
			)
			( signal "TP_CPU1_RSVD_45"
				( objectStatus "@baseboard_fab2_lib.baseboard_fab2(sch_1):tp_cpu1_rsvd_45" )
			)
			( signal "TP_CPU1_RSVD_46"
				( objectStatus "@baseboard_fab2_lib.baseboard_fab2(sch_1):tp_cpu1_rsvd_46" )
			)
			( signal "TP_CPU1_RSVD_47"
				( objectStatus "@baseboard_fab2_lib.baseboard_fab2(sch_1):tp_cpu1_rsvd_47" )
			)
			( signal "TP_CPU1_RSVD_48"
				( objectStatus "@baseboard_fab2_lib.baseboard_fab2(sch_1):tp_cpu1_rsvd_48" )
			)
			( signal "TP_CPU1_RSVD_49"
				( objectStatus "@baseboard_fab2_lib.baseboard_fab2(sch_1):tp_cpu1_rsvd_49" )
			)
			( signal "TP_CPU1_RSVD_5"
				( objectStatus "@baseboard_fab2_lib.baseboard_fab2(sch_1):tp_cpu1_rsvd_5" )
			)
			( signal "TP_CPU1_RSVD_50"
				( objectStatus "@baseboard_fab2_lib.baseboard_fab2(sch_1):tp_cpu1_rsvd_50" )
			)
			( signal "TP_CPU1_RSVD_51"
				( objectStatus "@baseboard_fab2_lib.baseboard_fab2(sch_1):tp_cpu1_rsvd_51" )
			)
			( signal "TP_CPU1_RSVD_53"
				( objectStatus "@baseboard_fab2_lib.baseboard_fab2(sch_1):tp_cpu1_rsvd_53" )
			)
			( signal "TP_CPU1_RSVD_54"
				( objectStatus "@baseboard_fab2_lib.baseboard_fab2(sch_1):tp_cpu1_rsvd_54" )
			)
			( signal "TP_CPU1_RSVD_55"
				( objectStatus "@baseboard_fab2_lib.baseboard_fab2(sch_1):tp_cpu1_rsvd_55" )
			)
			( signal "TP_CPU1_RSVD_56"
				( objectStatus "@baseboard_fab2_lib.baseboard_fab2(sch_1):tp_cpu1_rsvd_56" )
			)
			( signal "TP_CPU1_RSVD_57"
				( objectStatus "@baseboard_fab2_lib.baseboard_fab2(sch_1):tp_cpu1_rsvd_57" )
			)
			( signal "TP_CPU1_RSVD_59"
				( objectStatus "@baseboard_fab2_lib.baseboard_fab2(sch_1):tp_cpu1_rsvd_59" )
			)
			( signal "TP_CPU1_RSVD_6"
				( objectStatus "@baseboard_fab2_lib.baseboard_fab2(sch_1):tp_cpu1_rsvd_6" )
			)
			( signal "TP_CPU1_RSVD_60"
				( objectStatus "@baseboard_fab2_lib.baseboard_fab2(sch_1):tp_cpu1_rsvd_60" )
			)
			( signal "TP_CPU1_RSVD_61"
				( objectStatus "@baseboard_fab2_lib.baseboard_fab2(sch_1):tp_cpu1_rsvd_61" )
			)
			( signal "TP_CPU1_RSVD_64"
				( objectStatus "@baseboard_fab2_lib.baseboard_fab2(sch_1):tp_cpu1_rsvd_64" )
			)
			( signal "TP_CPU1_RSVD_66"
				( objectStatus "@baseboard_fab2_lib.baseboard_fab2(sch_1):tp_cpu1_rsvd_66" )
			)
			( signal "TP_CPU1_RSVD_67"
				( objectStatus "@baseboard_fab2_lib.baseboard_fab2(sch_1):tp_cpu1_rsvd_67" )
			)
			( signal "TP_CPU1_RSVD_69"
				( objectStatus "@baseboard_fab2_lib.baseboard_fab2(sch_1):tp_cpu1_rsvd_69" )
			)
			( signal "TP_CPU1_RSVD_7"
				( objectStatus "@baseboard_fab2_lib.baseboard_fab2(sch_1):tp_cpu1_rsvd_7" )
			)
			( signal "TP_CPU1_RSVD_70"
				( objectStatus "@baseboard_fab2_lib.baseboard_fab2(sch_1):tp_cpu1_rsvd_70" )
			)
			( signal "TP_CPU1_RSVD_72"
				( objectStatus "@baseboard_fab2_lib.baseboard_fab2(sch_1):tp_cpu1_rsvd_72" )
			)
			( signal "TP_CPU1_RSVD_73"
				( objectStatus "@baseboard_fab2_lib.baseboard_fab2(sch_1):tp_cpu1_rsvd_73" )
			)
			( signal "TP_CPU1_RSVD_8"
				( objectStatus "@baseboard_fab2_lib.baseboard_fab2(sch_1):tp_cpu1_rsvd_8" )
			)
			( signal "TP_CPU1_RSVD_9"
				( objectStatus "@baseboard_fab2_lib.baseboard_fab2(sch_1):tp_cpu1_rsvd_9" )
			)
			( signal "VSENSE_PVCCIO_CPU1_SKT_VRTN"
				( objectStatus "@baseboard_fab2_lib.baseboard_fab2(sch_1):vsense_pvccio_cpu1_skt_vrtn" )
			)
			( signal "VSENSE_PVCCIO_CPU1_SKT_VSEN"
				( objectStatus "@baseboard_fab2_lib.baseboard_fab2(sch_1):vsense_pvccio_cpu1_skt_vsen" )
			)
			( signal "VSENSE_PVCCIOMCP_CPU1_SKT_VRTN"
				( objectStatus "@baseboard_fab2_lib.baseboard_fab2(sch_1):vsense_pvcciomcp_cpu1_skt_vrtn" )
			)
			( signal "VSENSE_PVCCIOMCP_CPU1_SKT_VSEN"
				( objectStatus "@baseboard_fab2_lib.baseboard_fab2(sch_1):vsense_pvcciomcp_cpu1_skt_vsen" )
			)
			( signal "VSENSE_PVCCMCP_CPU1_SKT_VRTN"
				( objectStatus "@baseboard_fab2_lib.baseboard_fab2(sch_1):vsense_pvccmcp_cpu1_skt_vrtn" )
			)
			( signal "VSENSE_PVCCMCP_CPU1_SKT_VSEN"
				( objectStatus "@baseboard_fab2_lib.baseboard_fab2(sch_1):vsense_pvccmcp_cpu1_skt_vsen" )
			)
			( signal "VSENSE_PVSA_CPU1_SKT_VRTN"
				( objectStatus "@baseboard_fab2_lib.baseboard_fab2(sch_1):vsense_pvsa_cpu1_skt_vrtn" )
			)
			( signal "VSENSE_PVSA_CPU1_SKT_VSEN"
				( objectStatus "@baseboard_fab2_lib.baseboard_fab2(sch_1):vsense_pvsa_cpu1_skt_vsen" )
			)
			( signal "FM_ADR_COMPLETE_GHJ_N"
				( objectStatus "@baseboard_fab2_lib.baseboard_fab2(sch_1):fm_adr_complete_ghj_n" )
			)
			( signal "M_G_VREF"
				( objectStatus "@baseboard_fab2_lib.baseboard_fab2(sch_1):m_g_vref" )
			)
			( signal "P12V_NVDIMM_GHJ"
				( attribute "VOLTAGE" "12.0"
					( Units "uVoltage" "V" 1.000000)
					( Status sAliasFlattened )
					( Origin gFrontEnd )
				)
				( objectStatus "@baseboard_fab2_lib.baseboard_fab2(sch_1):p12v_nvdimm_ghj" )
			)
			( signal "PVTT_GHJ"
				( attribute "VOLTAGE" "0.6V"
					( Units "uVoltage" "V" 1.000000)
					( Status sAliasFlattened )
					( Origin gFrontEnd )
				)
				( objectStatus "@baseboard_fab2_lib.baseboard_fab2(sch_1):pvtt_ghj" )
			)
			( signal "SMB_DDR_GHJ_VPP_SCL"
				( objectStatus "@baseboard_fab2_lib.baseboard_fab2(sch_1):smb_ddr_ghj_vpp_scl" )
			)
			( signal "SMB_DDR_GHJ_VPP_SDA"
				( objectStatus "@baseboard_fab2_lib.baseboard_fab2(sch_1):smb_ddr_ghj_vpp_sda" )
			)
			( signal "TP_CH_G_DIMM_G0_RFU_0"
				( objectStatus "@baseboard_fab2_lib.baseboard_fab2(sch_1):tp_ch_g_dimm_g0_rfu_0" )
			)
			( signal "TP_CH_G_DIMM_G0_RFU_1"
				( objectStatus "@baseboard_fab2_lib.baseboard_fab2(sch_1):tp_ch_g_dimm_g0_rfu_1" )
			)
			( signal "TP_CH_G_DIMM_G0_RFU_2"
				( objectStatus "@baseboard_fab2_lib.baseboard_fab2(sch_1):tp_ch_g_dimm_g0_rfu_2" )
			)
			( signal "TP_CH_G_DIMM0_RFU_0"
				( objectStatus "@baseboard_fab2_lib.baseboard_fab2(sch_1):tp_ch_g_dimm0_rfu_0" )
			)
			( signal "TP_CH_G_DIMM0_RFU_1"
				( objectStatus "@baseboard_fab2_lib.baseboard_fab2(sch_1):tp_ch_g_dimm0_rfu_1" )
			)
			( signal "TP_CH_G_DIMM0_RFU_2"
				( objectStatus "@baseboard_fab2_lib.baseboard_fab2(sch_1):tp_ch_g_dimm0_rfu_2" )
			)
			( signal "M_H_VREF"
				( objectStatus "@baseboard_fab2_lib.baseboard_fab2(sch_1):m_h_vref" )
			)
			( signal "TP_CH_H_DIMM_H0_RFU_0"
				( objectStatus "@baseboard_fab2_lib.baseboard_fab2(sch_1):tp_ch_h_dimm_h0_rfu_0" )
			)
			( signal "TP_CH_H_DIMM_H0_RFU_1"
				( objectStatus "@baseboard_fab2_lib.baseboard_fab2(sch_1):tp_ch_h_dimm_h0_rfu_1" )
			)
			( signal "TP_CH_H_DIMM_H0_RFU_2"
				( objectStatus "@baseboard_fab2_lib.baseboard_fab2(sch_1):tp_ch_h_dimm_h0_rfu_2" )
			)
			( signal "TP_CH_H_DIMM0_RFU_0"
				( objectStatus "@baseboard_fab2_lib.baseboard_fab2(sch_1):tp_ch_h_dimm0_rfu_0" )
			)
			( signal "TP_CH_H_DIMM0_RFU_1"
				( objectStatus "@baseboard_fab2_lib.baseboard_fab2(sch_1):tp_ch_h_dimm0_rfu_1" )
			)
			( signal "TP_CH_H_DIMM0_RFU_2"
				( objectStatus "@baseboard_fab2_lib.baseboard_fab2(sch_1):tp_ch_h_dimm0_rfu_2" )
			)
			( signal "M_J_VREF"
				( objectStatus "@baseboard_fab2_lib.baseboard_fab2(sch_1):m_j_vref" )
			)
			( signal "TP_CH_J_DIMM_J0_RFU_0"
				( objectStatus "@baseboard_fab2_lib.baseboard_fab2(sch_1):tp_ch_j_dimm_j0_rfu_0" )
			)
			( signal "TP_CH_J_DIMM_J0_RFU_1"
				( objectStatus "@baseboard_fab2_lib.baseboard_fab2(sch_1):tp_ch_j_dimm_j0_rfu_1" )
			)
			( signal "TP_CH_J_DIMM_J0_RFU_2"
				( objectStatus "@baseboard_fab2_lib.baseboard_fab2(sch_1):tp_ch_j_dimm_j0_rfu_2" )
			)
			( signal "TP_CH_J_DIMM_J1_RFU_0"
				( objectStatus "@baseboard_fab2_lib.baseboard_fab2(sch_1):tp_ch_j_dimm_j1_rfu_0" )
			)
			( signal "TP_CH_J_DIMM_J1_RFU_1"
				( objectStatus "@baseboard_fab2_lib.baseboard_fab2(sch_1):tp_ch_j_dimm_j1_rfu_1" )
			)
			( signal "TP_CH_J_DIMM_J1_RFU_2"
				( objectStatus "@baseboard_fab2_lib.baseboard_fab2(sch_1):tp_ch_j_dimm_j1_rfu_2" )
			)
			( signal "FM_ADR_COMPLETE_KLM_N"
				( objectStatus "@baseboard_fab2_lib.baseboard_fab2(sch_1):fm_adr_complete_klm_n" )
			)
			( signal "M_K_VREF"
				( objectStatus "@baseboard_fab2_lib.baseboard_fab2(sch_1):m_k_vref" )
			)
			( signal "P12V_NVDIMM_KLM"
				( attribute "VOLTAGE" "12.0"
					( Units "uVoltage" "V" 1.000000)
					( Status sAliasFlattened )
					( Origin gFrontEnd )
				)
				( objectStatus "@baseboard_fab2_lib.baseboard_fab2(sch_1):p12v_nvdimm_klm" )
			)
			( signal "PVPP_KLM"
				( attribute "VOLTAGE" "2.5V"
					( Units "uVoltage" "V" 1.000000)
					( Status sAliasFlattened )
					( Origin gFrontEnd )
				)
				( objectStatus "@baseboard_fab2_lib.baseboard_fab2(sch_1):pvpp_klm" )
			)
			( signal "PVTT_KLM"
				( attribute "VOLTAGE" "0.6V"
					( Units "uVoltage" "V" 1.000000)
					( Status sAliasFlattened )
					( Origin gFrontEnd )
				)
				( objectStatus "@baseboard_fab2_lib.baseboard_fab2(sch_1):pvtt_klm" )
			)
			( signal "SMB_DDR_KLM_VPP_SCL"
				( objectStatus "@baseboard_fab2_lib.baseboard_fab2(sch_1):smb_ddr_klm_vpp_scl" )
			)
			( signal "SMB_DDR_KLM_VPP_SDA"
				( objectStatus "@baseboard_fab2_lib.baseboard_fab2(sch_1):smb_ddr_klm_vpp_sda" )
			)
			( signal "TP_CH_K_DIMM_K0_RFU_0"
				( objectStatus "@baseboard_fab2_lib.baseboard_fab2(sch_1):tp_ch_k_dimm_k0_rfu_0" )
			)
			( signal "TP_CH_K_DIMM_K0_RFU_1"
				( objectStatus "@baseboard_fab2_lib.baseboard_fab2(sch_1):tp_ch_k_dimm_k0_rfu_1" )
			)
			( signal "TP_CH_K_DIMM_K0_RFU_2"
				( objectStatus "@baseboard_fab2_lib.baseboard_fab2(sch_1):tp_ch_k_dimm_k0_rfu_2" )
			)
			( signal "TP_CH_K_DIMM0_RFU_0"
				( objectStatus "@baseboard_fab2_lib.baseboard_fab2(sch_1):tp_ch_k_dimm0_rfu_0" )
			)
			( signal "TP_CH_K_DIMM0_RFU_1"
				( objectStatus "@baseboard_fab2_lib.baseboard_fab2(sch_1):tp_ch_k_dimm0_rfu_1" )
			)
			( signal "TP_CH_K_DIMM0_RFU_2"
				( objectStatus "@baseboard_fab2_lib.baseboard_fab2(sch_1):tp_ch_k_dimm0_rfu_2" )
			)
			( signal "M_L_VREF"
				( objectStatus "@baseboard_fab2_lib.baseboard_fab2(sch_1):m_l_vref" )
			)
			( signal "TP_CH_L_DIMM_L0_RFU_0"
				( objectStatus "@baseboard_fab2_lib.baseboard_fab2(sch_1):tp_ch_l_dimm_l0_rfu_0" )
			)
			( signal "TP_CH_L_DIMM_L0_RFU_1"
				( objectStatus "@baseboard_fab2_lib.baseboard_fab2(sch_1):tp_ch_l_dimm_l0_rfu_1" )
			)
			( signal "TP_CH_L_DIMM_L0_RFU_2"
				( objectStatus "@baseboard_fab2_lib.baseboard_fab2(sch_1):tp_ch_l_dimm_l0_rfu_2" )
			)
			( signal "TP_CH_L_DIMM0_RFU_0"
				( objectStatus "@baseboard_fab2_lib.baseboard_fab2(sch_1):tp_ch_l_dimm0_rfu_0" )
			)
			( signal "TP_CH_L_DIMM0_RFU_1"
				( objectStatus "@baseboard_fab2_lib.baseboard_fab2(sch_1):tp_ch_l_dimm0_rfu_1" )
			)
			( signal "TP_CH_L_DIMM0_RFU_2"
				( objectStatus "@baseboard_fab2_lib.baseboard_fab2(sch_1):tp_ch_l_dimm0_rfu_2" )
			)
			( signal "M_M_VREF"
				( objectStatus "@baseboard_fab2_lib.baseboard_fab2(sch_1):m_m_vref" )
			)
			( signal "TP_CH_M_DIMM_M0_RFU_0"
				( objectStatus "@baseboard_fab2_lib.baseboard_fab2(sch_1):tp_ch_m_dimm_m0_rfu_0" )
			)
			( signal "TP_CH_M_DIMM_M0_RFU_1"
				( objectStatus "@baseboard_fab2_lib.baseboard_fab2(sch_1):tp_ch_m_dimm_m0_rfu_1" )
			)
			( signal "TP_CH_M_DIMM_M0_RFU_2"
				( objectStatus "@baseboard_fab2_lib.baseboard_fab2(sch_1):tp_ch_m_dimm_m0_rfu_2" )
			)
			( signal "TP_CH_M_DIMM_M1_RFU_0"
				( objectStatus "@baseboard_fab2_lib.baseboard_fab2(sch_1):tp_ch_m_dimm_m1_rfu_0" )
			)
			( signal "TP_CH_M_DIMM_M1_RFU_1"
				( objectStatus "@baseboard_fab2_lib.baseboard_fab2(sch_1):tp_ch_m_dimm_m1_rfu_1" )
			)
			( signal "TP_CH_M_DIMM_M1_RFU_2"
				( objectStatus "@baseboard_fab2_lib.baseboard_fab2(sch_1):tp_ch_m_dimm_m1_rfu_2" )
			)
			( signal "FM_ADR_COMPLETE"
				( objectStatus "@baseboard_fab2_lib.baseboard_fab2(sch_1):fm_adr_complete" )
			)
			( signal "FM_ADR_COMPLETE_DLY"
				( objectStatus "@baseboard_fab2_lib.baseboard_fab2(sch_1):fm_adr_complete_dly" )
			)
			( signal "FM_ADR_COMPLETE_R"
				( objectStatus "@baseboard_fab2_lib.baseboard_fab2(sch_1):fm_adr_complete_r" )
			)
			( signal "FAN_PWM_OUT_SYS0"
				( objectStatus "@baseboard_fab2_lib.baseboard_fab2(sch_1):fan_pwm_out_sys0" )
			)
			( signal "IRQ_DIMM_SAVE_LVT3"
				( objectStatus "@baseboard_fab2_lib.baseboard_fab2(sch_1):irq_dimm_save_lvt3" )
			)
			( signal "FAN_PWM_OUT_SYS1"
				( objectStatus "@baseboard_fab2_lib.baseboard_fab2(sch_1):fan_pwm_out_sys1" )
			)
			( signal "RMII_BMC_PCH_SPRNGVLLE_TXD0_R"
				( objectStatus "@baseboard_fab2_lib.baseboard_fab2(sch_1):rmii_bmc_pch_sprngvlle_txd0_r" )
			)
			( signal "RMII_BMC_SPRNGVLLE_TXEN_R"
				( objectStatus "@baseboard_fab2_lib.baseboard_fab2(sch_1):rmii_bmc_sprngvlle_txen_r" )
			)
			( signal "RMII_BMC_OCP_TXD0_R"
				( objectStatus "@baseboard_fab2_lib.baseboard_fab2(sch_1):rmii_bmc_ocp_txd0_r" )
			)
			( signal "RMII_BMC_OCP_CRSDV"
				( objectStatus "@baseboard_fab2_lib.baseboard_fab2(sch_1):rmii_bmc_ocp_crsdv" )
			)
			( signal "FM_BMC_SYS_THROTTLE_R_N"
				( objectStatus "@baseboard_fab2_lib.baseboard_fab2(sch_1):fm_bmc_sys_throttle_r_n" )
			)
			( signal "SPI_BMC_BT_CS0_N"
				( objectStatus "@baseboard_fab2_lib.baseboard_fab2(sch_1):spi_bmc_bt_cs0_n" )
			)
			( signal "IRQ_DIMM_SAVE_N"
				( objectStatus "@baseboard_fab2_lib.baseboard_fab2(sch_1):irq_dimm_save_n" )
			)
			( signal "IRQ_DIMM_SAVE_R_N"
				( objectStatus "@baseboard_fab2_lib.baseboard_fab2(sch_1):irq_dimm_save_r_n" )
			)
			( signal "P3V3"
				( attribute "VOLTAGE" "3.3V"
					( Units "uVoltage" "V" 1.000000)
					( Status sAliasFlattened )
					( Status sAliasConflict )
					( Origin gFrontEnd )
				)
				( objectStatus "@baseboard_fab2_lib.baseboard_fab2(sch_1):p3v3" )
			)
			( signal "PWRGD_PVPP_ABC"
				( objectStatus "@baseboard_fab2_lib.baseboard_fab2(sch_1):pwrgd_pvpp_abc" )
			)
			( signal "SMB_OCP_FRU_STBY_LVC3_SCL"
				( objectStatus "@baseboard_fab2_lib.baseboard_fab2(sch_1):smb_ocp_fru_stby_lvc3_scl" )
			)
			( signal "SMB_OCP_FRU_STBY_LVC3_SDA"
				( objectStatus "@baseboard_fab2_lib.baseboard_fab2(sch_1):smb_ocp_fru_stby_lvc3_sda" )
			)
			( signal "TP_HFI_IO_CONN0_RSVD_17"
				( objectStatus "@baseboard_fab2_lib.baseboard_fab2(sch_1):tp_hfi_io_conn0_rsvd_17" )
			)
			( signal "FM_CPU0_FIVR_FAULT_LVT3"
				( objectStatus "@baseboard_fab2_lib.baseboard_fab2(sch_1):fm_cpu0_fivr_fault_lvt3" )
			)
			( signal "FM_CPU0_FIVR_FAULT_R_LVT3"
				( objectStatus "@baseboard_fab2_lib.baseboard_fab2(sch_1):fm_cpu0_fivr_fault_r_lvt3" )
			)
			( signal "FM_CPU0_THERMTRIP_LVT3_N"
				( objectStatus "@baseboard_fab2_lib.baseboard_fab2(sch_1):fm_cpu0_thermtrip_lvt3_n" )
			)
			( signal "FM_CPU0_THERMTRIP_LVT3_R_N"
				( objectStatus "@baseboard_fab2_lib.baseboard_fab2(sch_1):fm_cpu0_thermtrip_lvt3_r_n" )
			)
			( signal "FM_CPU1_FIVR_FAULT_LVT3"
				( objectStatus "@baseboard_fab2_lib.baseboard_fab2(sch_1):fm_cpu1_fivr_fault_lvt3" )
			)
			( signal "FM_CPU1_FIVR_FAULT_R_LVT3"
				( objectStatus "@baseboard_fab2_lib.baseboard_fab2(sch_1):fm_cpu1_fivr_fault_r_lvt3" )
			)
			( signal "FM_CPU1_THERMTRIP_LVT3_N"
				( objectStatus "@baseboard_fab2_lib.baseboard_fab2(sch_1):fm_cpu1_thermtrip_lvt3_n" )
			)
			( signal "FM_CPU1_THERMTRIP_LVT3_R_N"
				( objectStatus "@baseboard_fab2_lib.baseboard_fab2(sch_1):fm_cpu1_thermtrip_lvt3_r_n" )
			)
			( signal "FM_CPU_CATERR_LVT3_N"
				( objectStatus "@baseboard_fab2_lib.baseboard_fab2(sch_1):fm_cpu_caterr_lvt3_n" )
			)
			( signal "FM_CPU_CATERR_LVT3_R2_N"
				( objectStatus "@baseboard_fab2_lib.baseboard_fab2(sch_1):fm_cpu_caterr_lvt3_r2_n" )
			)
			( signal "FM_CPU_ERR2_LVT3_N"
				( objectStatus "@baseboard_fab2_lib.baseboard_fab2(sch_1):fm_cpu_err2_lvt3_n" )
			)
			( signal "FM_CPU_ERR2_LVT3_R_N"
				( objectStatus "@baseboard_fab2_lib.baseboard_fab2(sch_1):fm_cpu_err2_lvt3_r_n" )
			)
			( signal "FM_CPU_MSMI_LVT3_N"
				( objectStatus "@baseboard_fab2_lib.baseboard_fab2(sch_1):fm_cpu_msmi_lvt3_n" )
			)
			( signal "FM_CPU_MSMI_LVT3_R_N"
				( objectStatus "@baseboard_fab2_lib.baseboard_fab2(sch_1):fm_cpu_msmi_lvt3_r_n" )
			)
			( signal "H_CPU_CATERR_G_N"
				( objectStatus "@baseboard_fab2_lib.baseboard_fab2(sch_1):h_cpu_caterr_g_n" )
			)
			( signal "H_CPU_ERR2_G_R_N"
				( objectStatus "@baseboard_fab2_lib.baseboard_fab2(sch_1):h_cpu_err2_g_r_n" )
			)
			( signal "H_CPU_ERR2_GTL_N"
				( objectStatus "@baseboard_fab2_lib.baseboard_fab2(sch_1):h_cpu_err2_gtl_n" )
			)
			( signal "H_CPU_MSMI_G_N"
				( objectStatus "@baseboard_fab2_lib.baseboard_fab2(sch_1):h_cpu_msmi_g_n" )
			)
			( signal "P0V7_GTL2104_VREF_0"
				( attribute "VOLTAGE" "+0.7 V"
					( Units "uVoltage" "V" 1.000000)
					( Status sAliasFlattened )
					( Origin gFrontEnd )
				)
				( objectStatus "@baseboard_fab2_lib.baseboard_fab2(sch_1):p0v7_gtl2104_vref_0" )
			)
			( signal "P0V7_GTL2104_VREF_1"
				( attribute "VOLTAGE" "+0.7 V"
					( Units "uVoltage" "V" 1.000000)
					( Status sAliasFlattened )
					( Origin gFrontEnd )
				)
				( objectStatus "@baseboard_fab2_lib.baseboard_fab2(sch_1):p0v7_gtl2104_vref_1" )
			)
			( signal "PD_GTL2104_DIR_0"
				( objectStatus "@baseboard_fab2_lib.baseboard_fab2(sch_1):pd_gtl2104_dir_0" )
			)
			( signal "PD_GTL2104_DIR_1"
				( objectStatus "@baseboard_fab2_lib.baseboard_fab2(sch_1):pd_gtl2104_dir_1" )
			)
			( signal "PWRGD_CPUPWRGD"
				( objectStatus "@baseboard_fab2_lib.baseboard_fab2(sch_1):pwrgd_cpupwrgd" )
			)
			( signal "PWRGD_CPUPWRGD_GTL"
				( objectStatus "@baseboard_fab2_lib.baseboard_fab2(sch_1):pwrgd_cpupwrgd_gtl" )
			)
			( signal "PWRGD_CPUPWRGD_R1"
				( objectStatus "@baseboard_fab2_lib.baseboard_fab2(sch_1):pwrgd_cpupwrgd_r1" )
			)
			( signal "FM_CPU0_PROCHOT_LVT3_BMC_N"
				( objectStatus "@baseboard_fab2_lib.baseboard_fab2(sch_1):fm_cpu0_prochot_lvt3_bmc_n" )
			)
			( signal "FM_CPU0_PROCHOT_LVT3_K_N"
				( objectStatus "@baseboard_fab2_lib.baseboard_fab2(sch_1):fm_cpu0_prochot_lvt3_k_n" )
			)
			( signal "FM_CPU0_PROCHOT_LVT3_N"
				( objectStatus "@baseboard_fab2_lib.baseboard_fab2(sch_1):fm_cpu0_prochot_lvt3_n" )
			)
			( signal "FM_CPU0_PROCHOT_LVT3_R_N"
				( objectStatus "@baseboard_fab2_lib.baseboard_fab2(sch_1):fm_cpu0_prochot_lvt3_r_n" )
			)
			( signal "FM_CPU0_PROCHOT_PCH_N"
				( objectStatus "@baseboard_fab2_lib.baseboard_fab2(sch_1):fm_cpu0_prochot_pch_n" )
			)
			( signal "FM_CPU1_PROCHOT_LVT3_BMC_N"
				( objectStatus "@baseboard_fab2_lib.baseboard_fab2(sch_1):fm_cpu1_prochot_lvt3_bmc_n" )
			)
			( signal "FM_CPU1_PROCHOT_LVT3_K_N"
				( objectStatus "@baseboard_fab2_lib.baseboard_fab2(sch_1):fm_cpu1_prochot_lvt3_k_n" )
			)
			( signal "FM_CPU1_PROCHOT_LVT3_N"
				( objectStatus "@baseboard_fab2_lib.baseboard_fab2(sch_1):fm_cpu1_prochot_lvt3_n" )
			)
			( signal "FM_CPU1_PROCHOT_LVT3_R_N"
				( objectStatus "@baseboard_fab2_lib.baseboard_fab2(sch_1):fm_cpu1_prochot_lvt3_r_n" )
			)
			( signal "FM_CPU1_PROCHOT_PCH_N"
				( objectStatus "@baseboard_fab2_lib.baseboard_fab2(sch_1):fm_cpu1_prochot_pch_n" )
			)
			( signal "FM_CPU_ERR0_LVT3_BMC_N"
				( objectStatus "@baseboard_fab2_lib.baseboard_fab2(sch_1):fm_cpu_err0_lvt3_bmc_n" )
			)
			( signal "FM_CPU_ERR0_LVT3_K_N"
				( objectStatus "@baseboard_fab2_lib.baseboard_fab2(sch_1):fm_cpu_err0_lvt3_k_n" )
			)
			( signal "FM_CPU_ERR0_LVT3_N"
				( objectStatus "@baseboard_fab2_lib.baseboard_fab2(sch_1):fm_cpu_err0_lvt3_n" )
			)
			( signal "FM_CPU_ERR0_LVT3_R_N"
				( objectStatus "@baseboard_fab2_lib.baseboard_fab2(sch_1):fm_cpu_err0_lvt3_r_n" )
			)
			( signal "FM_CPU_ERR0_PCH_N"
				( objectStatus "@baseboard_fab2_lib.baseboard_fab2(sch_1):fm_cpu_err0_pch_n" )
			)
			( signal "FM_CPU_ERR1_LVT3_BMC_N"
				( objectStatus "@baseboard_fab2_lib.baseboard_fab2(sch_1):fm_cpu_err1_lvt3_bmc_n" )
			)
			( signal "FM_CPU_ERR1_LVT3_K_N"
				( objectStatus "@baseboard_fab2_lib.baseboard_fab2(sch_1):fm_cpu_err1_lvt3_k_n" )
			)
			( signal "FM_CPU_ERR1_LVT3_N"
				( objectStatus "@baseboard_fab2_lib.baseboard_fab2(sch_1):fm_cpu_err1_lvt3_n" )
			)
			( signal "FM_CPU_ERR1_LVT3_R_N"
				( objectStatus "@baseboard_fab2_lib.baseboard_fab2(sch_1):fm_cpu_err1_lvt3_r_n" )
			)
			( signal "FM_CPU_ERR1_PCH_N"
				( objectStatus "@baseboard_fab2_lib.baseboard_fab2(sch_1):fm_cpu_err1_pch_n" )
			)
			( signal "H_CPU0_PROCHOT_G_PCH_N"
				( objectStatus "@baseboard_fab2_lib.baseboard_fab2(sch_1):h_cpu0_prochot_g_pch_n" )
			)
			( signal "H_CPU0_PROCHOT_G_R_N"
				( objectStatus "@baseboard_fab2_lib.baseboard_fab2(sch_1):h_cpu0_prochot_g_r_n" )
			)
			( signal "H_CPU1_PROCHOT_G_PCH_N"
				( objectStatus "@baseboard_fab2_lib.baseboard_fab2(sch_1):h_cpu1_prochot_g_pch_n" )
			)
			( signal "H_CPU1_PROCHOT_G_R_N"
				( objectStatus "@baseboard_fab2_lib.baseboard_fab2(sch_1):h_cpu1_prochot_g_r_n" )
			)
			( signal "H_CPU_ERR0_GTL_N"
				( objectStatus "@baseboard_fab2_lib.baseboard_fab2(sch_1):h_cpu_err0_gtl_n" )
			)
			( signal "H_CPU_ERR0_GTL_R_N"
				( objectStatus "@baseboard_fab2_lib.baseboard_fab2(sch_1):h_cpu_err0_gtl_r_n" )
			)
			( signal "H_CPU_ERR0_PCH_N"
				( objectStatus "@baseboard_fab2_lib.baseboard_fab2(sch_1):h_cpu_err0_pch_n" )
			)
			( signal "H_CPU_ERR1_GTL_N"
				( objectStatus "@baseboard_fab2_lib.baseboard_fab2(sch_1):h_cpu_err1_gtl_n" )
			)
			( signal "H_CPU_ERR1_GTL_R_N"
				( objectStatus "@baseboard_fab2_lib.baseboard_fab2(sch_1):h_cpu_err1_gtl_r_n" )
			)
			( signal "H_CPU_ERR1_PCH_N"
				( objectStatus "@baseboard_fab2_lib.baseboard_fab2(sch_1):h_cpu_err1_pch_n" )
			)
			( signal "P0V7_GTL2104_5_VREF"
				( attribute "VOLTAGE" "0.734"
					( Units "uVoltage" "V" 1.000000)
					( Status sAliasFlattened )
					( Origin gFrontEnd )
				)
				( objectStatus "@baseboard_fab2_lib.baseboard_fab2(sch_1):p0v7_gtl2104_5_vref" )
			)
			( signal "PD_GTL2104_4_DIR"
				( objectStatus "@baseboard_fab2_lib.baseboard_fab2(sch_1):pd_gtl2104_4_dir" )
			)
			( signal "FM_DIMM_EVENT_FET"
				( objectStatus "@baseboard_fab2_lib.baseboard_fab2(sch_1):fm_dimm_event_fet" )
			)
			( signal "FM_MEM_THERM_EVENT_LVT3_N"
				( objectStatus "@baseboard_fab2_lib.baseboard_fab2(sch_1):fm_mem_therm_event_lvt3_n" )
			)
			( signal "H_CPU0_MEMABC_MEMHOT"
				( objectStatus "@baseboard_fab2_lib.baseboard_fab2(sch_1):h_cpu0_memabc_memhot" )
			)
			( signal "H_CPU0_MEMDEF_MEMHOT"
				( objectStatus "@baseboard_fab2_lib.baseboard_fab2(sch_1):h_cpu0_memdef_memhot" )
			)
			( signal "H_CPU1_MEMGHJ_MEMHOT"
				( objectStatus "@baseboard_fab2_lib.baseboard_fab2(sch_1):h_cpu1_memghj_memhot" )
			)
			( signal "H_CPU1_MEMKLM_MEMHOT"
				( objectStatus "@baseboard_fab2_lib.baseboard_fab2(sch_1):h_cpu1_memklm_memhot" )
			)
			( signal "IRQ_PVDDQ_ABC_VRHOT_LVT3_N"
				( objectStatus "@baseboard_fab2_lib.baseboard_fab2(sch_1):irq_pvddq_abc_vrhot_lvt3_n" )
			)
			( signal "IRQ_PVDDQ_DEF_VRHOT_LVT3_N"
				( objectStatus "@baseboard_fab2_lib.baseboard_fab2(sch_1):irq_pvddq_def_vrhot_lvt3_n" )
			)
			( signal "SP1_BMC_HOST_UART_RX"
				( objectStatus "@baseboard_fab2_lib.baseboard_fab2(sch_1):sp1_bmc_host_uart_rx" )
			)
			( signal "FM_BMC_NMI_N_R"
				( objectStatus "@baseboard_fab2_lib.baseboard_fab2(sch_1):fm_bmc_nmi_n_r" )
			)
			( signal "IRQ_PVDDQ_GHJ_VRHOT_LVT3_N"
				( objectStatus "@baseboard_fab2_lib.baseboard_fab2(sch_1):irq_pvddq_ghj_vrhot_lvt3_n" )
			)
			( signal "PD_SP_ENTEST"
				( objectStatus "@baseboard_fab2_lib.baseboard_fab2(sch_1):pd_sp_entest" )
			)
			( signal "SP1_BMC_HOST_UART_TX"
				( objectStatus "@baseboard_fab2_lib.baseboard_fab2(sch_1):sp1_bmc_host_uart_tx" )
			)
			( signal "P2E_SSB_BMC_RX_DP"
				( objectStatus "@baseboard_fab2_lib.baseboard_fab2(sch_1):p2e_ssb_bmc_rx_dp" )
			)
			( signal "PECI_BMC"
				( objectStatus "@baseboard_fab2_lib.baseboard_fab2(sch_1):peci_bmc" )
			)
			( signal "TP_TPM_SPI_6"
				( objectStatus "@baseboard_fab2_lib.baseboard_fab2(sch_1):tp_tpm_spi_6" )
			)
			( signal "TP_TPM_SPI_3"
				( objectStatus "@baseboard_fab2_lib.baseboard_fab2(sch_1):tp_tpm_spi_3" )
			)
			( signal "IRQ_PVDDQ_KLM_VRHOT_LVT3_N"
				( objectStatus "@baseboard_fab2_lib.baseboard_fab2(sch_1):irq_pvddq_klm_vrhot_lvt3_n" )
			)
			( signal "FM_PVCCIN_CPU0_PWR_IN_ALERT_N"
				( objectStatus "@baseboard_fab2_lib.baseboard_fab2(sch_1):fm_pvccin_cpu0_pwr_in_alert_n" )
			)
			( signal "FM_PVCCIN_CPU1_PWR_IN_ALERT_N"
				( objectStatus "@baseboard_fab2_lib.baseboard_fab2(sch_1):fm_pvccin_cpu1_pwr_in_alert_n" )
			)
			( signal "FM_PWRBRK_N"
				( objectStatus "@baseboard_fab2_lib.baseboard_fab2(sch_1):fm_pwrbrk_n" )
			)
			( signal "FM_SYS_THROTTLE_LVC3"
				( objectStatus "@baseboard_fab2_lib.baseboard_fab2(sch_1):fm_sys_throttle_lvc3" )
			)
			( signal "FM_THROTTLE_N"
				( objectStatus "@baseboard_fab2_lib.baseboard_fab2(sch_1):fm_throttle_n" )
			)
			( signal "FM_THROTTLE_R_N"
				( objectStatus "@baseboard_fab2_lib.baseboard_fab2(sch_1):fm_throttle_r_n" )
			)
			( signal "IRQ_CPU0_PROCHOT_G_N"
				( objectStatus "@baseboard_fab2_lib.baseboard_fab2(sch_1):irq_cpu0_prochot_g_n" )
			)
			( signal "IRQ_CPU0_VRHOT"
				( objectStatus "@baseboard_fab2_lib.baseboard_fab2(sch_1):irq_cpu0_vrhot" )
			)
			( signal "IRQ_CPU1_PROCHOT_G_N"
				( objectStatus "@baseboard_fab2_lib.baseboard_fab2(sch_1):irq_cpu1_prochot_g_n" )
			)
			( signal "IRQ_CPU1_VRHOT"
				( objectStatus "@baseboard_fab2_lib.baseboard_fab2(sch_1):irq_cpu1_vrhot" )
			)
			( signal "IRQ_PVCCIN_CPU0_VRHOT_LVC3_N"
				( objectStatus "@baseboard_fab2_lib.baseboard_fab2(sch_1):irq_pvccin_cpu0_vrhot_lvc3_n" )
			)
			( signal "IRQ_PVCCIN_CPU1_VRHOT_LVC3_N"
				( objectStatus "@baseboard_fab2_lib.baseboard_fab2(sch_1):irq_pvccin_cpu1_vrhot_lvc3_n" )
			)
			( signal "PD_GTL2014_1_VREF"
				( objectStatus "@baseboard_fab2_lib.baseboard_fab2(sch_1):pd_gtl2014_1_vref" )
			)
			( signal "PD_GTL2014_2_VREF"
				( objectStatus "@baseboard_fab2_lib.baseboard_fab2(sch_1):pd_gtl2014_2_vref" )
			)
			( signal "PU_GTL2014_1_DIR"
				( objectStatus "@baseboard_fab2_lib.baseboard_fab2(sch_1):pu_gtl2014_1_dir" )
			)
			( signal "PU_GTL2014_2_DIR"
				( objectStatus "@baseboard_fab2_lib.baseboard_fab2(sch_1):pu_gtl2014_2_dir" )
			)
			( signal "PWRGD_CPU0_LVC3"
				( objectStatus "@baseboard_fab2_lib.baseboard_fab2(sch_1):pwrgd_cpu0_lvc3" )
			)
			( signal "PWRGD_CPU1_LVC3"
				( objectStatus "@baseboard_fab2_lib.baseboard_fab2(sch_1):pwrgd_cpu1_lvc3" )
			)
			( signal "PWRGD_DRAMPWRGD"
				( objectStatus "@baseboard_fab2_lib.baseboard_fab2(sch_1):pwrgd_drampwrgd" )
			)
			( signal "RST_CPU0_LVC3_N"
				( objectStatus "@baseboard_fab2_lib.baseboard_fab2(sch_1):rst_cpu0_lvc3_n" )
			)
			( signal "RST_CPU1_LVC3_N"
				( objectStatus "@baseboard_fab2_lib.baseboard_fab2(sch_1):rst_cpu1_lvc3_n" )
			)
			( signal "SMB_DDR_ABC_SCL_G"
				( objectStatus "@baseboard_fab2_lib.baseboard_fab2(sch_1):smb_ddr_abc_scl_g" )
			)
			( signal "SMB_DDR_ABC_SDA_G"
				( objectStatus "@baseboard_fab2_lib.baseboard_fab2(sch_1):smb_ddr_abc_sda_g" )
			)
			( signal "SMB_DDR_ABC_VPP_SCL_R"
				( objectStatus "@baseboard_fab2_lib.baseboard_fab2(sch_1):smb_ddr_abc_vpp_scl_r" )
			)
			( signal "SMB_DDR_ABC_VPP_SDA_R"
				( objectStatus "@baseboard_fab2_lib.baseboard_fab2(sch_1):smb_ddr_abc_vpp_sda_r" )
			)
			( signal "SMB_DDR_DEF_SCL_G"
				( objectStatus "@baseboard_fab2_lib.baseboard_fab2(sch_1):smb_ddr_def_scl_g" )
			)
			( signal "SMB_DDR_DEF_SDA_G"
				( objectStatus "@baseboard_fab2_lib.baseboard_fab2(sch_1):smb_ddr_def_sda_g" )
			)
			( signal "SMB_DDR_DEF_VPP_SCL_R"
				( objectStatus "@baseboard_fab2_lib.baseboard_fab2(sch_1):smb_ddr_def_vpp_scl_r" )
			)
			( signal "SMB_DDR_DEF_VPP_SDA_R"
				( objectStatus "@baseboard_fab2_lib.baseboard_fab2(sch_1):smb_ddr_def_vpp_sda_r" )
			)
			( signal "SMB_DDR_GHJ_SCL_G"
				( objectStatus "@baseboard_fab2_lib.baseboard_fab2(sch_1):smb_ddr_ghj_scl_g" )
			)
			( signal "SMB_DDR_GHJ_SDA_G"
				( objectStatus "@baseboard_fab2_lib.baseboard_fab2(sch_1):smb_ddr_ghj_sda_g" )
			)
			( signal "SMB_DDR_GHJ_VPP_SCL_R"
				( objectStatus "@baseboard_fab2_lib.baseboard_fab2(sch_1):smb_ddr_ghj_vpp_scl_r" )
			)
			( signal "SMB_DDR_GHJ_VPP_SDA_R"
				( objectStatus "@baseboard_fab2_lib.baseboard_fab2(sch_1):smb_ddr_ghj_vpp_sda_r" )
			)
			( signal "SMB_DDR_KLM_SCL_G"
				( objectStatus "@baseboard_fab2_lib.baseboard_fab2(sch_1):smb_ddr_klm_scl_g" )
			)
			( signal "SMB_DDR_KLM_SDA_G"
				( objectStatus "@baseboard_fab2_lib.baseboard_fab2(sch_1):smb_ddr_klm_sda_g" )
			)
			( signal "SMB_DDR_KLM_VPP_SCL_R"
				( objectStatus "@baseboard_fab2_lib.baseboard_fab2(sch_1):smb_ddr_klm_vpp_scl_r" )
			)
			( signal "SMB_DDR_KLM_VPP_SDA_R"
				( objectStatus "@baseboard_fab2_lib.baseboard_fab2(sch_1):smb_ddr_klm_vpp_sda_r" )
			)
			( signal "TP_SMB_DDR_ABC_EN"
				( objectStatus "@baseboard_fab2_lib.baseboard_fab2(sch_1):tp_smb_ddr_abc_en" )
			)
			( signal "TP_SMB_DDR_DEF_EN"
				( objectStatus "@baseboard_fab2_lib.baseboard_fab2(sch_1):tp_smb_ddr_def_en" )
			)
			( signal "TP_SMB_DDR_GHJ_EN"
				( objectStatus "@baseboard_fab2_lib.baseboard_fab2(sch_1):tp_smb_ddr_ghj_en" )
			)
			( signal "TP_SMB_DDR_KLM_EN"
				( objectStatus "@baseboard_fab2_lib.baseboard_fab2(sch_1):tp_smb_ddr_klm_en" )
			)
			( signal "A_COMP_CKMNG"
				( objectStatus "@baseboard_fab2_lib.baseboard_fab2(sch_1):a_comp_ckmng" )
			)
			( signal "CLK_25M_BMC"
				( objectStatus "@baseboard_fab2_lib.baseboard_fab2(sch_1):clk_25m_bmc" )
			)
			( signal "CLK_25M_BMC_R"
				( objectStatus "@baseboard_fab2_lib.baseboard_fab2(sch_1):clk_25m_bmc_r" )
			)
			( signal "CLK_25M_CPLD"
				( objectStatus "@baseboard_fab2_lib.baseboard_fab2(sch_1):clk_25m_cpld" )
			)
			( signal "CLK_25M_CPLD_R"
				( objectStatus "@baseboard_fab2_lib.baseboard_fab2(sch_1):clk_25m_cpld_r" )
			)
			( signal "CLK_32K_SUSCLK_PLD"
				( objectStatus "@baseboard_fab2_lib.baseboard_fab2(sch_1):clk_32k_susclk_pld" )
			)
			( signal "CLK_32K_SUSCLK_PLD_R"
				( objectStatus "@baseboard_fab2_lib.baseboard_fab2(sch_1):clk_32k_susclk_pld_r" )
			)
			( signal "CLK_50M_CKMNG_BMC_1"
				( objectStatus "@baseboard_fab2_lib.baseboard_fab2(sch_1):clk_50m_ckmng_bmc_1" )
			)
			( signal "CLK_50M_CKMNG_BMC_1_R"
				( objectStatus "@baseboard_fab2_lib.baseboard_fab2(sch_1):clk_50m_ckmng_bmc_1_r" )
			)
			( signal "CLK_50M_CKMNG_BMC_2"
				( objectStatus "@baseboard_fab2_lib.baseboard_fab2(sch_1):clk_50m_ckmng_bmc_2" )
			)
			( signal "CLK_50M_CKMNG_BMC_2_R"
				( objectStatus "@baseboard_fab2_lib.baseboard_fab2(sch_1):clk_50m_ckmng_bmc_2_r" )
			)
			( signal "CLK_50M_CKMNG_OCP"
				( objectStatus "@baseboard_fab2_lib.baseboard_fab2(sch_1):clk_50m_ckmng_ocp" )
			)
			( signal "CLK_50M_CKMNG_OCP_R"
				( objectStatus "@baseboard_fab2_lib.baseboard_fab2(sch_1):clk_50m_ckmng_ocp_r" )
			)
			( signal "CLK_50M_CKMNG_PCH_10GBE"
				( objectStatus "@baseboard_fab2_lib.baseboard_fab2(sch_1):clk_50m_ckmng_pch_10gbe" )
			)
			( signal "CLK_50M_CKMNG_PCH_10GBE_R"
				( objectStatus "@baseboard_fab2_lib.baseboard_fab2(sch_1):clk_50m_ckmng_pch_10gbe_r" )
			)
			( signal "CLK_50M_CKMNG_SPRVLLE"
				( objectStatus "@baseboard_fab2_lib.baseboard_fab2(sch_1):clk_50m_ckmng_sprvlle" )
			)
			( signal "CLK_50M_CKMNG_SPRVLLE_R"
				( objectStatus "@baseboard_fab2_lib.baseboard_fab2(sch_1):clk_50m_ckmng_sprvlle_r" )
			)
			( signal "P3V3_STBY_MNG"
				( attribute "VOLTAGE" "5"
					( Units "uVoltage" "V" 1.000000)
					( Status sAliasFlattened )
					( Origin gFrontEnd )
				)
				( objectStatus "@baseboard_fab2_lib.baseboard_fab2(sch_1):p3v3_stby_mng" )
			)
			( signal "P3V3_STBY_MNG_CPU"
				( attribute "VOLTAGE" "3.3"
					( Units "uVoltage" "V" 1.000000)
					( Status sAliasFlattened )
					( Origin gFrontEnd )
				)
				( objectStatus "@baseboard_fab2_lib.baseboard_fab2(sch_1):p3v3_stby_mng_cpu" )
			)
			( signal "P3V3_STBY_MNG_RGMII"
				( attribute "VOLTAGE" "3.3"
					( Units "uVoltage" "V" 1.000000)
					( Status sAliasFlattened )
					( Origin gFrontEnd )
				)
				( objectStatus "@baseboard_fab2_lib.baseboard_fab2(sch_1):p3v3_stby_mng_rgmii" )
			)
			( signal "P3V3_STBY_MNG_RMII"
				( attribute "VOLTAGE" "3.3"
					( Units "uVoltage" "V" 1.000000)
					( Status sAliasFlattened )
					( Origin gFrontEnd )
				)
				( objectStatus "@baseboard_fab2_lib.baseboard_fab2(sch_1):p3v3_stby_mng_rmii" )
			)
			( signal "PD_CKMNG_OE"
				( objectStatus "@baseboard_fab2_lib.baseboard_fab2(sch_1):pd_ckmng_oe" )
			)
			( signal "PWRGD_P3V3_STBY"
				( objectStatus "@baseboard_fab2_lib.baseboard_fab2(sch_1):pwrgd_p3v3_stby" )
			)
			( signal "SMB_HOST_STBY_LVC3_SCL"
				( objectStatus "@baseboard_fab2_lib.baseboard_fab2(sch_1):smb_host_stby_lvc3_scl" )
			)
			( signal "SMB_HOST_STBY_LVC3_SDA"
				( objectStatus "@baseboard_fab2_lib.baseboard_fab2(sch_1):smb_host_stby_lvc3_sda" )
			)
			( signal "TP_CLK5_50M_CKMNG"
				( objectStatus "@baseboard_fab2_lib.baseboard_fab2(sch_1):tp_clk5_50m_ckmng" )
			)
			( signal "TP_CLK_100M_R_DN"
				( objectStatus "@baseboard_fab2_lib.baseboard_fab2(sch_1):tp_clk_100m_r_dn" )
			)
			( signal "TP_CLK_100M_R_DP"
				( objectStatus "@baseboard_fab2_lib.baseboard_fab2(sch_1):tp_clk_100m_r_dp" )
			)
			( signal "TP_CLK_125M"
				( objectStatus "@baseboard_fab2_lib.baseboard_fab2(sch_1):tp_clk_125m" )
			)
			( signal "TP_CLK_125M_BMCA"
				( objectStatus "@baseboard_fab2_lib.baseboard_fab2(sch_1):tp_clk_125m_bmca" )
			)
			( signal "TP_CLK_96M_CKMNG_N"
				( objectStatus "@baseboard_fab2_lib.baseboard_fab2(sch_1):tp_clk_96m_ckmng_n" )
			)
			( signal "TP_CLK_96M_CKMNG_P"
				( objectStatus "@baseboard_fab2_lib.baseboard_fab2(sch_1):tp_clk_96m_ckmng_p" )
			)
			( signal "XTAL_CK_MNG_IN"
				( objectStatus "@baseboard_fab2_lib.baseboard_fab2(sch_1):xtal_ck_mng_in" )
			)
			( signal "XTAL_CK_MNG_OUT"
				( objectStatus "@baseboard_fab2_lib.baseboard_fab2(sch_1):xtal_ck_mng_out" )
			)
			( signal "CLK_100M_CPU0_BCLK0_R_DN"
				( objectStatus "@baseboard_fab2_lib.baseboard_fab2(sch_1):clk_100m_cpu0_bclk0_r_dn" )
			)
			( signal "CLK_100M_CPU0_BCLK0_R_DP"
				( objectStatus "@baseboard_fab2_lib.baseboard_fab2(sch_1):clk_100m_cpu0_bclk0_r_dp" )
			)
			( signal "CLK_100M_CPU0_BCLK1_R_DN"
				( objectStatus "@baseboard_fab2_lib.baseboard_fab2(sch_1):clk_100m_cpu0_bclk1_r_dn" )
			)
			( signal "CLK_100M_CPU0_BCLK1_R_DP"
				( objectStatus "@baseboard_fab2_lib.baseboard_fab2(sch_1):clk_100m_cpu0_bclk1_r_dp" )
			)
			( signal "CLK_100M_CPU0_BCLK2_R_DN"
				( objectStatus "@baseboard_fab2_lib.baseboard_fab2(sch_1):clk_100m_cpu0_bclk2_r_dn" )
			)
			( signal "CLK_100M_CPU0_BCLK2_R_DP"
				( objectStatus "@baseboard_fab2_lib.baseboard_fab2(sch_1):clk_100m_cpu0_bclk2_r_dp" )
			)
			( signal "CLK_100M_CPU0_PE_REFCLK_R_DN"
				( objectStatus "@baseboard_fab2_lib.baseboard_fab2(sch_1):clk_100m_cpu0_pe_refclk_r_dn" )
			)
			( signal "CLK_100M_CPU0_PE_REFCLK_R_DP"
				( objectStatus "@baseboard_fab2_lib.baseboard_fab2(sch_1):clk_100m_cpu0_pe_refclk_r_dp" )
			)
			( signal "CLK_100M_CPU0_RC_REFCLK0_R_DN"
				( objectStatus "@baseboard_fab2_lib.baseboard_fab2(sch_1):clk_100m_cpu0_rc_refclk0_r_dn" )
			)
			( signal "CLK_100M_CPU0_RC_REFCLK0_R_DP"
				( objectStatus "@baseboard_fab2_lib.baseboard_fab2(sch_1):clk_100m_cpu0_rc_refclk0_r_dp" )
			)
			( signal "CLK_100M_CPU0_RC_REFCLK1_R_DN"
				( objectStatus "@baseboard_fab2_lib.baseboard_fab2(sch_1):clk_100m_cpu0_rc_refclk1_r_dn" )
			)
			( signal "CLK_100M_CPU0_RC_REFCLK1_R_DP"
				( objectStatus "@baseboard_fab2_lib.baseboard_fab2(sch_1):clk_100m_cpu0_rc_refclk1_r_dp" )
			)
			( signal "CLK_100M_CPU1_BCLK0_R_DN"
				( objectStatus "@baseboard_fab2_lib.baseboard_fab2(sch_1):clk_100m_cpu1_bclk0_r_dn" )
			)
			( signal "CLK_100M_CPU1_BCLK0_R_DP"
				( objectStatus "@baseboard_fab2_lib.baseboard_fab2(sch_1):clk_100m_cpu1_bclk0_r_dp" )
			)
			( signal "CLK_100M_CPU1_BCLK1_R_DN"
				( objectStatus "@baseboard_fab2_lib.baseboard_fab2(sch_1):clk_100m_cpu1_bclk1_r_dn" )
			)
			( signal "CLK_100M_CPU1_BCLK1_R_DP"
				( objectStatus "@baseboard_fab2_lib.baseboard_fab2(sch_1):clk_100m_cpu1_bclk1_r_dp" )
			)
			( signal "CLK_100M_CPU1_BCLK2_R_DN"
				( objectStatus "@baseboard_fab2_lib.baseboard_fab2(sch_1):clk_100m_cpu1_bclk2_r_dn" )
			)
			( signal "CLK_100M_CPU1_BCLK2_R_DP"
				( objectStatus "@baseboard_fab2_lib.baseboard_fab2(sch_1):clk_100m_cpu1_bclk2_r_dp" )
			)
			( signal "CLK_100M_CPU1_PE_REFCLK_R_DN"
				( objectStatus "@baseboard_fab2_lib.baseboard_fab2(sch_1):clk_100m_cpu1_pe_refclk_r_dn" )
			)
			( signal "CLK_100M_CPU1_PE_REFCLK_R_DP"
				( objectStatus "@baseboard_fab2_lib.baseboard_fab2(sch_1):clk_100m_cpu1_pe_refclk_r_dp" )
			)
			( signal "CLK_100M_CPU1_RC_REFCLK0_R_DN"
				( objectStatus "@baseboard_fab2_lib.baseboard_fab2(sch_1):clk_100m_cpu1_rc_refclk0_r_dn" )
			)
			( signal "CLK_100M_CPU1_RC_REFCLK0_R_DP"
				( objectStatus "@baseboard_fab2_lib.baseboard_fab2(sch_1):clk_100m_cpu1_rc_refclk0_r_dp" )
			)
			( signal "CLK_100M_CPU1_RC_REFCLK1_R_DN"
				( objectStatus "@baseboard_fab2_lib.baseboard_fab2(sch_1):clk_100m_cpu1_rc_refclk1_r_dn" )
			)
			( signal "CLK_100M_CPU1_RC_REFCLK1_R_DP"
				( objectStatus "@baseboard_fab2_lib.baseboard_fab2(sch_1):clk_100m_cpu1_rc_refclk1_r_dp" )
			)
			( signal "CLK_100M_DB1200_DN"
				( objectStatus "@baseboard_fab2_lib.baseboard_fab2(sch_1):clk_100m_db1200_dn" )
			)
			( signal "CLK_100M_DB1200_DP"
				( objectStatus "@baseboard_fab2_lib.baseboard_fab2(sch_1):clk_100m_db1200_dp" )
			)
			( signal "FM_100M_N"
				( objectStatus "@baseboard_fab2_lib.baseboard_fab2(sch_1):fm_100m_n" )
			)
			( signal "FM_CPU0_MCP_CLK_EN_N"
				( objectStatus "@baseboard_fab2_lib.baseboard_fab2(sch_1):fm_cpu0_mcp_clk_en_n" )
			)
			( signal "FM_CPU1_MCP_CLK_EN_N"
				( objectStatus "@baseboard_fab2_lib.baseboard_fab2(sch_1):fm_cpu1_mcp_clk_en_n" )
			)
			( signal "FM_DB1200_PWRGD"
				( objectStatus "@baseboard_fab2_lib.baseboard_fab2(sch_1):fm_db1200_pwrgd" )
			)
			( signal "FM_DB1200_SMB_SA0"
				( objectStatus "@baseboard_fab2_lib.baseboard_fab2(sch_1):fm_db1200_smb_sa0" )
			)
			( signal "FM_DB1200_SMB_SA1"
				( objectStatus "@baseboard_fab2_lib.baseboard_fab2(sch_1):fm_db1200_smb_sa1" )
			)
			( signal "FM_DB1200ZL_BCLKS_EN_N"
				( objectStatus "@baseboard_fab2_lib.baseboard_fab2(sch_1):fm_db1200zl_bclks_en_n" )
			)
			( signal "FM_HBW_BYPASS_LOWBW_N"
				( objectStatus "@baseboard_fab2_lib.baseboard_fab2(sch_1):fm_hbw_bypass_lowbw_n" )
			)
			( signal "P3V3_DB1200"
				( attribute "VOLTAGE" "5"
					( Units "uVoltage" "V" 1.000000)
					( Status sAliasFlattened )
					( Origin gFrontEnd )
				)
				( objectStatus "@baseboard_fab2_lib.baseboard_fab2(sch_1):p3v3_db1200" )
			)
			( signal "P3V3_DB1200_A"
				( attribute "VOLTAGE" "+3.3V"
					( Units "uVoltage" "V" 1.000000)
					( Status sAliasFlattened )
					( Origin gFrontEnd )
				)
				( objectStatus "@baseboard_fab2_lib.baseboard_fab2(sch_1):p3v3_db1200_a" )
			)
			( signal "P3V3_DB1200_R"
				( attribute "VOLTAGE" "+3.3V"
					( Units "uVoltage" "V" 1.000000)
					( Status sAliasFlattened )
					( Origin gFrontEnd )
				)
				( objectStatus "@baseboard_fab2_lib.baseboard_fab2(sch_1):p3v3_db1200_r" )
			)
			( signal "SMB_HOST_STBY_LVC3_SCL_R2"
				( objectStatus "@baseboard_fab2_lib.baseboard_fab2(sch_1):smb_host_stby_lvc3_scl_r2" )
			)
			( signal "SMB_HOST_STBY_LVC3_SDA_R2"
				( objectStatus "@baseboard_fab2_lib.baseboard_fab2(sch_1):smb_host_stby_lvc3_sda_r2" )
			)
			( signal "CLK_156M_OSC_BRD_CPU0_DN"
				( objectStatus "@baseboard_fab2_lib.baseboard_fab2(sch_1):clk_156m_osc_brd_cpu0_dn" )
			)
			( signal "CLK_156M_OSC_BRD_CPU0_DP"
				( objectStatus "@baseboard_fab2_lib.baseboard_fab2(sch_1):clk_156m_osc_brd_cpu0_dp" )
			)
			( signal "CLK_156M_OSC_BRD_CPU1_DN"
				( objectStatus "@baseboard_fab2_lib.baseboard_fab2(sch_1):clk_156m_osc_brd_cpu1_dn" )
			)
			( signal "CLK_156M_OSC_BRD_CPU1_DP"
				( objectStatus "@baseboard_fab2_lib.baseboard_fab2(sch_1):clk_156m_osc_brd_cpu1_dp" )
			)
			( signal "CLK_322M_156M_CPU0_OSC_VRM_DN"
				( objectStatus "@baseboard_fab2_lib.baseboard_fab2(sch_1):clk_322m_156m_cpu0_osc_vrm_dn" )
			)
			( signal "CLK_322M_156M_CPU0_OSC_VRM_DP"
				( objectStatus "@baseboard_fab2_lib.baseboard_fab2(sch_1):clk_322m_156m_cpu0_osc_vrm_dp" )
			)
			( signal "CLK_322M_156M_CPU1_OSC_VRM_DN"
				( objectStatus "@baseboard_fab2_lib.baseboard_fab2(sch_1):clk_322m_156m_cpu1_osc_vrm_dn" )
			)
			( signal "CLK_322M_156M_CPU1_OSC_VRM_DP"
				( objectStatus "@baseboard_fab2_lib.baseboard_fab2(sch_1):clk_322m_156m_cpu1_osc_vrm_dp" )
			)
			( signal "FM_156M_CPU0_BRD_OSC_EN"
				( objectStatus "@baseboard_fab2_lib.baseboard_fab2(sch_1):fm_156m_cpu0_brd_osc_en" )
			)
			( signal "FM_156M_CPU1_BRD_OSC_EN"
				( objectStatus "@baseboard_fab2_lib.baseboard_fab2(sch_1):fm_156m_cpu1_brd_osc_en" )
			)
			( signal "FM_CPU0_STL_BRD_OSC_EN"
				( objectStatus "@baseboard_fab2_lib.baseboard_fab2(sch_1):fm_cpu0_stl_brd_osc_en" )
			)
			( signal "FM_CPU0_VRM_322M_156M_OSC_EN"
				( objectStatus "@baseboard_fab2_lib.baseboard_fab2(sch_1):fm_cpu0_vrm_322m_156m_osc_en" )
			)
			( signal "FM_CPU0_VRM_OSC_EN"
				( objectStatus "@baseboard_fab2_lib.baseboard_fab2(sch_1):fm_cpu0_vrm_osc_en" )
			)
			( signal "FM_CPU1_STL_BRD_OSC_EN"
				( objectStatus "@baseboard_fab2_lib.baseboard_fab2(sch_1):fm_cpu1_stl_brd_osc_en" )
			)
			( signal "FM_CPU1_VRM_322M_156M_OSC_EN"
				( objectStatus "@baseboard_fab2_lib.baseboard_fab2(sch_1):fm_cpu1_vrm_322m_156m_osc_en" )
			)
			( signal "FM_CPU1_VRM_OSC_EN"
				( objectStatus "@baseboard_fab2_lib.baseboard_fab2(sch_1):fm_cpu1_vrm_osc_en" )
			)
			( signal "P3E_CPU0_PE1_PCH_C_TXN<8>"
				( objectStatus "@baseboard_fab2_lib.baseboard_fab2(sch_1):p3e_cpu0_pe1_pch_c_txn(8)" )
			)
			( signal "P3E_CPU0_PE1_PCH_C_TXN<9>"
				( objectStatus "@baseboard_fab2_lib.baseboard_fab2(sch_1):p3e_cpu0_pe1_pch_c_txn(9)" )
			)
			( signal "P3E_CPU0_PE1_PCH_C_TXN<10>"
				( objectStatus "@baseboard_fab2_lib.baseboard_fab2(sch_1):p3e_cpu0_pe1_pch_c_txn(10)" )
			)
			( signal "P3E_CPU0_PE1_PCH_C_TXN<11>"
				( objectStatus "@baseboard_fab2_lib.baseboard_fab2(sch_1):p3e_cpu0_pe1_pch_c_txn(11)" )
			)
			( signal "P3E_CPU0_PE1_PCH_C_TXN<12>"
				( objectStatus "@baseboard_fab2_lib.baseboard_fab2(sch_1):p3e_cpu0_pe1_pch_c_txn(12)" )
			)
			( signal "P3E_CPU0_PE1_PCH_C_TXN<13>"
				( objectStatus "@baseboard_fab2_lib.baseboard_fab2(sch_1):p3e_cpu0_pe1_pch_c_txn(13)" )
			)
			( signal "P3E_CPU0_PE1_PCH_C_TXN<14>"
				( objectStatus "@baseboard_fab2_lib.baseboard_fab2(sch_1):p3e_cpu0_pe1_pch_c_txn(14)" )
			)
			( signal "P3E_CPU0_PE1_PCH_C_TXN<15>"
				( objectStatus "@baseboard_fab2_lib.baseboard_fab2(sch_1):p3e_cpu0_pe1_pch_c_txn(15)" )
			)
			( signal "P3E_CPU0_PE1_PCH_C_TXP<8>"
				( objectStatus "@baseboard_fab2_lib.baseboard_fab2(sch_1):p3e_cpu0_pe1_pch_c_txp(8)" )
			)
			( signal "P3E_CPU0_PE1_PCH_C_TXP<9>"
				( objectStatus "@baseboard_fab2_lib.baseboard_fab2(sch_1):p3e_cpu0_pe1_pch_c_txp(9)" )
			)
			( signal "P3E_CPU0_PE1_PCH_C_TXP<10>"
				( objectStatus "@baseboard_fab2_lib.baseboard_fab2(sch_1):p3e_cpu0_pe1_pch_c_txp(10)" )
			)
			( signal "P3E_CPU0_PE1_PCH_C_TXP<11>"
				( objectStatus "@baseboard_fab2_lib.baseboard_fab2(sch_1):p3e_cpu0_pe1_pch_c_txp(11)" )
			)
			( signal "P3E_CPU0_PE1_PCH_C_TXP<12>"
				( objectStatus "@baseboard_fab2_lib.baseboard_fab2(sch_1):p3e_cpu0_pe1_pch_c_txp(12)" )
			)
			( signal "P3E_CPU0_PE1_PCH_C_TXP<13>"
				( objectStatus "@baseboard_fab2_lib.baseboard_fab2(sch_1):p3e_cpu0_pe1_pch_c_txp(13)" )
			)
			( signal "P3E_CPU0_PE1_PCH_C_TXP<14>"
				( objectStatus "@baseboard_fab2_lib.baseboard_fab2(sch_1):p3e_cpu0_pe1_pch_c_txp(14)" )
			)
			( signal "P3E_CPU0_PE1_PCH_C_TXP<15>"
				( objectStatus "@baseboard_fab2_lib.baseboard_fab2(sch_1):p3e_cpu0_pe1_pch_c_txp(15)" )
			)
			( signal "P3E_CPU0_PE1_PCH_R_RXN<8>"
				( objectStatus "@baseboard_fab2_lib.baseboard_fab2(sch_1):p3e_cpu0_pe1_pch_r_rxn(8)" )
			)
			( signal "P3E_CPU0_PE1_PCH_R_RXN<9>"
				( objectStatus "@baseboard_fab2_lib.baseboard_fab2(sch_1):p3e_cpu0_pe1_pch_r_rxn(9)" )
			)
			( signal "P3E_CPU0_PE1_PCH_R_RXN<10>"
				( objectStatus "@baseboard_fab2_lib.baseboard_fab2(sch_1):p3e_cpu0_pe1_pch_r_rxn(10)" )
			)
			( signal "P3E_CPU0_PE1_PCH_R_RXN<11>"
				( objectStatus "@baseboard_fab2_lib.baseboard_fab2(sch_1):p3e_cpu0_pe1_pch_r_rxn(11)" )
			)
			( signal "P3E_CPU0_PE1_PCH_R_RXN<12>"
				( objectStatus "@baseboard_fab2_lib.baseboard_fab2(sch_1):p3e_cpu0_pe1_pch_r_rxn(12)" )
			)
			( signal "P3E_CPU0_PE1_PCH_R_RXN<13>"
				( objectStatus "@baseboard_fab2_lib.baseboard_fab2(sch_1):p3e_cpu0_pe1_pch_r_rxn(13)" )
			)
			( signal "P3E_CPU0_PE1_PCH_R_RXN<14>"
				( objectStatus "@baseboard_fab2_lib.baseboard_fab2(sch_1):p3e_cpu0_pe1_pch_r_rxn(14)" )
			)
			( signal "P3E_CPU0_PE1_PCH_R_RXN<15>"
				( objectStatus "@baseboard_fab2_lib.baseboard_fab2(sch_1):p3e_cpu0_pe1_pch_r_rxn(15)" )
			)
			( signal "P3E_CPU0_PE1_PCH_R_RXP<8>"
				( objectStatus "@baseboard_fab2_lib.baseboard_fab2(sch_1):p3e_cpu0_pe1_pch_r_rxp(8)" )
			)
			( signal "P3E_CPU0_PE1_PCH_R_RXP<9>"
				( objectStatus "@baseboard_fab2_lib.baseboard_fab2(sch_1):p3e_cpu0_pe1_pch_r_rxp(9)" )
			)
			( signal "P3E_CPU0_PE1_PCH_R_RXP<10>"
				( objectStatus "@baseboard_fab2_lib.baseboard_fab2(sch_1):p3e_cpu0_pe1_pch_r_rxp(10)" )
			)
			( signal "P3E_CPU0_PE1_PCH_R_RXP<11>"
				( objectStatus "@baseboard_fab2_lib.baseboard_fab2(sch_1):p3e_cpu0_pe1_pch_r_rxp(11)" )
			)
			( signal "P3E_CPU0_PE1_PCH_R_RXP<12>"
				( objectStatus "@baseboard_fab2_lib.baseboard_fab2(sch_1):p3e_cpu0_pe1_pch_r_rxp(12)" )
			)
			( signal "P3E_CPU0_PE1_PCH_R_RXP<13>"
				( objectStatus "@baseboard_fab2_lib.baseboard_fab2(sch_1):p3e_cpu0_pe1_pch_r_rxp(13)" )
			)
			( signal "P3E_CPU0_PE1_PCH_R_RXP<14>"
				( objectStatus "@baseboard_fab2_lib.baseboard_fab2(sch_1):p3e_cpu0_pe1_pch_r_rxp(14)" )
			)
			( signal "P3E_CPU0_PE1_PCH_R_RXP<15>"
				( objectStatus "@baseboard_fab2_lib.baseboard_fab2(sch_1):p3e_cpu0_pe1_pch_r_rxp(15)" )
			)
			( signal "P3E_CPU0_PE2_SS_C_TXN<0>"
				( objectStatus "@baseboard_fab2_lib.baseboard_fab2(sch_1):p3e_cpu0_pe2_ss_c_txn(0)" )
			)
			( signal "P3E_CPU0_PE2_SS_C_TXN<1>"
				( objectStatus "@baseboard_fab2_lib.baseboard_fab2(sch_1):p3e_cpu0_pe2_ss_c_txn(1)" )
			)
			( signal "P3E_CPU0_PE2_SS_C_TXN<2>"
				( objectStatus "@baseboard_fab2_lib.baseboard_fab2(sch_1):p3e_cpu0_pe2_ss_c_txn(2)" )
			)
			( signal "P3E_CPU0_PE2_SS_C_TXN<3>"
				( objectStatus "@baseboard_fab2_lib.baseboard_fab2(sch_1):p3e_cpu0_pe2_ss_c_txn(3)" )
			)
			( signal "P3E_CPU0_PE2_SS_C_TXN<4>"
				( objectStatus "@baseboard_fab2_lib.baseboard_fab2(sch_1):p3e_cpu0_pe2_ss_c_txn(4)" )
			)
			( signal "P3E_CPU0_PE2_SS_C_TXN<5>"
				( objectStatus "@baseboard_fab2_lib.baseboard_fab2(sch_1):p3e_cpu0_pe2_ss_c_txn(5)" )
			)
			( signal "P3E_CPU0_PE2_SS_C_TXN<6>"
				( objectStatus "@baseboard_fab2_lib.baseboard_fab2(sch_1):p3e_cpu0_pe2_ss_c_txn(6)" )
			)
			( signal "P3E_CPU0_PE2_SS_C_TXN<7>"
				( objectStatus "@baseboard_fab2_lib.baseboard_fab2(sch_1):p3e_cpu0_pe2_ss_c_txn(7)" )
			)
			( signal "P3E_CPU0_PE2_SS_C_TXN<8>"
				( objectStatus "@baseboard_fab2_lib.baseboard_fab2(sch_1):p3e_cpu0_pe2_ss_c_txn(8)" )
			)
			( signal "P3E_CPU0_PE2_SS_C_TXN<9>"
				( objectStatus "@baseboard_fab2_lib.baseboard_fab2(sch_1):p3e_cpu0_pe2_ss_c_txn(9)" )
			)
			( signal "P3E_CPU0_PE2_SS_C_TXN<10>"
				( objectStatus "@baseboard_fab2_lib.baseboard_fab2(sch_1):p3e_cpu0_pe2_ss_c_txn(10)" )
			)
			( signal "P3E_CPU0_PE2_SS_C_TXN<11>"
				( objectStatus "@baseboard_fab2_lib.baseboard_fab2(sch_1):p3e_cpu0_pe2_ss_c_txn(11)" )
			)
			( signal "P3E_CPU0_PE2_SS_C_TXN<12>"
				( objectStatus "@baseboard_fab2_lib.baseboard_fab2(sch_1):p3e_cpu0_pe2_ss_c_txn(12)" )
			)
			( signal "P3E_CPU0_PE2_SS_C_TXN<13>"
				( objectStatus "@baseboard_fab2_lib.baseboard_fab2(sch_1):p3e_cpu0_pe2_ss_c_txn(13)" )
			)
			( signal "P3E_CPU0_PE2_SS_C_TXN<14>"
				( objectStatus "@baseboard_fab2_lib.baseboard_fab2(sch_1):p3e_cpu0_pe2_ss_c_txn(14)" )
			)
			( signal "P3E_CPU0_PE2_SS_C_TXN<15>"
				( objectStatus "@baseboard_fab2_lib.baseboard_fab2(sch_1):p3e_cpu0_pe2_ss_c_txn(15)" )
			)
			( signal "P3E_CPU0_PE2_SS_C_TXP<0>"
				( objectStatus "@baseboard_fab2_lib.baseboard_fab2(sch_1):p3e_cpu0_pe2_ss_c_txp(0)" )
			)
			( signal "P3E_CPU0_PE2_SS_C_TXP<1>"
				( objectStatus "@baseboard_fab2_lib.baseboard_fab2(sch_1):p3e_cpu0_pe2_ss_c_txp(1)" )
			)
			( signal "P3E_CPU0_PE2_SS_C_TXP<2>"
				( objectStatus "@baseboard_fab2_lib.baseboard_fab2(sch_1):p3e_cpu0_pe2_ss_c_txp(2)" )
			)
			( signal "P3E_CPU0_PE2_SS_C_TXP<3>"
				( objectStatus "@baseboard_fab2_lib.baseboard_fab2(sch_1):p3e_cpu0_pe2_ss_c_txp(3)" )
			)
			( signal "P3E_CPU0_PE2_SS_C_TXP<4>"
				( objectStatus "@baseboard_fab2_lib.baseboard_fab2(sch_1):p3e_cpu0_pe2_ss_c_txp(4)" )
			)
			( signal "P3E_CPU0_PE2_SS_C_TXP<5>"
				( objectStatus "@baseboard_fab2_lib.baseboard_fab2(sch_1):p3e_cpu0_pe2_ss_c_txp(5)" )
			)
			( signal "P3E_CPU0_PE2_SS_C_TXP<6>"
				( objectStatus "@baseboard_fab2_lib.baseboard_fab2(sch_1):p3e_cpu0_pe2_ss_c_txp(6)" )
			)
			( signal "P3E_CPU0_PE2_SS_C_TXP<7>"
				( objectStatus "@baseboard_fab2_lib.baseboard_fab2(sch_1):p3e_cpu0_pe2_ss_c_txp(7)" )
			)
			( signal "P3E_CPU0_PE2_SS_C_TXP<8>"
				( objectStatus "@baseboard_fab2_lib.baseboard_fab2(sch_1):p3e_cpu0_pe2_ss_c_txp(8)" )
			)
			( signal "P3E_CPU0_PE2_SS_C_TXP<9>"
				( objectStatus "@baseboard_fab2_lib.baseboard_fab2(sch_1):p3e_cpu0_pe2_ss_c_txp(9)" )
			)
			( signal "P3E_CPU0_PE2_SS_C_TXP<10>"
				( objectStatus "@baseboard_fab2_lib.baseboard_fab2(sch_1):p3e_cpu0_pe2_ss_c_txp(10)" )
			)
			( signal "P3E_CPU0_PE2_SS_C_TXP<11>"
				( objectStatus "@baseboard_fab2_lib.baseboard_fab2(sch_1):p3e_cpu0_pe2_ss_c_txp(11)" )
			)
			( signal "P3E_CPU0_PE2_SS_C_TXP<12>"
				( objectStatus "@baseboard_fab2_lib.baseboard_fab2(sch_1):p3e_cpu0_pe2_ss_c_txp(12)" )
			)
			( signal "P3E_CPU0_PE2_SS_C_TXP<13>"
				( objectStatus "@baseboard_fab2_lib.baseboard_fab2(sch_1):p3e_cpu0_pe2_ss_c_txp(13)" )
			)
			( signal "P3E_CPU0_PE2_SS_C_TXP<14>"
				( objectStatus "@baseboard_fab2_lib.baseboard_fab2(sch_1):p3e_cpu0_pe2_ss_c_txp(14)" )
			)
			( signal "P3E_CPU0_PE2_SS_C_TXP<15>"
				( objectStatus "@baseboard_fab2_lib.baseboard_fab2(sch_1):p3e_cpu0_pe2_ss_c_txp(15)" )
			)
			( signal "P3E_OCP_CPU0_PE3_C_TXN<0>"
				( objectStatus "@baseboard_fab2_lib.baseboard_fab2(sch_1):p3e_ocp_cpu0_pe3_c_txn(0)" )
			)
			( signal "P3E_OCP_CPU0_PE3_C_TXN<1>"
				( objectStatus "@baseboard_fab2_lib.baseboard_fab2(sch_1):p3e_ocp_cpu0_pe3_c_txn(1)" )
			)
			( signal "P3E_OCP_CPU0_PE3_C_TXN<2>"
				( objectStatus "@baseboard_fab2_lib.baseboard_fab2(sch_1):p3e_ocp_cpu0_pe3_c_txn(2)" )
			)
			( signal "P3E_OCP_CPU0_PE3_C_TXN<3>"
				( objectStatus "@baseboard_fab2_lib.baseboard_fab2(sch_1):p3e_ocp_cpu0_pe3_c_txn(3)" )
			)
			( signal "P3E_OCP_CPU0_PE3_C_TXN<4>"
				( objectStatus "@baseboard_fab2_lib.baseboard_fab2(sch_1):p3e_ocp_cpu0_pe3_c_txn(4)" )
			)
			( signal "P3E_OCP_CPU0_PE3_C_TXN<5>"
				( objectStatus "@baseboard_fab2_lib.baseboard_fab2(sch_1):p3e_ocp_cpu0_pe3_c_txn(5)" )
			)
			( signal "P3E_OCP_CPU0_PE3_C_TXN<6>"
				( objectStatus "@baseboard_fab2_lib.baseboard_fab2(sch_1):p3e_ocp_cpu0_pe3_c_txn(6)" )
			)
			( signal "P3E_OCP_CPU0_PE3_C_TXN<7>"
				( objectStatus "@baseboard_fab2_lib.baseboard_fab2(sch_1):p3e_ocp_cpu0_pe3_c_txn(7)" )
			)
			( signal "P3E_OCP_CPU0_PE3_C_TXN<8>"
				( objectStatus "@baseboard_fab2_lib.baseboard_fab2(sch_1):p3e_ocp_cpu0_pe3_c_txn(8)" )
			)
			( signal "P3E_OCP_CPU0_PE3_C_TXN<9>"
				( objectStatus "@baseboard_fab2_lib.baseboard_fab2(sch_1):p3e_ocp_cpu0_pe3_c_txn(9)" )
			)
			( signal "P3E_OCP_CPU0_PE3_C_TXN<10>"
				( objectStatus "@baseboard_fab2_lib.baseboard_fab2(sch_1):p3e_ocp_cpu0_pe3_c_txn(10)" )
			)
			( signal "P3E_OCP_CPU0_PE3_C_TXN<11>"
				( objectStatus "@baseboard_fab2_lib.baseboard_fab2(sch_1):p3e_ocp_cpu0_pe3_c_txn(11)" )
			)
			( signal "P3E_OCP_CPU0_PE3_C_TXN<12>"
				( objectStatus "@baseboard_fab2_lib.baseboard_fab2(sch_1):p3e_ocp_cpu0_pe3_c_txn(12)" )
			)
			( signal "P3E_OCP_CPU0_PE3_C_TXN<13>"
				( objectStatus "@baseboard_fab2_lib.baseboard_fab2(sch_1):p3e_ocp_cpu0_pe3_c_txn(13)" )
			)
			( signal "P3E_OCP_CPU0_PE3_C_TXN<14>"
				( objectStatus "@baseboard_fab2_lib.baseboard_fab2(sch_1):p3e_ocp_cpu0_pe3_c_txn(14)" )
			)
			( signal "P3E_OCP_CPU0_PE3_C_TXN<15>"
				( objectStatus "@baseboard_fab2_lib.baseboard_fab2(sch_1):p3e_ocp_cpu0_pe3_c_txn(15)" )
			)
			( signal "P3E_OCP_CPU0_PE3_C_TXP<0>"
				( objectStatus "@baseboard_fab2_lib.baseboard_fab2(sch_1):p3e_ocp_cpu0_pe3_c_txp(0)" )
			)
			( signal "P3E_OCP_CPU0_PE3_C_TXP<1>"
				( objectStatus "@baseboard_fab2_lib.baseboard_fab2(sch_1):p3e_ocp_cpu0_pe3_c_txp(1)" )
			)
			( signal "P3E_OCP_CPU0_PE3_C_TXP<2>"
				( objectStatus "@baseboard_fab2_lib.baseboard_fab2(sch_1):p3e_ocp_cpu0_pe3_c_txp(2)" )
			)
			( signal "P3E_OCP_CPU0_PE3_C_TXP<3>"
				( objectStatus "@baseboard_fab2_lib.baseboard_fab2(sch_1):p3e_ocp_cpu0_pe3_c_txp(3)" )
			)
			( signal "P3E_OCP_CPU0_PE3_C_TXP<4>"
				( objectStatus "@baseboard_fab2_lib.baseboard_fab2(sch_1):p3e_ocp_cpu0_pe3_c_txp(4)" )
			)
			( signal "P3E_OCP_CPU0_PE3_C_TXP<5>"
				( objectStatus "@baseboard_fab2_lib.baseboard_fab2(sch_1):p3e_ocp_cpu0_pe3_c_txp(5)" )
			)
			( signal "P3E_OCP_CPU0_PE3_C_TXP<6>"
				( objectStatus "@baseboard_fab2_lib.baseboard_fab2(sch_1):p3e_ocp_cpu0_pe3_c_txp(6)" )
			)
			( signal "P3E_OCP_CPU0_PE3_C_TXP<7>"
				( objectStatus "@baseboard_fab2_lib.baseboard_fab2(sch_1):p3e_ocp_cpu0_pe3_c_txp(7)" )
			)
			( signal "P3E_OCP_CPU0_PE3_C_TXP<8>"
				( objectStatus "@baseboard_fab2_lib.baseboard_fab2(sch_1):p3e_ocp_cpu0_pe3_c_txp(8)" )
			)
			( signal "P3E_OCP_CPU0_PE3_C_TXP<9>"
				( objectStatus "@baseboard_fab2_lib.baseboard_fab2(sch_1):p3e_ocp_cpu0_pe3_c_txp(9)" )
			)
			( signal "P3E_OCP_CPU0_PE3_C_TXP<10>"
				( objectStatus "@baseboard_fab2_lib.baseboard_fab2(sch_1):p3e_ocp_cpu0_pe3_c_txp(10)" )
			)
			( signal "P3E_OCP_CPU0_PE3_C_TXP<11>"
				( objectStatus "@baseboard_fab2_lib.baseboard_fab2(sch_1):p3e_ocp_cpu0_pe3_c_txp(11)" )
			)
			( signal "P3E_OCP_CPU0_PE3_C_TXP<12>"
				( objectStatus "@baseboard_fab2_lib.baseboard_fab2(sch_1):p3e_ocp_cpu0_pe3_c_txp(12)" )
			)
			( signal "P3E_OCP_CPU0_PE3_C_TXP<13>"
				( objectStatus "@baseboard_fab2_lib.baseboard_fab2(sch_1):p3e_ocp_cpu0_pe3_c_txp(13)" )
			)
			( signal "P3E_OCP_CPU0_PE3_C_TXP<14>"
				( objectStatus "@baseboard_fab2_lib.baseboard_fab2(sch_1):p3e_ocp_cpu0_pe3_c_txp(14)" )
			)
			( signal "P3E_OCP_CPU0_PE3_C_TXP<15>"
				( objectStatus "@baseboard_fab2_lib.baseboard_fab2(sch_1):p3e_ocp_cpu0_pe3_c_txp(15)" )
			)
			( signal "P3E_CPU0_PE1_PCH_RXN<0>"
				( objectStatus "@baseboard_fab2_lib.baseboard_fab2(sch_1):p3e_cpu0_pe1_pch_rxn(0)" )
			)
			( signal "P3E_CPU0_PE1_PCH_RXN<1>"
				( objectStatus "@baseboard_fab2_lib.baseboard_fab2(sch_1):p3e_cpu0_pe1_pch_rxn(1)" )
			)
			( signal "P3E_CPU0_PE1_PCH_RXN<2>"
				( objectStatus "@baseboard_fab2_lib.baseboard_fab2(sch_1):p3e_cpu0_pe1_pch_rxn(2)" )
			)
			( signal "P3E_CPU0_PE1_PCH_RXN<3>"
				( objectStatus "@baseboard_fab2_lib.baseboard_fab2(sch_1):p3e_cpu0_pe1_pch_rxn(3)" )
			)
			( signal "P3E_CPU0_PE1_PCH_RXN<4>"
				( objectStatus "@baseboard_fab2_lib.baseboard_fab2(sch_1):p3e_cpu0_pe1_pch_rxn(4)" )
			)
			( signal "P3E_CPU0_PE1_PCH_RXN<5>"
				( objectStatus "@baseboard_fab2_lib.baseboard_fab2(sch_1):p3e_cpu0_pe1_pch_rxn(5)" )
			)
			( signal "P3E_CPU0_PE1_PCH_RXN<6>"
				( objectStatus "@baseboard_fab2_lib.baseboard_fab2(sch_1):p3e_cpu0_pe1_pch_rxn(6)" )
			)
			( signal "P3E_CPU0_PE1_PCH_RXN<7>"
				( objectStatus "@baseboard_fab2_lib.baseboard_fab2(sch_1):p3e_cpu0_pe1_pch_rxn(7)" )
			)
			( signal "P3E_CPU0_PE1_PCH_RXP<0>"
				( objectStatus "@baseboard_fab2_lib.baseboard_fab2(sch_1):p3e_cpu0_pe1_pch_rxp(0)" )
			)
			( signal "P3E_CPU0_PE1_PCH_RXP<1>"
				( objectStatus "@baseboard_fab2_lib.baseboard_fab2(sch_1):p3e_cpu0_pe1_pch_rxp(1)" )
			)
			( signal "P3E_CPU0_PE1_PCH_RXP<2>"
				( objectStatus "@baseboard_fab2_lib.baseboard_fab2(sch_1):p3e_cpu0_pe1_pch_rxp(2)" )
			)
			( signal "P3E_CPU0_PE1_PCH_RXP<3>"
				( objectStatus "@baseboard_fab2_lib.baseboard_fab2(sch_1):p3e_cpu0_pe1_pch_rxp(3)" )
			)
			( signal "P3E_CPU0_PE1_PCH_RXP<4>"
				( objectStatus "@baseboard_fab2_lib.baseboard_fab2(sch_1):p3e_cpu0_pe1_pch_rxp(4)" )
			)
			( signal "P3E_CPU0_PE1_PCH_RXP<5>"
				( objectStatus "@baseboard_fab2_lib.baseboard_fab2(sch_1):p3e_cpu0_pe1_pch_rxp(5)" )
			)
			( signal "P3E_CPU0_PE1_PCH_RXP<6>"
				( objectStatus "@baseboard_fab2_lib.baseboard_fab2(sch_1):p3e_cpu0_pe1_pch_rxp(6)" )
			)
			( signal "P3E_CPU0_PE1_PCH_RXP<7>"
				( objectStatus "@baseboard_fab2_lib.baseboard_fab2(sch_1):p3e_cpu0_pe1_pch_rxp(7)" )
			)
			( signal "P3E_CPU0_PE1_PCH_TXN<0>"
				( objectStatus "@baseboard_fab2_lib.baseboard_fab2(sch_1):p3e_cpu0_pe1_pch_txn(0)" )
			)
			( signal "P3E_CPU0_PE1_PCH_TXN<1>"
				( objectStatus "@baseboard_fab2_lib.baseboard_fab2(sch_1):p3e_cpu0_pe1_pch_txn(1)" )
			)
			( signal "P3E_CPU0_PE1_PCH_TXN<2>"
				( objectStatus "@baseboard_fab2_lib.baseboard_fab2(sch_1):p3e_cpu0_pe1_pch_txn(2)" )
			)
			( signal "P3E_CPU0_PE1_PCH_TXN<3>"
				( objectStatus "@baseboard_fab2_lib.baseboard_fab2(sch_1):p3e_cpu0_pe1_pch_txn(3)" )
			)
			( signal "P3E_CPU0_PE1_PCH_TXN<4>"
				( objectStatus "@baseboard_fab2_lib.baseboard_fab2(sch_1):p3e_cpu0_pe1_pch_txn(4)" )
			)
			( signal "P3E_CPU0_PE1_PCH_TXN<5>"
				( objectStatus "@baseboard_fab2_lib.baseboard_fab2(sch_1):p3e_cpu0_pe1_pch_txn(5)" )
			)
			( signal "P3E_CPU0_PE1_PCH_TXN<6>"
				( objectStatus "@baseboard_fab2_lib.baseboard_fab2(sch_1):p3e_cpu0_pe1_pch_txn(6)" )
			)
			( signal "P3E_CPU0_PE1_PCH_TXN<7>"
				( objectStatus "@baseboard_fab2_lib.baseboard_fab2(sch_1):p3e_cpu0_pe1_pch_txn(7)" )
			)
			( signal "P3E_CPU0_PE1_PCH_TXP<0>"
				( objectStatus "@baseboard_fab2_lib.baseboard_fab2(sch_1):p3e_cpu0_pe1_pch_txp(0)" )
			)
			( signal "P3E_CPU0_PE1_PCH_TXP<1>"
				( objectStatus "@baseboard_fab2_lib.baseboard_fab2(sch_1):p3e_cpu0_pe1_pch_txp(1)" )
			)
			( signal "P3E_CPU0_PE1_PCH_TXP<2>"
				( objectStatus "@baseboard_fab2_lib.baseboard_fab2(sch_1):p3e_cpu0_pe1_pch_txp(2)" )
			)
			( signal "P3E_CPU0_PE1_PCH_TXP<3>"
				( objectStatus "@baseboard_fab2_lib.baseboard_fab2(sch_1):p3e_cpu0_pe1_pch_txp(3)" )
			)
			( signal "P3E_CPU0_PE1_PCH_TXP<4>"
				( objectStatus "@baseboard_fab2_lib.baseboard_fab2(sch_1):p3e_cpu0_pe1_pch_txp(4)" )
			)
			( signal "P3E_CPU0_PE1_PCH_TXP<5>"
				( objectStatus "@baseboard_fab2_lib.baseboard_fab2(sch_1):p3e_cpu0_pe1_pch_txp(5)" )
			)
			( signal "P3E_CPU0_PE1_PCH_TXP<6>"
				( objectStatus "@baseboard_fab2_lib.baseboard_fab2(sch_1):p3e_cpu0_pe1_pch_txp(6)" )
			)
			( signal "P3E_CPU0_PE1_PCH_TXP<7>"
				( objectStatus "@baseboard_fab2_lib.baseboard_fab2(sch_1):p3e_cpu0_pe1_pch_txp(7)" )
			)
			( signal "P3E_CPU0_PE1_SS_C_TXN<0>"
				( objectStatus "@baseboard_fab2_lib.baseboard_fab2(sch_1):p3e_cpu0_pe1_ss_c_txn(0)" )
			)
			( signal "P3E_CPU0_PE1_SS_C_TXN<1>"
				( objectStatus "@baseboard_fab2_lib.baseboard_fab2(sch_1):p3e_cpu0_pe1_ss_c_txn(1)" )
			)
			( signal "P3E_CPU0_PE1_SS_C_TXN<2>"
				( objectStatus "@baseboard_fab2_lib.baseboard_fab2(sch_1):p3e_cpu0_pe1_ss_c_txn(2)" )
			)
			( signal "P3E_CPU0_PE1_SS_C_TXN<3>"
				( objectStatus "@baseboard_fab2_lib.baseboard_fab2(sch_1):p3e_cpu0_pe1_ss_c_txn(3)" )
			)
			( signal "P3E_CPU0_PE1_SS_C_TXN<4>"
				( objectStatus "@baseboard_fab2_lib.baseboard_fab2(sch_1):p3e_cpu0_pe1_ss_c_txn(4)" )
			)
			( signal "P3E_CPU0_PE1_SS_C_TXN<5>"
				( objectStatus "@baseboard_fab2_lib.baseboard_fab2(sch_1):p3e_cpu0_pe1_ss_c_txn(5)" )
			)
			( signal "P3E_CPU0_PE1_SS_C_TXN<6>"
				( objectStatus "@baseboard_fab2_lib.baseboard_fab2(sch_1):p3e_cpu0_pe1_ss_c_txn(6)" )
			)
			( signal "P3E_CPU0_PE1_SS_C_TXN<7>"
				( objectStatus "@baseboard_fab2_lib.baseboard_fab2(sch_1):p3e_cpu0_pe1_ss_c_txn(7)" )
			)
			( signal "P3E_CPU0_PE1_SS_C_TXP<0>"
				( objectStatus "@baseboard_fab2_lib.baseboard_fab2(sch_1):p3e_cpu0_pe1_ss_c_txp(0)" )
			)
			( signal "P3E_CPU0_PE1_SS_C_TXP<1>"
				( objectStatus "@baseboard_fab2_lib.baseboard_fab2(sch_1):p3e_cpu0_pe1_ss_c_txp(1)" )
			)
			( signal "P3E_CPU0_PE1_SS_C_TXP<2>"
				( objectStatus "@baseboard_fab2_lib.baseboard_fab2(sch_1):p3e_cpu0_pe1_ss_c_txp(2)" )
			)
			( signal "P3E_CPU0_PE1_SS_C_TXP<3>"
				( objectStatus "@baseboard_fab2_lib.baseboard_fab2(sch_1):p3e_cpu0_pe1_ss_c_txp(3)" )
			)
			( signal "P3E_CPU0_PE1_SS_C_TXP<4>"
				( objectStatus "@baseboard_fab2_lib.baseboard_fab2(sch_1):p3e_cpu0_pe1_ss_c_txp(4)" )
			)
			( signal "P3E_CPU0_PE1_SS_C_TXP<5>"
				( objectStatus "@baseboard_fab2_lib.baseboard_fab2(sch_1):p3e_cpu0_pe1_ss_c_txp(5)" )
			)
			( signal "P3E_CPU0_PE1_SS_C_TXP<6>"
				( objectStatus "@baseboard_fab2_lib.baseboard_fab2(sch_1):p3e_cpu0_pe1_ss_c_txp(6)" )
			)
			( signal "P3E_CPU0_PE1_SS_C_TXP<7>"
				( objectStatus "@baseboard_fab2_lib.baseboard_fab2(sch_1):p3e_cpu0_pe1_ss_c_txp(7)" )
			)
			( signal "P3E_CPU0_PE1_SS_R_RXN<0>"
				( objectStatus "@baseboard_fab2_lib.baseboard_fab2(sch_1):p3e_cpu0_pe1_ss_r_rxn(0)" )
			)
			( signal "P3E_CPU0_PE1_SS_R_RXN<1>"
				( objectStatus "@baseboard_fab2_lib.baseboard_fab2(sch_1):p3e_cpu0_pe1_ss_r_rxn(1)" )
			)
			( signal "P3E_CPU0_PE1_SS_R_RXN<2>"
				( objectStatus "@baseboard_fab2_lib.baseboard_fab2(sch_1):p3e_cpu0_pe1_ss_r_rxn(2)" )
			)
			( signal "P3E_CPU0_PE1_SS_R_RXN<3>"
				( objectStatus "@baseboard_fab2_lib.baseboard_fab2(sch_1):p3e_cpu0_pe1_ss_r_rxn(3)" )
			)
			( signal "P3E_CPU0_PE1_SS_R_RXN<4>"
				( objectStatus "@baseboard_fab2_lib.baseboard_fab2(sch_1):p3e_cpu0_pe1_ss_r_rxn(4)" )
			)
			( signal "P3E_CPU0_PE1_SS_R_RXN<5>"
				( objectStatus "@baseboard_fab2_lib.baseboard_fab2(sch_1):p3e_cpu0_pe1_ss_r_rxn(5)" )
			)
			( signal "P3E_CPU0_PE1_SS_R_RXN<6>"
				( objectStatus "@baseboard_fab2_lib.baseboard_fab2(sch_1):p3e_cpu0_pe1_ss_r_rxn(6)" )
			)
			( signal "P3E_CPU0_PE1_SS_R_RXN<7>"
				( objectStatus "@baseboard_fab2_lib.baseboard_fab2(sch_1):p3e_cpu0_pe1_ss_r_rxn(7)" )
			)
			( signal "P3E_CPU0_PE1_SS_R_RXP<0>"
				( objectStatus "@baseboard_fab2_lib.baseboard_fab2(sch_1):p3e_cpu0_pe1_ss_r_rxp(0)" )
			)
			( signal "P3E_CPU0_PE1_SS_R_RXP<1>"
				( objectStatus "@baseboard_fab2_lib.baseboard_fab2(sch_1):p3e_cpu0_pe1_ss_r_rxp(1)" )
			)
			( signal "P3E_CPU0_PE1_SS_R_RXP<2>"
				( objectStatus "@baseboard_fab2_lib.baseboard_fab2(sch_1):p3e_cpu0_pe1_ss_r_rxp(2)" )
			)
			( signal "P3E_CPU0_PE1_SS_R_RXP<3>"
				( objectStatus "@baseboard_fab2_lib.baseboard_fab2(sch_1):p3e_cpu0_pe1_ss_r_rxp(3)" )
			)
			( signal "P3E_CPU0_PE1_SS_R_RXP<4>"
				( objectStatus "@baseboard_fab2_lib.baseboard_fab2(sch_1):p3e_cpu0_pe1_ss_r_rxp(4)" )
			)
			( signal "P3E_CPU0_PE1_SS_R_RXP<5>"
				( objectStatus "@baseboard_fab2_lib.baseboard_fab2(sch_1):p3e_cpu0_pe1_ss_r_rxp(5)" )
			)
			( signal "P3E_CPU0_PE1_SS_R_RXP<6>"
				( objectStatus "@baseboard_fab2_lib.baseboard_fab2(sch_1):p3e_cpu0_pe1_ss_r_rxp(6)" )
			)
			( signal "P3E_CPU0_PE1_SS_R_RXP<7>"
				( objectStatus "@baseboard_fab2_lib.baseboard_fab2(sch_1):p3e_cpu0_pe1_ss_r_rxp(7)" )
			)
			( signal "CLK_100M_PCH_SLOTX24_S0_DN"
				( objectStatus "@baseboard_fab2_lib.baseboard_fab2(sch_1):clk_100m_pch_slotx24_s0_dn" )
			)
			( signal "CLK_100M_PCH_SLOTX24_S0_DP"
				( objectStatus "@baseboard_fab2_lib.baseboard_fab2(sch_1):clk_100m_pch_slotx24_s0_dp" )
			)
			( signal "CLK_100M_PCH_SLOTX24_S1_DN"
				( objectStatus "@baseboard_fab2_lib.baseboard_fab2(sch_1):clk_100m_pch_slotx24_s1_dn" )
			)
			( signal "CLK_100M_PCH_SLOTX24_S1_DP"
				( objectStatus "@baseboard_fab2_lib.baseboard_fab2(sch_1):clk_100m_pch_slotx24_s1_dp" )
			)
			( signal "CLK_100M_PCH_SLOTX24_S2_DN"
				( objectStatus "@baseboard_fab2_lib.baseboard_fab2(sch_1):clk_100m_pch_slotx24_s2_dn" )
			)
			( signal "CLK_100M_PCH_SLOTX24_S2_DP"
				( objectStatus "@baseboard_fab2_lib.baseboard_fab2(sch_1):clk_100m_pch_slotx24_s2_dp" )
			)
			( signal "CLK_100M_PCH_SLOTX24_S3_DN"
				( objectStatus "@baseboard_fab2_lib.baseboard_fab2(sch_1):clk_100m_pch_slotx24_s3_dn" )
			)
			( signal "CLK_100M_PCH_SLOTX24_S3_DP"
				( objectStatus "@baseboard_fab2_lib.baseboard_fab2(sch_1):clk_100m_pch_slotx24_s3_dp" )
			)
			( signal "CLK_100M_PCH_SLOTX24_S4_DN"
				( objectStatus "@baseboard_fab2_lib.baseboard_fab2(sch_1):clk_100m_pch_slotx24_s4_dn" )
			)
			( signal "CLK_100M_PCH_SLOTX24_S4_DP"
				( objectStatus "@baseboard_fab2_lib.baseboard_fab2(sch_1):clk_100m_pch_slotx24_s4_dp" )
			)
			( signal "CLK_100M_PCH_SLOTX24_S5_DN"
				( objectStatus "@baseboard_fab2_lib.baseboard_fab2(sch_1):clk_100m_pch_slotx24_s5_dn" )
			)
			( signal "CLK_100M_PCH_SLOTX24_S5_DP"
				( objectStatus "@baseboard_fab2_lib.baseboard_fab2(sch_1):clk_100m_pch_slotx24_s5_dp" )
			)
			( signal "FM_PE_SLOTX24_WAKE_N"
				( objectStatus "@baseboard_fab2_lib.baseboard_fab2(sch_1):fm_pe_slotx24_wake_n" )
			)
			( signal "FM_PRSNT_2_2_N"
				( objectStatus "@baseboard_fab2_lib.baseboard_fab2(sch_1):fm_prsnt_2_2_n" )
			)
			( signal "FM_PRSNT_2_3_N"
				( objectStatus "@baseboard_fab2_lib.baseboard_fab2(sch_1):fm_prsnt_2_3_n" )
			)
			( signal "FM_PRSNT_2_4_N"
				( objectStatus "@baseboard_fab2_lib.baseboard_fab2(sch_1):fm_prsnt_2_4_n" )
			)
			( signal "FM_PRSNT_2_5_N"
				( objectStatus "@baseboard_fab2_lib.baseboard_fab2(sch_1):fm_prsnt_2_5_n" )
			)
			( signal "FM_PWRBRK_SLOT_N"
				( objectStatus "@baseboard_fab2_lib.baseboard_fab2(sch_1):fm_pwrbrk_slot_n" )
			)
			( signal "FM_SLT_CFG0"
				( objectStatus "@baseboard_fab2_lib.baseboard_fab2(sch_1):fm_slt_cfg0" )
			)
			( signal "FM_SLT_CFG1"
				( objectStatus "@baseboard_fab2_lib.baseboard_fab2(sch_1):fm_slt_cfg1" )
			)
			( signal "IRQ_OOB_MGMT_RISER_ALERT_N"
				( objectStatus "@baseboard_fab2_lib.baseboard_fab2(sch_1):irq_oob_mgmt_riser_alert_n" )
			)
			( signal "P12V"
				( attribute "VOLTAGE" "+12."
					( Units "uVoltage" "V" 1.000000)
					( Status sAliasFlattened )
					( Status sAliasConflict )
					( Origin gFrontEnd )
				)
				( objectStatus "@baseboard_fab2_lib.baseboard_fab2(sch_1):p12v" )
			)
			( signal "RST_PCIE_RISER1_PERST_N"
				( objectStatus "@baseboard_fab2_lib.baseboard_fab2(sch_1):rst_pcie_riser1_perst_n" )
			)
			( signal "RST_PCIE_RISER1_PERST_R_N"
				( objectStatus "@baseboard_fab2_lib.baseboard_fab2(sch_1):rst_pcie_riser1_perst_r_n" )
			)
			( signal "SMB_SLOTX24_BMC_STBY_LVC3_SCL"
				( objectStatus "@baseboard_fab2_lib.baseboard_fab2(sch_1):smb_slotx24_bmc_stby_lvc3_scl" )
			)
			( signal "SMB_SLOTX24_BMC_STBY_LVC3_SDA"
				( objectStatus "@baseboard_fab2_lib.baseboard_fab2(sch_1):smb_slotx24_bmc_stby_lvc3_sda" )
			)
			( signal "SMB_SLOTX24_STBY_LVC3_SCL_R2"
				( objectStatus "@baseboard_fab2_lib.baseboard_fab2(sch_1):smb_slotx24_stby_lvc3_scl_r2" )
			)
			( signal "SMB_SLOTX24_STBY_LVC3_SDA_R2"
				( objectStatus "@baseboard_fab2_lib.baseboard_fab2(sch_1):smb_slotx24_stby_lvc3_sda_r2" )
			)
			( signal "FM_PRSNT_2_6_N"
				( objectStatus "@baseboard_fab2_lib.baseboard_fab2(sch_1):fm_prsnt_2_6_n" )
			)
			( signal "CLK_100M_PCH_XDP_DN"
				( objectStatus "@baseboard_fab2_lib.baseboard_fab2(sch_1):clk_100m_pch_xdp_dn" )
			)
			( signal "CLK_100M_PCH_XDP_DP"
				( objectStatus "@baseboard_fab2_lib.baseboard_fab2(sch_1):clk_100m_pch_xdp_dp" )
			)
			( signal "FM_DEBUG_RST_BTN_N"
				( objectStatus "@baseboard_fab2_lib.baseboard_fab2(sch_1):fm_debug_rst_btn_n" )
			)
			( signal "FM_DEBUG_RST_BTN_R1_N"
				( objectStatus "@baseboard_fab2_lib.baseboard_fab2(sch_1):fm_debug_rst_btn_r1_n" )
			)
			( signal "P1V05_PCH_STBY"
				( attribute "VOLTAGE" "1.05V"
					( Units "uVoltage" "V" 1.000000)
					( Status sAliasFlattened )
					( Origin gFrontEnd )
				)
				( objectStatus "@baseboard_fab2_lib.baseboard_fab2(sch_1):p1v05_pch_stby" )
			)
			( signal "RST_RSMRST_N"
				( objectStatus "@baseboard_fab2_lib.baseboard_fab2(sch_1):rst_rsmrst_n" )
			)
			( signal "SPI_PCH_IO2"
				( objectStatus "@baseboard_fab2_lib.baseboard_fab2(sch_1):spi_pch_io2" )
			)
			( signal "SPI_PCH_MOSI"
				( objectStatus "@baseboard_fab2_lib.baseboard_fab2(sch_1):spi_pch_mosi" )
			)
			( signal "TP_XDP_CPU_OBSDATA_C0"
				( objectStatus "@baseboard_fab2_lib.baseboard_fab2(sch_1):tp_xdp_cpu_obsdata_c0" )
			)
			( signal "TP_XDP_CPU_OBSDATA_C1"
				( objectStatus "@baseboard_fab2_lib.baseboard_fab2(sch_1):tp_xdp_cpu_obsdata_c1" )
			)
			( signal "TP_XDP_CPU_OBSDATA_C2"
				( objectStatus "@baseboard_fab2_lib.baseboard_fab2(sch_1):tp_xdp_cpu_obsdata_c2" )
			)
			( signal "TP_XDP_CPU_OBSDATA_C3"
				( objectStatus "@baseboard_fab2_lib.baseboard_fab2(sch_1):tp_xdp_cpu_obsdata_c3" )
			)
			( signal "TP_XDP_CPU_OBSDATA_D0"
				( objectStatus "@baseboard_fab2_lib.baseboard_fab2(sch_1):tp_xdp_cpu_obsdata_d0" )
			)
			( signal "TP_XDP_CPU_OBSDATA_D1"
				( objectStatus "@baseboard_fab2_lib.baseboard_fab2(sch_1):tp_xdp_cpu_obsdata_d1" )
			)
			( signal "TP_XDP_CPU_OBSDATA_D2"
				( objectStatus "@baseboard_fab2_lib.baseboard_fab2(sch_1):tp_xdp_cpu_obsdata_d2" )
			)
			( signal "TP_XDP_CPU_OBSDATA_D3"
				( objectStatus "@baseboard_fab2_lib.baseboard_fab2(sch_1):tp_xdp_cpu_obsdata_d3" )
			)
			( signal "TP_XDP_CPU_OBSFN_C0"
				( objectStatus "@baseboard_fab2_lib.baseboard_fab2(sch_1):tp_xdp_cpu_obsfn_c0" )
			)
			( signal "TP_XDP_OBSDATA_A0"
				( objectStatus "@baseboard_fab2_lib.baseboard_fab2(sch_1):tp_xdp_obsdata_a0" )
			)
			( signal "TP_XDP_OBSDATA_A1"
				( objectStatus "@baseboard_fab2_lib.baseboard_fab2(sch_1):tp_xdp_obsdata_a1" )
			)
			( signal "TP_XDP_OBSDATA_A2"
				( objectStatus "@baseboard_fab2_lib.baseboard_fab2(sch_1):tp_xdp_obsdata_a2" )
			)
			( signal "TP_XDP_OBSDATA_A3"
				( objectStatus "@baseboard_fab2_lib.baseboard_fab2(sch_1):tp_xdp_obsdata_a3" )
			)
			( signal "TP_XDP_OBSDATA_B0"
				( objectStatus "@baseboard_fab2_lib.baseboard_fab2(sch_1):tp_xdp_obsdata_b0" )
			)
			( signal "TP_XDP_OBSDATA_B1"
				( objectStatus "@baseboard_fab2_lib.baseboard_fab2(sch_1):tp_xdp_obsdata_b1" )
			)
			( signal "TP_XDP_OBSDATA_B2"
				( objectStatus "@baseboard_fab2_lib.baseboard_fab2(sch_1):tp_xdp_obsdata_b2" )
			)
			( signal "TP_XDP_OBSDATA_B3"
				( objectStatus "@baseboard_fab2_lib.baseboard_fab2(sch_1):tp_xdp_obsdata_b3" )
			)
			( signal "TP_XDP_OBSFN_B0"
				( objectStatus "@baseboard_fab2_lib.baseboard_fab2(sch_1):tp_xdp_obsfn_b0" )
			)
			( signal "TP_XDP_OBSFN_B1"
				( objectStatus "@baseboard_fab2_lib.baseboard_fab2(sch_1):tp_xdp_obsfn_b1" )
			)
			( signal "XDP_CPU_GTL_TCK_R2"
				( objectStatus "@baseboard_fab2_lib.baseboard_fab2(sch_1):xdp_cpu_gtl_tck_r2" )
			)
			( signal "XDP_CPU_TCK_BUF"
				( objectStatus "@baseboard_fab2_lib.baseboard_fab2(sch_1):xdp_cpu_tck_buf" )
			)
			( signal "XDP_DEBUG_CONSENT_N"
				( objectStatus "@baseboard_fab2_lib.baseboard_fab2(sch_1):xdp_debug_consent_n" )
			)
			( signal "XDP_ITP_PMODE"
				( objectStatus "@baseboard_fab2_lib.baseboard_fab2(sch_1):xdp_itp_pmode" )
			)
			( signal "XDP_OBSFN_B0_MBP6_N"
				( objectStatus "@baseboard_fab2_lib.baseboard_fab2(sch_1):xdp_obsfn_b0_mbp6_n" )
			)
			( signal "XDP_OBSFN_B1_MBP7_N"
				( objectStatus "@baseboard_fab2_lib.baseboard_fab2(sch_1):xdp_obsfn_b1_mbp7_n" )
			)
			( signal "XDP_PCH_CPU_TCK0"
				( objectStatus "@baseboard_fab2_lib.baseboard_fab2(sch_1):xdp_pch_cpu_tck0" )
			)
			( signal "XDP_PCH_TCK1"
				( objectStatus "@baseboard_fab2_lib.baseboard_fab2(sch_1):xdp_pch_tck1" )
			)
			( signal "XDP_PRDY_N"
				( objectStatus "@baseboard_fab2_lib.baseboard_fab2(sch_1):xdp_prdy_n" )
			)
			( signal "XDP_PREQ_N"
				( objectStatus "@baseboard_fab2_lib.baseboard_fab2(sch_1):xdp_preq_n" )
			)
			( signal "XDP_PWRGD_RST_N"
				( objectStatus "@baseboard_fab2_lib.baseboard_fab2(sch_1):xdp_pwrgd_rst_n" )
			)
			( signal "XDP_RSMRST_N"
				( objectStatus "@baseboard_fab2_lib.baseboard_fab2(sch_1):xdp_rsmrst_n" )
			)
			( signal "XDP_RST_CO_N"
				( objectStatus "@baseboard_fab2_lib.baseboard_fab2(sch_1):xdp_rst_co_n" )
			)
			( signal "XDP_SPI_PCH_MOSI_BOOT_HALT_N"
				( objectStatus "@baseboard_fab2_lib.baseboard_fab2(sch_1):xdp_spi_pch_mosi_boot_halt_n" )
			)
			( signal "XDP_SYSPWROK"
				( objectStatus "@baseboard_fab2_lib.baseboard_fab2(sch_1):xdp_syspwrok" )
			)
			( signal "XDP_TDI"
				( objectStatus "@baseboard_fab2_lib.baseboard_fab2(sch_1):xdp_tdi" )
			)
			( signal "XDP_TDO"
				( objectStatus "@baseboard_fab2_lib.baseboard_fab2(sch_1):xdp_tdo" )
			)
			( signal "XDP_TMS"
				( objectStatus "@baseboard_fab2_lib.baseboard_fab2(sch_1):xdp_tms" )
			)
			( signal "XDP_TRST_N"
				( objectStatus "@baseboard_fab2_lib.baseboard_fab2(sch_1):xdp_trst_n" )
			)
			( signal "PWRGD_PVCCIN_CPU0"
				( objectStatus "@baseboard_fab2_lib.baseboard_fab2(sch_1):pwrgd_pvccin_cpu0" )
			)
			( signal "XDP_CPU_TDO"
				( objectStatus "@baseboard_fab2_lib.baseboard_fab2(sch_1):xdp_cpu_tdo" )
			)
			( signal "FM_CPU0_AND_CPU1_MCP_PRES"
				( objectStatus "@baseboard_fab2_lib.baseboard_fab2(sch_1):fm_cpu0_and_cpu1_mcp_pres" )
			)
			( signal "FM_CPU0_CD_PRES"
				( objectStatus "@baseboard_fab2_lib.baseboard_fab2(sch_1):fm_cpu0_cd_pres" )
			)
			( signal "FM_CPU0_OR_CPU1_MCP_PRES"
				( objectStatus "@baseboard_fab2_lib.baseboard_fab2(sch_1):fm_cpu0_or_cpu1_mcp_pres" )
			)
			( signal "JTAG_MCP_CPU0_TDI_R"
				( objectStatus "@baseboard_fab2_lib.baseboard_fab2(sch_1):jtag_mcp_cpu0_tdi_r" )
			)
			( signal "JTAG_MCP_CPU1_TDI_R"
				( objectStatus "@baseboard_fab2_lib.baseboard_fab2(sch_1):jtag_mcp_cpu1_tdi_r" )
			)
			( signal "JTAG_MCP_MUX_TDI"
				( objectStatus "@baseboard_fab2_lib.baseboard_fab2(sch_1):jtag_mcp_mux_tdi" )
			)
			( signal "JTAG_MCP_MUX_TDO"
				( objectStatus "@baseboard_fab2_lib.baseboard_fab2(sch_1):jtag_mcp_mux_tdo" )
			)
			( signal "JTAG_MCP_TCK_R"
				( objectStatus "@baseboard_fab2_lib.baseboard_fab2(sch_1):jtag_mcp_tck_r" )
			)
			( signal "JTAG_MCP_TMS_R"
				( objectStatus "@baseboard_fab2_lib.baseboard_fab2(sch_1):jtag_mcp_tms_r" )
			)
			( signal "JTAG_MCP_TMS_R1"
				( objectStatus "@baseboard_fab2_lib.baseboard_fab2(sch_1):jtag_mcp_tms_r1" )
			)
			( signal "PWRGD_CPU0_G_R"
				( objectStatus "@baseboard_fab2_lib.baseboard_fab2(sch_1):pwrgd_cpu0_g_r" )
			)
			( signal "TP_JTAG_MCP_IO8_RSVD"
				( objectStatus "@baseboard_fab2_lib.baseboard_fab2(sch_1):tp_jtag_mcp_io8_rsvd" )
			)
			( signal "A_PCH_XCLK_BIASREF"
				( objectStatus "@baseboard_fab2_lib.baseboard_fab2(sch_1):a_pch_xclk_biasref" )
			)
			( signal "CLK_100M_AIRMAX8_PE1_DN"
				( objectStatus "@baseboard_fab2_lib.baseboard_fab2(sch_1):clk_100m_airmax8_pe1_dn" )
			)
			( signal "CLK_100M_AIRMAX8_PE1_DP"
				( objectStatus "@baseboard_fab2_lib.baseboard_fab2(sch_1):clk_100m_airmax8_pe1_dp" )
			)
			( signal "CLK_100M_BMC_PE_DN"
				( objectStatus "@baseboard_fab2_lib.baseboard_fab2(sch_1):clk_100m_bmc_pe_dn" )
			)
			( signal "CLK_100M_BMC_PE_DP"
				( objectStatus "@baseboard_fab2_lib.baseboard_fab2(sch_1):clk_100m_bmc_pe_dp" )
			)
			( signal "CLK_100M_BMC_PE_R_DN"
				( objectStatus "@baseboard_fab2_lib.baseboard_fab2(sch_1):clk_100m_bmc_pe_r_dn" )
			)
			( signal "CLK_100M_BMC_PE_R_DP"
				( objectStatus "@baseboard_fab2_lib.baseboard_fab2(sch_1):clk_100m_bmc_pe_r_dp" )
			)
			( signal "CLK_100M_M2_DN"
				( objectStatus "@baseboard_fab2_lib.baseboard_fab2(sch_1):clk_100m_m2_dn" )
			)
			( signal "CLK_100M_M2_DP"
				( objectStatus "@baseboard_fab2_lib.baseboard_fab2(sch_1):clk_100m_m2_dp" )
			)
			( signal "CLK_100M_MEZZ1_DN"
				( objectStatus "@baseboard_fab2_lib.baseboard_fab2(sch_1):clk_100m_mezz1_dn" )
			)
			( signal "CLK_100M_MEZZ1_DP"
				( objectStatus "@baseboard_fab2_lib.baseboard_fab2(sch_1):clk_100m_mezz1_dp" )
			)
			( signal "CLK_100M_MEZZ2_DN"
				( objectStatus "@baseboard_fab2_lib.baseboard_fab2(sch_1):clk_100m_mezz2_dn" )
			)
			( signal "CLK_100M_MEZZ2_DP"
				( objectStatus "@baseboard_fab2_lib.baseboard_fab2(sch_1):clk_100m_mezz2_dp" )
			)
			( signal "CLK_100M_MEZZ3_DN"
				( objectStatus "@baseboard_fab2_lib.baseboard_fab2(sch_1):clk_100m_mezz3_dn" )
			)
			( signal "VCC_A_1V1"
				( objectStatus "@baseboard_fab2_lib.baseboard_fab2(sch_1):vcc_a_1v1" )
			)
			( signal "SPI_BMC_BT_CLK_R"
				( objectStatus "@baseboard_fab2_lib.baseboard_fab2(sch_1):spi_bmc_bt_clk_r" )
			)
			( signal "SPI_BMC_BT_DO"
				( objectStatus "@baseboard_fab2_lib.baseboard_fab2(sch_1):spi_bmc_bt_do" )
			)
			( signal "TP_PCH_RSVD53"
				( objectStatus "@baseboard_fab2_lib.baseboard_fab2(sch_1):tp_pch_rsvd53" )
			)
			( signal "FM_BMC_READY_N"
				( objectStatus "@baseboard_fab2_lib.baseboard_fab2(sch_1):fm_bmc_ready_n" )
			)
			( signal "TP_PCH_RSVD37"
				( objectStatus "@baseboard_fab2_lib.baseboard_fab2(sch_1):tp_pch_rsvd37" )
			)
			( signal "FM_ADR_MODE_SEL"
				( objectStatus "@baseboard_fab2_lib.baseboard_fab2(sch_1):fm_adr_mode_sel" )
			)
			( signal "FM_ADR_MODE_SEL_R"
				( objectStatus "@baseboard_fab2_lib.baseboard_fab2(sch_1):fm_adr_mode_sel_r" )
			)
			( signal "CLK_24M_BMC_LPC_R"
				( objectStatus "@baseboard_fab2_lib.baseboard_fab2(sch_1):clk_24m_bmc_lpc_r" )
			)
			( signal "CLK_100M_MEZZ3_DP"
				( objectStatus "@baseboard_fab2_lib.baseboard_fab2(sch_1):clk_100m_mezz3_dp" )
			)
			( signal "CLK_100M_MEZZ4_DN"
				( objectStatus "@baseboard_fab2_lib.baseboard_fab2(sch_1):clk_100m_mezz4_dn" )
			)
			( signal "CLK_100M_MEZZ4_DP"
				( objectStatus "@baseboard_fab2_lib.baseboard_fab2(sch_1):clk_100m_mezz4_dp" )
			)
			( signal "FM_BMC_FAULT_LED_N"
				( objectStatus "@baseboard_fab2_lib.baseboard_fab2(sch_1):fm_bmc_fault_led_n" )
			)
			( signal "TP_PLTRST_CPU_N"
				( objectStatus "@baseboard_fab2_lib.baseboard_fab2(sch_1):tp_pltrst_cpu_n" )
			)
			( signal "TP_PM_SYNC_GTL"
				( objectStatus "@baseboard_fab2_lib.baseboard_fab2(sch_1):tp_pm_sync_gtl" )
			)
			( signal "A_P5V_SCALED"
				( attribute "VOLTAGE" "+2V"
					( Units "uVoltage" "V" 1.000000)
					( Status sAliasFlattened )
					( Origin gFrontEnd )
				)
				( objectStatus "@baseboard_fab2_lib.baseboard_fab2(sch_1):a_p5v_scaled" )
			)
			( signal "TP_PCH_RSVD45"
				( objectStatus "@baseboard_fab2_lib.baseboard_fab2(sch_1):tp_pch_rsvd45" )
			)
			( signal "XDP_PCH_PWR_DEBUG_N"
				( objectStatus "@baseboard_fab2_lib.baseboard_fab2(sch_1):xdp_pch_pwr_debug_n" )
			)
			( signal "CLK_100M_SPRV_DN"
				( objectStatus "@baseboard_fab2_lib.baseboard_fab2(sch_1):clk_100m_sprv_dn" )
			)
			( signal "CLK_100M_SPRV_DP"
				( objectStatus "@baseboard_fab2_lib.baseboard_fab2(sch_1):clk_100m_sprv_dp" )
			)
			( signal "CLK_48M_USB_BMC"
				( objectStatus "@baseboard_fab2_lib.baseboard_fab2(sch_1):clk_48m_usb_bmc" )
			)
			( signal "H_PMSYNC_CLK_24M_R"
				( objectStatus "@baseboard_fab2_lib.baseboard_fab2(sch_1):h_pmsync_clk_24m_r" )
			)
			( signal "TP_CLK_100M_NSSCC0_DN"
				( objectStatus "@baseboard_fab2_lib.baseboard_fab2(sch_1):tp_clk_100m_nsscc0_dn" )
			)
			( signal "TP_CLK_100M_NSSCC0_DP"
				( objectStatus "@baseboard_fab2_lib.baseboard_fab2(sch_1):tp_clk_100m_nsscc0_dp" )
			)
			( signal "TP_CLK_100M_NSSCC1_DN"
				( objectStatus "@baseboard_fab2_lib.baseboard_fab2(sch_1):tp_clk_100m_nsscc1_dn" )
			)
			( signal "TP_CLK_100M_NSSCC1_DP"
				( objectStatus "@baseboard_fab2_lib.baseboard_fab2(sch_1):tp_clk_100m_nsscc1_dp" )
			)
			( signal "TP_CLK_100M_PLAT1_DN"
				( objectStatus "@baseboard_fab2_lib.baseboard_fab2(sch_1):tp_clk_100m_plat1_dn" )
			)
			( signal "TP_CLK_100M_PLAT1_DP"
				( objectStatus "@baseboard_fab2_lib.baseboard_fab2(sch_1):tp_clk_100m_plat1_dp" )
			)
			( signal "TP_CLK_24M_PMSYNC2"
				( objectStatus "@baseboard_fab2_lib.baseboard_fab2(sch_1):tp_clk_24m_pmsync2" )
			)
			( signal "TP_PCH_RSVD64"
				( objectStatus "@baseboard_fab2_lib.baseboard_fab2(sch_1):tp_pch_rsvd64" )
			)
			( signal "TP_PCH_RSVD65"
				( objectStatus "@baseboard_fab2_lib.baseboard_fab2(sch_1):tp_pch_rsvd65" )
			)
			( signal "XTAL_33K_RTC1"
				( objectStatus "@baseboard_fab2_lib.baseboard_fab2(sch_1):xtal_33k_rtc1" )
			)
			( signal "XTAL_33K_RTC2"
				( objectStatus "@baseboard_fab2_lib.baseboard_fab2(sch_1):xtal_33k_rtc2" )
			)
			( signal "XTAL_PCH_48M_IN"
				( objectStatus "@baseboard_fab2_lib.baseboard_fab2(sch_1):xtal_pch_48m_in" )
			)
			( signal "XTAL_PCH_48M_OUT"
				( objectStatus "@baseboard_fab2_lib.baseboard_fab2(sch_1):xtal_pch_48m_out" )
			)
			( signal "A_USB2_COMP"
				( objectStatus "@baseboard_fab2_lib.baseboard_fab2(sch_1):a_usb2_comp" )
			)
			( signal "A_USB2_VBUS"
				( objectStatus "@baseboard_fab2_lib.baseboard_fab2(sch_1):a_usb2_vbus" )
			)
			( signal "TP_PCH_RSVD55"
				( objectStatus "@baseboard_fab2_lib.baseboard_fab2(sch_1):tp_pch_rsvd55" )
			)
			( signal "JTAG_RISER_TDI"
				( objectStatus "@baseboard_fab2_lib.baseboard_fab2(sch_1):jtag_riser_tdi" )
			)
			( signal "JTAG_RISER_TDO"
				( objectStatus "@baseboard_fab2_lib.baseboard_fab2(sch_1):jtag_riser_tdo" )
			)
			( signal "TP_USB2_P03_DN"
				( objectStatus "@baseboard_fab2_lib.baseboard_fab2(sch_1):tp_usb2_p03_dn" )
			)
			( signal "TP_USB2_P03_DP"
				( objectStatus "@baseboard_fab2_lib.baseboard_fab2(sch_1):tp_usb2_p03_dp" )
			)
			( signal "TP_USB2_P06_DN"
				( objectStatus "@baseboard_fab2_lib.baseboard_fab2(sch_1):tp_usb2_p06_dn" )
			)
			( signal "TP_USB2_P06_DP"
				( objectStatus "@baseboard_fab2_lib.baseboard_fab2(sch_1):tp_usb2_p06_dp" )
			)
			( signal "TP_USB2_P07_DN"
				( objectStatus "@baseboard_fab2_lib.baseboard_fab2(sch_1):tp_usb2_p07_dn" )
			)
			( signal "TP_USB2_P07_DP"
				( objectStatus "@baseboard_fab2_lib.baseboard_fab2(sch_1):tp_usb2_p07_dp" )
			)
			( signal "TP_USB2_P10_DN"
				( objectStatus "@baseboard_fab2_lib.baseboard_fab2(sch_1):tp_usb2_p10_dn" )
			)
			( signal "TP_USB2_P10_DP"
				( objectStatus "@baseboard_fab2_lib.baseboard_fab2(sch_1):tp_usb2_p10_dp" )
			)
			( signal "TP_USB2_P11_DN"
				( objectStatus "@baseboard_fab2_lib.baseboard_fab2(sch_1):tp_usb2_p11_dn" )
			)
			( signal "TP_USB2_P11_DP"
				( objectStatus "@baseboard_fab2_lib.baseboard_fab2(sch_1):tp_usb2_p11_dp" )
			)
			( signal "TP_USB2_P12_DN"
				( objectStatus "@baseboard_fab2_lib.baseboard_fab2(sch_1):tp_usb2_p12_dn" )
			)
			( signal "TP_USB2_P12_DP"
				( objectStatus "@baseboard_fab2_lib.baseboard_fab2(sch_1):tp_usb2_p12_dp" )
			)
			( signal "TP_USB2_P13_DN"
				( objectStatus "@baseboard_fab2_lib.baseboard_fab2(sch_1):tp_usb2_p13_dn" )
			)
			( signal "TP_USB2_P13_DP"
				( objectStatus "@baseboard_fab2_lib.baseboard_fab2(sch_1):tp_usb2_p13_dp" )
			)
			( signal "TP_USB2_P14_DN"
				( objectStatus "@baseboard_fab2_lib.baseboard_fab2(sch_1):tp_usb2_p14_dn" )
			)
			( signal "TP_USB2_P14_DP"
				( objectStatus "@baseboard_fab2_lib.baseboard_fab2(sch_1):tp_usb2_p14_dp" )
			)
			( signal "TP_USB2_P8_DN"
				( objectStatus "@baseboard_fab2_lib.baseboard_fab2(sch_1):tp_usb2_p8_dn" )
			)
			( signal "TP_USB2_P8_DP"
				( objectStatus "@baseboard_fab2_lib.baseboard_fab2(sch_1):tp_usb2_p8_dp" )
			)
			( signal "TP_USB2_P9_DN"
				( objectStatus "@baseboard_fab2_lib.baseboard_fab2(sch_1):tp_usb2_p9_dn" )
			)
			( signal "TP_USB2_P9_DP"
				( objectStatus "@baseboard_fab2_lib.baseboard_fab2(sch_1):tp_usb2_p9_dp" )
			)
			( signal "TP_USB3_P02_RXN"
				( objectStatus "@baseboard_fab2_lib.baseboard_fab2(sch_1):tp_usb3_p02_rxn" )
			)
			( signal "TP_USB3_P02_RXP"
				( objectStatus "@baseboard_fab2_lib.baseboard_fab2(sch_1):tp_usb3_p02_rxp" )
			)
			( signal "TP_USB3_P02_TXN"
				( objectStatus "@baseboard_fab2_lib.baseboard_fab2(sch_1):tp_usb3_p02_txn" )
			)
			( signal "TP_USB3_P02_TXP"
				( objectStatus "@baseboard_fab2_lib.baseboard_fab2(sch_1):tp_usb3_p02_txp" )
			)
			( signal "TP_USB3_P03_RXN"
				( objectStatus "@baseboard_fab2_lib.baseboard_fab2(sch_1):tp_usb3_p03_rxn" )
			)
			( signal "TP_USB3_P03_RXP"
				( objectStatus "@baseboard_fab2_lib.baseboard_fab2(sch_1):tp_usb3_p03_rxp" )
			)
			( signal "TP_USB3_P03_TXN"
				( objectStatus "@baseboard_fab2_lib.baseboard_fab2(sch_1):tp_usb3_p03_txn" )
			)
			( signal "TP_USB3_P03_TXP"
				( objectStatus "@baseboard_fab2_lib.baseboard_fab2(sch_1):tp_usb3_p03_txp" )
			)
			( signal "TP_USB3_P04_RXN"
				( objectStatus "@baseboard_fab2_lib.baseboard_fab2(sch_1):tp_usb3_p04_rxn" )
			)
			( signal "TP_USB3_P04_RXP"
				( objectStatus "@baseboard_fab2_lib.baseboard_fab2(sch_1):tp_usb3_p04_rxp" )
			)
			( signal "TP_USB3_P04_TXN"
				( objectStatus "@baseboard_fab2_lib.baseboard_fab2(sch_1):tp_usb3_p04_txn" )
			)
			( signal "TP_USB3_P04_TXP"
				( objectStatus "@baseboard_fab2_lib.baseboard_fab2(sch_1):tp_usb3_p04_txp" )
			)
			( signal "TP_USB3_P05_RXN"
				( objectStatus "@baseboard_fab2_lib.baseboard_fab2(sch_1):tp_usb3_p05_rxn" )
			)
			( signal "TP_USB3_P05_RXP"
				( objectStatus "@baseboard_fab2_lib.baseboard_fab2(sch_1):tp_usb3_p05_rxp" )
			)
			( signal "TP_USB3_P05_TXN"
				( objectStatus "@baseboard_fab2_lib.baseboard_fab2(sch_1):tp_usb3_p05_txn" )
			)
			( signal "TP_USB3_P05_TXP"
				( objectStatus "@baseboard_fab2_lib.baseboard_fab2(sch_1):tp_usb3_p05_txp" )
			)
			( signal "TP_USB3_P06_RXN"
				( objectStatus "@baseboard_fab2_lib.baseboard_fab2(sch_1):tp_usb3_p06_rxn" )
			)
			( signal "TP_USB3_P06_RXP"
				( objectStatus "@baseboard_fab2_lib.baseboard_fab2(sch_1):tp_usb3_p06_rxp" )
			)
			( signal "TP_USB3_P06_TXN"
				( objectStatus "@baseboard_fab2_lib.baseboard_fab2(sch_1):tp_usb3_p06_txn" )
			)
			( signal "TP_USB3_P06_TXP"
				( objectStatus "@baseboard_fab2_lib.baseboard_fab2(sch_1):tp_usb3_p06_txp" )
			)
			( signal "USB2_P01_DN"
				( objectStatus "@baseboard_fab2_lib.baseboard_fab2(sch_1):usb2_p01_dn" )
			)
			( signal "USB2_P01_DP"
				( objectStatus "@baseboard_fab2_lib.baseboard_fab2(sch_1):usb2_p01_dp" )
			)
			( signal "USB2_PCH_BMC_P5_DN"
				( objectStatus "@baseboard_fab2_lib.baseboard_fab2(sch_1):usb2_pch_bmc_p5_dn" )
			)
			( signal "USB2_PCH_BMC_P5_DP"
				( objectStatus "@baseboard_fab2_lib.baseboard_fab2(sch_1):usb2_pch_bmc_p5_dp" )
			)
			( signal "VCC_VA_3V3"
				( objectStatus "@baseboard_fab2_lib.baseboard_fab2(sch_1):vcc_va_3v3" )
			)
			( signal "TP_TPM_SPI_2"
				( objectStatus "@baseboard_fab2_lib.baseboard_fab2(sch_1):tp_tpm_spi_2" )
			)
			( signal "BMC_M_RST_N"
				( objectStatus "@baseboard_fab2_lib.baseboard_fab2(sch_1):bmc_m_rst_n" )
			)
			( signal "USB_PCH_BMC_P4_DN"
				( objectStatus "@baseboard_fab2_lib.baseboard_fab2(sch_1):usb_pch_bmc_p4_dn" )
			)
			( signal "BMC_M_VREFCA"
				( objectStatus "@baseboard_fab2_lib.baseboard_fab2(sch_1):bmc_m_vrefca" )
			)
			( signal "JTAG_BMC_TDI"
				( objectStatus "@baseboard_fab2_lib.baseboard_fab2(sch_1):jtag_bmc_tdi" )
			)
			( signal "FM_UART_ALERT_N"
				( objectStatus "@baseboard_fab2_lib.baseboard_fab2(sch_1):fm_uart_alert_n" )
			)
			( signal "JTAG_BMC_TCK"
				( objectStatus "@baseboard_fab2_lib.baseboard_fab2(sch_1):jtag_bmc_tck" )
			)
			( signal "SGPIO_BMC_DIN"
				( objectStatus "@baseboard_fab2_lib.baseboard_fab2(sch_1):sgpio_bmc_din" )
			)
			( signal "USB_PCH_BMC_P4_DP"
				( objectStatus "@baseboard_fab2_lib.baseboard_fab2(sch_1):usb_pch_bmc_p4_dp" )
			)
			( signal "VCC_PA_3V3"
				( objectStatus "@baseboard_fab2_lib.baseboard_fab2(sch_1):vcc_pa_3v3" )
			)
			( signal "PECI_BMC_R"
				( objectStatus "@baseboard_fab2_lib.baseboard_fab2(sch_1):peci_bmc_r" )
			)
			( signal "A_EXTCLKN"
				( objectStatus "@baseboard_fab2_lib.baseboard_fab2(sch_1):a_extclkn" )
			)
			( signal "A_EXTCLKP"
				( objectStatus "@baseboard_fab2_lib.baseboard_fab2(sch_1):a_extclkp" )
			)
			( signal "A_PCIE_RCOMP_N"
				( objectStatus "@baseboard_fab2_lib.baseboard_fab2(sch_1):a_pcie_rcomp_n" )
			)
			( signal "A_PCIE_RCOMP_P"
				( objectStatus "@baseboard_fab2_lib.baseboard_fab2(sch_1):a_pcie_rcomp_p" )
			)
			( signal "A_PCIEUP_RCOMP_N"
				( objectStatus "@baseboard_fab2_lib.baseboard_fab2(sch_1):a_pcieup_rcomp_n" )
			)
			( signal "A_PCIEUP_RCOMP_P"
				( objectStatus "@baseboard_fab2_lib.baseboard_fab2(sch_1):a_pcieup_rcomp_p" )
			)
			( signal "P2E_SSB_BMC_RX_C_DN"
				( objectStatus "@baseboard_fab2_lib.baseboard_fab2(sch_1):p2e_ssb_bmc_rx_c_dn" )
			)
			( signal "P2E_SSB_BMC_RX_C_DP"
				( objectStatus "@baseboard_fab2_lib.baseboard_fab2(sch_1):p2e_ssb_bmc_rx_c_dp" )
			)
			( signal "P2E_SSB_BMC_TX_C_DN"
				( objectStatus "@baseboard_fab2_lib.baseboard_fab2(sch_1):p2e_ssb_bmc_tx_c_dn" )
			)
			( signal "P2E_SSB_BMC_TX_C_DP"
				( objectStatus "@baseboard_fab2_lib.baseboard_fab2(sch_1):p2e_ssb_bmc_tx_c_dp" )
			)
			( signal "P2E_SSB_BMC_TX_DN"
				( objectStatus "@baseboard_fab2_lib.baseboard_fab2(sch_1):p2e_ssb_bmc_tx_dn" )
			)
			( signal "P2E_SSB_BMC_TX_DP"
				( objectStatus "@baseboard_fab2_lib.baseboard_fab2(sch_1):p2e_ssb_bmc_tx_dp" )
			)
			( signal "P3E_PCH_M2_RX_DN<1>"
				( objectStatus "@baseboard_fab2_lib.baseboard_fab2(sch_1):p3e_pch_m2_rx_dn(1)" )
			)
			( signal "P3E_PCH_M2_RX_DN<2>"
				( objectStatus "@baseboard_fab2_lib.baseboard_fab2(sch_1):p3e_pch_m2_rx_dn(2)" )
			)
			( signal "P3E_PCH_M2_RX_DN<3>"
				( objectStatus "@baseboard_fab2_lib.baseboard_fab2(sch_1):p3e_pch_m2_rx_dn(3)" )
			)
			( signal "P3E_PCH_M2_RX_DP<1>"
				( objectStatus "@baseboard_fab2_lib.baseboard_fab2(sch_1):p3e_pch_m2_rx_dp(1)" )
			)
			( signal "P3E_PCH_M2_RX_DP<2>"
				( objectStatus "@baseboard_fab2_lib.baseboard_fab2(sch_1):p3e_pch_m2_rx_dp(2)" )
			)
			( signal "P3E_PCH_M2_RX_DP<3>"
				( objectStatus "@baseboard_fab2_lib.baseboard_fab2(sch_1):p3e_pch_m2_rx_dp(3)" )
			)
			( signal "P3E_PCH_M2_TX_DN<1>"
				( objectStatus "@baseboard_fab2_lib.baseboard_fab2(sch_1):p3e_pch_m2_tx_dn(1)" )
			)
			( signal "P3E_PCH_M2_TX_DN<2>"
				( objectStatus "@baseboard_fab2_lib.baseboard_fab2(sch_1):p3e_pch_m2_tx_dn(2)" )
			)
			( signal "P3E_PCH_M2_TX_DN<3>"
				( objectStatus "@baseboard_fab2_lib.baseboard_fab2(sch_1):p3e_pch_m2_tx_dn(3)" )
			)
			( signal "P3E_PCH_M2_TX_DP<1>"
				( objectStatus "@baseboard_fab2_lib.baseboard_fab2(sch_1):p3e_pch_m2_tx_dp(1)" )
			)
			( signal "P3E_PCH_M2_TX_DP<2>"
				( objectStatus "@baseboard_fab2_lib.baseboard_fab2(sch_1):p3e_pch_m2_tx_dp(2)" )
			)
			( signal "P3E_PCH_M2_TX_DP<3>"
				( objectStatus "@baseboard_fab2_lib.baseboard_fab2(sch_1):p3e_pch_m2_tx_dp(3)" )
			)
			( signal "P3E_PCH_RX_0_DN"
				( objectStatus "@baseboard_fab2_lib.baseboard_fab2(sch_1):p3e_pch_rx_0_dn" )
			)
			( signal "P3E_PCH_RX_0_DP"
				( objectStatus "@baseboard_fab2_lib.baseboard_fab2(sch_1):p3e_pch_rx_0_dp" )
			)
			( signal "P3E_PCH_TX_0_DN"
				( objectStatus "@baseboard_fab2_lib.baseboard_fab2(sch_1):p3e_pch_tx_0_dn" )
			)
			( signal "P3E_PCH_TX_0_DP"
				( objectStatus "@baseboard_fab2_lib.baseboard_fab2(sch_1):p3e_pch_tx_0_dp" )
			)
			( signal "PE_PCH_SPRV_RX_C_DN"
				( objectStatus "@baseboard_fab2_lib.baseboard_fab2(sch_1):pe_pch_sprv_rx_c_dn" )
			)
			( signal "PE_PCH_SPRV_RX_C_DP"
				( objectStatus "@baseboard_fab2_lib.baseboard_fab2(sch_1):pe_pch_sprv_rx_c_dp" )
			)
			( signal "PE_PCH_SPRV_TX_DN"
				( objectStatus "@baseboard_fab2_lib.baseboard_fab2(sch_1):pe_pch_sprv_tx_dn" )
			)
			( signal "PE_PCH_SPRV_TX_DP"
				( objectStatus "@baseboard_fab2_lib.baseboard_fab2(sch_1):pe_pch_sprv_tx_dp" )
			)
			( signal "SATA6G_PCH_PCIE_UP_SATA_RXN<0>"
				( objectStatus "@baseboard_fab2_lib.baseboard_fab2(sch_1):sata6g_pch_pcie_up_sata_rxn(0)" )
			)
			( signal "SATA6G_PCH_PCIE_UP_SATA_RXN<1>"
				( objectStatus "@baseboard_fab2_lib.baseboard_fab2(sch_1):sata6g_pch_pcie_up_sata_rxn(1)" )
			)
			( signal "SATA6G_PCH_PCIE_UP_SATA_RXN<2>"
				( objectStatus "@baseboard_fab2_lib.baseboard_fab2(sch_1):sata6g_pch_pcie_up_sata_rxn(2)" )
			)
			( signal "SATA6G_PCH_PCIE_UP_SATA_RXN<3>"
				( objectStatus "@baseboard_fab2_lib.baseboard_fab2(sch_1):sata6g_pch_pcie_up_sata_rxn(3)" )
			)
			( signal "SATA6G_PCH_PCIE_UP_SATA_RXN<4>"
				( objectStatus "@baseboard_fab2_lib.baseboard_fab2(sch_1):sata6g_pch_pcie_up_sata_rxn(4)" )
			)
			( signal "SATA6G_PCH_PCIE_UP_SATA_RXN<5>"
				( objectStatus "@baseboard_fab2_lib.baseboard_fab2(sch_1):sata6g_pch_pcie_up_sata_rxn(5)" )
			)
			( signal "SATA6G_PCH_PCIE_UP_SATA_RXN<6>"
				( objectStatus "@baseboard_fab2_lib.baseboard_fab2(sch_1):sata6g_pch_pcie_up_sata_rxn(6)" )
			)
			( signal "SATA6G_PCH_PCIE_UP_SATA_RXN<7>"
				( objectStatus "@baseboard_fab2_lib.baseboard_fab2(sch_1):sata6g_pch_pcie_up_sata_rxn(7)" )
			)
			( signal "SATA6G_PCH_PCIE_UP_SATA_RXP<0>"
				( objectStatus "@baseboard_fab2_lib.baseboard_fab2(sch_1):sata6g_pch_pcie_up_sata_rxp(0)" )
			)
			( signal "SATA6G_PCH_PCIE_UP_SATA_RXP<1>"
				( objectStatus "@baseboard_fab2_lib.baseboard_fab2(sch_1):sata6g_pch_pcie_up_sata_rxp(1)" )
			)
			( signal "SATA6G_PCH_PCIE_UP_SATA_RXP<2>"
				( objectStatus "@baseboard_fab2_lib.baseboard_fab2(sch_1):sata6g_pch_pcie_up_sata_rxp(2)" )
			)
			( signal "SATA6G_PCH_PCIE_UP_SATA_RXP<3>"
				( objectStatus "@baseboard_fab2_lib.baseboard_fab2(sch_1):sata6g_pch_pcie_up_sata_rxp(3)" )
			)
			( signal "SATA6G_PCH_PCIE_UP_SATA_RXP<4>"
				( objectStatus "@baseboard_fab2_lib.baseboard_fab2(sch_1):sata6g_pch_pcie_up_sata_rxp(4)" )
			)
			( signal "SATA6G_PCH_PCIE_UP_SATA_RXP<5>"
				( objectStatus "@baseboard_fab2_lib.baseboard_fab2(sch_1):sata6g_pch_pcie_up_sata_rxp(5)" )
			)
			( signal "SATA6G_PCH_PCIE_UP_SATA_RXP<6>"
				( objectStatus "@baseboard_fab2_lib.baseboard_fab2(sch_1):sata6g_pch_pcie_up_sata_rxp(6)" )
			)
			( signal "SATA6G_PCH_PCIE_UP_SATA_RXP<7>"
				( objectStatus "@baseboard_fab2_lib.baseboard_fab2(sch_1):sata6g_pch_pcie_up_sata_rxp(7)" )
			)
			( signal "SATA6G_PCH_PCIE_UP_SATA_TXN<0>"
				( objectStatus "@baseboard_fab2_lib.baseboard_fab2(sch_1):sata6g_pch_pcie_up_sata_txn(0)" )
			)
			( signal "SATA6G_PCH_PCIE_UP_SATA_TXN<1>"
				( objectStatus "@baseboard_fab2_lib.baseboard_fab2(sch_1):sata6g_pch_pcie_up_sata_txn(1)" )
			)
			( signal "SATA6G_PCH_PCIE_UP_SATA_TXN<2>"
				( objectStatus "@baseboard_fab2_lib.baseboard_fab2(sch_1):sata6g_pch_pcie_up_sata_txn(2)" )
			)
			( signal "SATA6G_PCH_PCIE_UP_SATA_TXN<3>"
				( objectStatus "@baseboard_fab2_lib.baseboard_fab2(sch_1):sata6g_pch_pcie_up_sata_txn(3)" )
			)
			( signal "SATA6G_PCH_PCIE_UP_SATA_TXN<4>"
				( objectStatus "@baseboard_fab2_lib.baseboard_fab2(sch_1):sata6g_pch_pcie_up_sata_txn(4)" )
			)
			( signal "SATA6G_PCH_PCIE_UP_SATA_TXN<5>"
				( objectStatus "@baseboard_fab2_lib.baseboard_fab2(sch_1):sata6g_pch_pcie_up_sata_txn(5)" )
			)
			( signal "SATA6G_PCH_PCIE_UP_SATA_TXN<6>"
				( objectStatus "@baseboard_fab2_lib.baseboard_fab2(sch_1):sata6g_pch_pcie_up_sata_txn(6)" )
			)
			( signal "SATA6G_PCH_PCIE_UP_SATA_TXN<7>"
				( objectStatus "@baseboard_fab2_lib.baseboard_fab2(sch_1):sata6g_pch_pcie_up_sata_txn(7)" )
			)
			( signal "SATA6G_PCH_PCIE_UP_SATA_TXP<0>"
				( objectStatus "@baseboard_fab2_lib.baseboard_fab2(sch_1):sata6g_pch_pcie_up_sata_txp(0)" )
			)
			( signal "SATA6G_PCH_PCIE_UP_SATA_TXP<1>"
				( objectStatus "@baseboard_fab2_lib.baseboard_fab2(sch_1):sata6g_pch_pcie_up_sata_txp(1)" )
			)
			( signal "SATA6G_PCH_PCIE_UP_SATA_TXP<2>"
				( objectStatus "@baseboard_fab2_lib.baseboard_fab2(sch_1):sata6g_pch_pcie_up_sata_txp(2)" )
			)
			( signal "SATA6G_PCH_PCIE_UP_SATA_TXP<3>"
				( objectStatus "@baseboard_fab2_lib.baseboard_fab2(sch_1):sata6g_pch_pcie_up_sata_txp(3)" )
			)
			( signal "SATA6G_PCH_PCIE_UP_SATA_TXP<4>"
				( objectStatus "@baseboard_fab2_lib.baseboard_fab2(sch_1):sata6g_pch_pcie_up_sata_txp(4)" )
			)
			( signal "SATA6G_PCH_PCIE_UP_SATA_TXP<5>"
				( objectStatus "@baseboard_fab2_lib.baseboard_fab2(sch_1):sata6g_pch_pcie_up_sata_txp(5)" )
			)
			( signal "SATA6G_PCH_PCIE_UP_SATA_TXP<6>"
				( objectStatus "@baseboard_fab2_lib.baseboard_fab2(sch_1):sata6g_pch_pcie_up_sata_txp(6)" )
			)
			( signal "SATA6G_PCH_PCIE_UP_SATA_TXP<7>"
				( objectStatus "@baseboard_fab2_lib.baseboard_fab2(sch_1):sata6g_pch_pcie_up_sata_txp(7)" )
			)
			( signal "BMC_PWR_DEBUG_N"
				( objectStatus "@baseboard_fab2_lib.baseboard_fab2(sch_1):bmc_pwr_debug_n" )
			)
			( signal "BMC_PREQ_N"
				( objectStatus "@baseboard_fab2_lib.baseboard_fab2(sch_1):bmc_preq_n" )
			)
			( signal "SATA6G_S0_RX_DN"
				( objectStatus "@baseboard_fab2_lib.baseboard_fab2(sch_1):sata6g_s0_rx_dn" )
			)
			( signal "SATA6G_S0_RX_DP"
				( objectStatus "@baseboard_fab2_lib.baseboard_fab2(sch_1):sata6g_s0_rx_dp" )
			)
			( signal "SATA6G_S0_TX_DN"
				( objectStatus "@baseboard_fab2_lib.baseboard_fab2(sch_1):sata6g_s0_tx_dn" )
			)
			( signal "SATA6G_S0_TX_DP"
				( objectStatus "@baseboard_fab2_lib.baseboard_fab2(sch_1):sata6g_s0_tx_dp" )
			)
			( signal "SATA6G_S1_RX_DN"
				( objectStatus "@baseboard_fab2_lib.baseboard_fab2(sch_1):sata6g_s1_rx_dn" )
			)
			( signal "SATA6G_S1_RX_DP"
				( objectStatus "@baseboard_fab2_lib.baseboard_fab2(sch_1):sata6g_s1_rx_dp" )
			)
			( signal "SATA6G_S1_TX_DN"
				( objectStatus "@baseboard_fab2_lib.baseboard_fab2(sch_1):sata6g_s1_tx_dn" )
			)
			( signal "SATA6G_S1_TX_DP"
				( objectStatus "@baseboard_fab2_lib.baseboard_fab2(sch_1):sata6g_s1_tx_dp" )
			)
			( signal "BMC_PRDY_N"
				( objectStatus "@baseboard_fab2_lib.baseboard_fab2(sch_1):bmc_prdy_n" )
			)
			( signal "BMC_RSMRST_B_N"
				( objectStatus "@baseboard_fab2_lib.baseboard_fab2(sch_1):bmc_rsmrst_b_n" )
			)
			( signal "BMC_TCK_MUX_SEL"
				( objectStatus "@baseboard_fab2_lib.baseboard_fab2(sch_1):bmc_tck_mux_sel" )
			)
			( signal "TP_PCH_RSVD47"
				( objectStatus "@baseboard_fab2_lib.baseboard_fab2(sch_1):tp_pch_rsvd47" )
			)
			( signal "TP_PCH_RSVD48"
				( objectStatus "@baseboard_fab2_lib.baseboard_fab2(sch_1):tp_pch_rsvd48" )
			)
			( signal "TP_PCH_RSVD49"
				( objectStatus "@baseboard_fab2_lib.baseboard_fab2(sch_1):tp_pch_rsvd49" )
			)
			( signal "TP_PCH_RSVD50"
				( objectStatus "@baseboard_fab2_lib.baseboard_fab2(sch_1):tp_pch_rsvd50" )
			)
			( signal "TP_PCH_RSVD51"
				( objectStatus "@baseboard_fab2_lib.baseboard_fab2(sch_1):tp_pch_rsvd51" )
			)
			( signal "TP_PCH_RSVD52"
				( objectStatus "@baseboard_fab2_lib.baseboard_fab2(sch_1):tp_pch_rsvd52" )
			)
			( signal "DMI_CPU0_PCH_RX_DN<0>"
				( objectStatus "@baseboard_fab2_lib.baseboard_fab2(sch_1):dmi_cpu0_pch_rx_dn(0)" )
			)
			( signal "DMI_CPU0_PCH_RX_DN<1>"
				( objectStatus "@baseboard_fab2_lib.baseboard_fab2(sch_1):dmi_cpu0_pch_rx_dn(1)" )
			)
			( signal "DMI_CPU0_PCH_RX_DN<2>"
				( objectStatus "@baseboard_fab2_lib.baseboard_fab2(sch_1):dmi_cpu0_pch_rx_dn(2)" )
			)
			( signal "DMI_CPU0_PCH_RX_DN<3>"
				( objectStatus "@baseboard_fab2_lib.baseboard_fab2(sch_1):dmi_cpu0_pch_rx_dn(3)" )
			)
			( signal "DMI_CPU0_PCH_RX_DP<0>"
				( objectStatus "@baseboard_fab2_lib.baseboard_fab2(sch_1):dmi_cpu0_pch_rx_dp(0)" )
			)
			( signal "DMI_CPU0_PCH_RX_DP<1>"
				( objectStatus "@baseboard_fab2_lib.baseboard_fab2(sch_1):dmi_cpu0_pch_rx_dp(1)" )
			)
			( signal "DMI_CPU0_PCH_RX_DP<2>"
				( objectStatus "@baseboard_fab2_lib.baseboard_fab2(sch_1):dmi_cpu0_pch_rx_dp(2)" )
			)
			( signal "DMI_CPU0_PCH_RX_DP<3>"
				( objectStatus "@baseboard_fab2_lib.baseboard_fab2(sch_1):dmi_cpu0_pch_rx_dp(3)" )
			)
			( signal "DMI_CPU0_PCH_TX_C_DN<0>"
				( objectStatus "@baseboard_fab2_lib.baseboard_fab2(sch_1):dmi_cpu0_pch_tx_c_dn(0)" )
			)
			( signal "DMI_CPU0_PCH_TX_C_DN<1>"
				( objectStatus "@baseboard_fab2_lib.baseboard_fab2(sch_1):dmi_cpu0_pch_tx_c_dn(1)" )
			)
			( signal "DMI_CPU0_PCH_TX_C_DN<2>"
				( objectStatus "@baseboard_fab2_lib.baseboard_fab2(sch_1):dmi_cpu0_pch_tx_c_dn(2)" )
			)
			( signal "DMI_CPU0_PCH_TX_C_DN<3>"
				( objectStatus "@baseboard_fab2_lib.baseboard_fab2(sch_1):dmi_cpu0_pch_tx_c_dn(3)" )
			)
			( signal "DMI_CPU0_PCH_TX_C_DP<0>"
				( objectStatus "@baseboard_fab2_lib.baseboard_fab2(sch_1):dmi_cpu0_pch_tx_c_dp(0)" )
			)
			( signal "DMI_CPU0_PCH_TX_C_DP<1>"
				( objectStatus "@baseboard_fab2_lib.baseboard_fab2(sch_1):dmi_cpu0_pch_tx_c_dp(1)" )
			)
			( signal "DMI_CPU0_PCH_TX_C_DP<2>"
				( objectStatus "@baseboard_fab2_lib.baseboard_fab2(sch_1):dmi_cpu0_pch_tx_c_dp(2)" )
			)
			( signal "DMI_CPU0_PCH_TX_C_DP<3>"
				( objectStatus "@baseboard_fab2_lib.baseboard_fab2(sch_1):dmi_cpu0_pch_tx_c_dp(3)" )
			)
			( signal "BMC_M_RAS_N"
				( objectStatus "@baseboard_fab2_lib.baseboard_fab2(sch_1):bmc_m_ras_n" )
			)
			( signal "A_KR0_RBIAS"
				( objectStatus "@baseboard_fab2_lib.baseboard_fab2(sch_1):a_kr0_rbias" )
			)
			( signal "A_KR1_RBIAS"
				( objectStatus "@baseboard_fab2_lib.baseboard_fab2(sch_1):a_kr1_rbias" )
			)
			( signal "BMC_M_MALERT_N"
				( objectStatus "@baseboard_fab2_lib.baseboard_fab2(sch_1):bmc_m_malert_n" )
			)
			( signal "IRQ_LVC3_WAKE_R_N"
				( objectStatus "@baseboard_fab2_lib.baseboard_fab2(sch_1):irq_lvc3_wake_r_n" )
			)
			( signal "SMB_BMC_PMBUS_STBY_LVC3_SCL_R"
				( objectStatus "@baseboard_fab2_lib.baseboard_fab2(sch_1):smb_bmc_pmbus_stby_lvc3_scl_r" )
			)
			( signal "PU_TRI_STATE_EN"
				( objectStatus "@baseboard_fab2_lib.baseboard_fab2(sch_1):pu_tri_state_en" )
			)
			( signal "FM_PE_OCP_WAKE_N"
				( objectStatus "@baseboard_fab2_lib.baseboard_fab2(sch_1):fm_pe_ocp_wake_n" )
			)
			( signal "SGPIO_BMC_CLK"
				( objectStatus "@baseboard_fab2_lib.baseboard_fab2(sch_1):sgpio_bmc_clk" )
			)
			( signal "FM_10GBE_LOM_DISABLE_N"
				( objectStatus "@baseboard_fab2_lib.baseboard_fab2(sch_1):fm_10gbe_lom_disable_n" )
			)
			( signal "FM_1GB_LOM_DISABLE_N"
				( objectStatus "@baseboard_fab2_lib.baseboard_fab2(sch_1):fm_1gb_lom_disable_n" )
			)
			( signal "FM_BATTERY_SENSE_EN_N"
				( objectStatus "@baseboard_fab2_lib.baseboard_fab2(sch_1):fm_battery_sense_en_n" )
			)
			( signal "FM_BMC_CPLD_MP_RST_N"
				( objectStatus "@baseboard_fab2_lib.baseboard_fab2(sch_1):fm_bmc_cpld_mp_rst_n" )
			)
			( signal "FM_GBE_LOM_DISABLE_N"
				( objectStatus "@baseboard_fab2_lib.baseboard_fab2(sch_1):fm_gbe_lom_disable_n" )
			)
			( signal "FM_PCH_LVC1_THERMTRIP_N"
				( objectStatus "@baseboard_fab2_lib.baseboard_fab2(sch_1):fm_pch_lvc1_thermtrip_n" )
			)
			( signal "FM_PCH_PWRBTN_N"
				( objectStatus "@baseboard_fab2_lib.baseboard_fab2(sch_1):fm_pch_pwrbtn_n" )
			)
			( signal "FM_SLP_SUS_N"
				( objectStatus "@baseboard_fab2_lib.baseboard_fab2(sch_1):fm_slp_sus_n" )
			)
			( signal "FM_SLPS3_N"
				( objectStatus "@baseboard_fab2_lib.baseboard_fab2(sch_1):fm_slps3_n" )
			)
			( signal "FM_SLPS4_N"
				( objectStatus "@baseboard_fab2_lib.baseboard_fab2(sch_1):fm_slps4_n" )
			)
			( signal "H_PM_SYNC1_GTL_R"
				( objectStatus "@baseboard_fab2_lib.baseboard_fab2(sch_1):h_pm_sync1_gtl_r" )
			)
			( signal "IRQ_LVC3_WAKE_N"
				( objectStatus "@baseboard_fab2_lib.baseboard_fab2(sch_1):irq_lvc3_wake_n" )
			)
			( signal "IRQ_SML1_PMBUS_ALERT_N"
				( objectStatus "@baseboard_fab2_lib.baseboard_fab2(sch_1):irq_sml1_pmbus_alert_n" )
			)
			( signal "KR_P0_OCP_RX_C_DN"
				( objectStatus "@baseboard_fab2_lib.baseboard_fab2(sch_1):kr_p0_ocp_rx_c_dn" )
			)
			( signal "KR_P0_OCP_RX_C_DP"
				( objectStatus "@baseboard_fab2_lib.baseboard_fab2(sch_1):kr_p0_ocp_rx_c_dp" )
			)
			( signal "KR_P0_OCP_TX_DN"
				( objectStatus "@baseboard_fab2_lib.baseboard_fab2(sch_1):kr_p0_ocp_tx_dn" )
			)
			( signal "KR_P0_OCP_TX_DP"
				( objectStatus "@baseboard_fab2_lib.baseboard_fab2(sch_1):kr_p0_ocp_tx_dp" )
			)
			( signal "P1V05_PCH_STBY_KR_PLL"
				( attribute "VOLTAGE" "1.05V"
					( Units "uVoltage" "V" 1.000000)
					( Status sAliasFlattened )
					( Origin gFrontEnd )
				)
				( objectStatus "@baseboard_fab2_lib.baseboard_fab2(sch_1):p1v05_pch_stby_kr_pll" )
			)
			( signal "PECI_PCH"
				( objectStatus "@baseboard_fab2_lib.baseboard_fab2(sch_1):peci_pch" )
			)
			( signal "PWRGD_DSW_PWROK"
				( objectStatus "@baseboard_fab2_lib.baseboard_fab2(sch_1):pwrgd_dsw_pwrok" )
			)
			( signal "PWRGD_PCH_PWROK"
				( objectStatus "@baseboard_fab2_lib.baseboard_fab2(sch_1):pwrgd_pch_pwrok" )
			)
			( signal "PWRGD_PVCCIO_CPU0"
				( objectStatus "@baseboard_fab2_lib.baseboard_fab2(sch_1):pwrgd_pvccio_cpu0" )
			)
			( signal "PWRGD_SYS_PWROK"
				( objectStatus "@baseboard_fab2_lib.baseboard_fab2(sch_1):pwrgd_sys_pwrok" )
			)
			( signal "RST_BMC_SRST_N"
				( objectStatus "@baseboard_fab2_lib.baseboard_fab2(sch_1):rst_bmc_srst_n" )
			)
			( signal "RST_BMC_SRST_R_N"
				( objectStatus "@baseboard_fab2_lib.baseboard_fab2(sch_1):rst_bmc_srst_r_n" )
			)
			( signal "RST_BMC_SYSRST_BTN_OUT_B_N"
				( objectStatus "@baseboard_fab2_lib.baseboard_fab2(sch_1):rst_bmc_sysrst_btn_out_b_n" )
			)
			( signal "TP_10GBE_KR0_MON_DN"
				( objectStatus "@baseboard_fab2_lib.baseboard_fab2(sch_1):tp_10gbe_kr0_mon_dn" )
			)
			( signal "TP_10GBE_KR0_MON_DP"
				( objectStatus "@baseboard_fab2_lib.baseboard_fab2(sch_1):tp_10gbe_kr0_mon_dp" )
			)
			( signal "TP_10GBE_KR1_MON_DN"
				( objectStatus "@baseboard_fab2_lib.baseboard_fab2(sch_1):tp_10gbe_kr1_mon_dn" )
			)
			( signal "TP_10GBE_KR1_MON_DP"
				( objectStatus "@baseboard_fab2_lib.baseboard_fab2(sch_1):tp_10gbe_kr1_mon_dp" )
			)
			( signal "TP_CPU_PCH_TRIGGER_IN"
				( objectStatus "@baseboard_fab2_lib.baseboard_fab2(sch_1):tp_cpu_pch_trigger_in" )
			)
			( signal "TP_CPU_PCH_TRIGGER_OUT"
				( objectStatus "@baseboard_fab2_lib.baseboard_fab2(sch_1):tp_cpu_pch_trigger_out" )
			)
			( signal "TP_PCH_RSVD32"
				( objectStatus "@baseboard_fab2_lib.baseboard_fab2(sch_1):tp_pch_rsvd32" )
			)
			( signal "TP_PCH_RSVD33"
				( objectStatus "@baseboard_fab2_lib.baseboard_fab2(sch_1):tp_pch_rsvd33" )
			)
			( signal "TP_PCH_RSVD34"
				( objectStatus "@baseboard_fab2_lib.baseboard_fab2(sch_1):tp_pch_rsvd34" )
			)
			( signal "TP_PCH_RSVD35"
				( objectStatus "@baseboard_fab2_lib.baseboard_fab2(sch_1):tp_pch_rsvd35" )
			)
			( signal "TP_PCH_RSVD36"
				( objectStatus "@baseboard_fab2_lib.baseboard_fab2(sch_1):tp_pch_rsvd36" )
			)
			( signal "TP_PCH_RSVD38"
				( objectStatus "@baseboard_fab2_lib.baseboard_fab2(sch_1):tp_pch_rsvd38" )
			)
			( signal "TP_PCH_RSVD41"
				( objectStatus "@baseboard_fab2_lib.baseboard_fab2(sch_1):tp_pch_rsvd41" )
			)
			( signal "TP_PCH_RSVD42"
				( objectStatus "@baseboard_fab2_lib.baseboard_fab2(sch_1):tp_pch_rsvd42" )
			)
			( signal "TP_PCH_RSVD54"
				( objectStatus "@baseboard_fab2_lib.baseboard_fab2(sch_1):tp_pch_rsvd54" )
			)
			( signal "TP_SLP_LAN_N"
				( objectStatus "@baseboard_fab2_lib.baseboard_fab2(sch_1):tp_slp_lan_n" )
			)
			( signal "FM_BOARD_REV_ID2"
				( objectStatus "@baseboard_fab2_lib.baseboard_fab2(sch_1):fm_board_rev_id2" )
			)
			( signal "P3V3_STBY_BMC_ADCVREFP"
				( attribute "VOLTAGE" "+3.3V"
					( Units "uVoltage" "V" 1.000000)
					( Status sAliasFlattened )
					( Origin gFrontEnd )
				)
				( objectStatus "@baseboard_fab2_lib.baseboard_fab2(sch_1):p3v3_stby_bmc_adcvrefp" )
			)
			( signal "RMII_BMC_OCP_RXD1"
				( objectStatus "@baseboard_fab2_lib.baseboard_fab2(sch_1):rmii_bmc_ocp_rxd1" )
			)
			( signal "XTAL_KR_25M_IN"
				( objectStatus "@baseboard_fab2_lib.baseboard_fab2(sch_1):xtal_kr_25m_in" )
			)
			( signal "FM_CPLD_BMC_PWRDN_N"
				( objectStatus "@baseboard_fab2_lib.baseboard_fab2(sch_1):fm_cpld_bmc_pwrdn_n" )
			)
			( signal "NIC_MDI_SPRV_RJ45_1_R_DN"
				( objectStatus "@baseboard_fab2_lib.baseboard_fab2(sch_1):nic_mdi_sprv_rj45_1_r_dn" )
			)
			( signal "FM_HEARTBEAT_LED"
				( objectStatus "@baseboard_fab2_lib.baseboard_fab2(sch_1):fm_heartbeat_led" )
			)
			( signal "A_P3V3_STBY_SCALED"
				( attribute "VOLTAGE" "+1.8V"
					( Units "uVoltage" "V" 1.000000)
					( Status sAliasFlattened )
					( Origin gFrontEnd )
				)
				( objectStatus "@baseboard_fab2_lib.baseboard_fab2(sch_1):a_p3v3_stby_scaled" )
			)
			( signal "XTAL_KR_25M_OUT"
				( objectStatus "@baseboard_fab2_lib.baseboard_fab2(sch_1):xtal_kr_25m_out" )
			)
			( signal "FM_BOARD_REV_ID1"
				( objectStatus "@baseboard_fab2_lib.baseboard_fab2(sch_1):fm_board_rev_id1" )
			)
			( signal "FM_BOARD_REV_ID0"
				( objectStatus "@baseboard_fab2_lib.baseboard_fab2(sch_1):fm_board_rev_id0" )
			)
			( signal "FM_CPU1_RC_EN"
				( objectStatus "@baseboard_fab2_lib.baseboard_fab2(sch_1):fm_cpu1_rc_en" )
			)
			( signal "A_PVNN_STBY_PCH_SENSOR"
				( attribute "VOLTAGE" "+1.2V"
					( Units "uVoltage" "V" 1.000000)
					( Status sAliasFlattened )
					( Origin gFrontEnd )
				)
				( objectStatus "@baseboard_fab2_lib.baseboard_fab2(sch_1):a_pvnn_stby_pch_sensor" )
			)
			( signal "CLK_24M_BMC_LPC"
				( objectStatus "@baseboard_fab2_lib.baseboard_fab2(sch_1):clk_24m_bmc_lpc" )
			)
			( signal "FM_BB_BMC_MP_GPIO"
				( objectStatus "@baseboard_fab2_lib.baseboard_fab2(sch_1):fm_bb_bmc_mp_gpio" )
			)
			( signal "FM_BIOS_POST_CMPLT_N"
				( objectStatus "@baseboard_fab2_lib.baseboard_fab2(sch_1):fm_bios_post_cmplt_n" )
			)
			( signal "FM_BIOS_PREFRB2_GOOD"
				( objectStatus "@baseboard_fab2_lib.baseboard_fab2(sch_1):fm_bios_prefrb2_good" )
			)
			( signal "SGPIO_BMC_DOUT_R"
				( objectStatus "@baseboard_fab2_lib.baseboard_fab2(sch_1):sgpio_bmc_dout_r" )
			)
			( signal "FM_BIOS_TOP_SWAP_SPKR"
				( objectStatus "@baseboard_fab2_lib.baseboard_fab2(sch_1):fm_bios_top_swap_spkr" )
			)
			( signal "LPC_LAD2_IO2_R"
				( objectStatus "@baseboard_fab2_lib.baseboard_fab2(sch_1):lpc_lad2_io2_r" )
			)
			( signal "FM_BMC_CPLD_GPO"
				( objectStatus "@baseboard_fab2_lib.baseboard_fab2(sch_1):fm_bmc_cpld_gpo" )
			)
			( signal "VCC_D_3V3"
				( objectStatus "@baseboard_fab2_lib.baseboard_fab2(sch_1):vcc_d_3v3" )
			)
			( signal "LPC_LFRAME_N_CS0_R_N"
				( objectStatus "@baseboard_fab2_lib.baseboard_fab2(sch_1):lpc_lframe_n_cs0_r_n" )
			)
			( signal "RMII_BMC_OCP_TXD1"
				( objectStatus "@baseboard_fab2_lib.baseboard_fab2(sch_1):rmii_bmc_ocp_txd1" )
			)
			( signal "FM_BMC_ENABLE_N"
				( objectStatus "@baseboard_fab2_lib.baseboard_fab2(sch_1):fm_bmc_enable_n" )
			)
			( signal "BMC_M_ODT"
				( objectStatus "@baseboard_fab2_lib.baseboard_fab2(sch_1):bmc_m_odt" )
			)
			( signal "FM_BMC_HEARTBEAT_N"
				( objectStatus "@baseboard_fab2_lib.baseboard_fab2(sch_1):fm_bmc_heartbeat_n" )
			)
			( signal "FM_CPU0_THERMTRIP_LATCH_LVT3_N"
				( objectStatus "@baseboard_fab2_lib.baseboard_fab2(sch_1):fm_cpu0_thermtrip_latch_lvt3_n" )
			)
			( signal "FM_CPU_BMC_INIT"
				( objectStatus "@baseboard_fab2_lib.baseboard_fab2(sch_1):fm_cpu_bmc_init" )
			)
			( signal "FM_CPU_CATERR_DLY_LVT3_N"
				( objectStatus "@baseboard_fab2_lib.baseboard_fab2(sch_1):fm_cpu_caterr_dly_lvt3_n" )
			)
			( signal "FM_CPU_CATERR_DLY_LVT3_R_N"
				( objectStatus "@baseboard_fab2_lib.baseboard_fab2(sch_1):fm_cpu_caterr_dly_lvt3_r_n" )
			)
			( signal "FM_FAST_PROCHOT_EN_N"
				( objectStatus "@baseboard_fab2_lib.baseboard_fab2(sch_1):fm_fast_prochot_en_n" )
			)
			( signal "FM_GLOBAL_RST_WARN_N"
				( objectStatus "@baseboard_fab2_lib.baseboard_fab2(sch_1):fm_global_rst_warn_n" )
			)
			( signal "FM_MB_SLOT_ID0"
				( objectStatus "@baseboard_fab2_lib.baseboard_fab2(sch_1):fm_mb_slot_id0" )
			)
			( signal "SMB_PCH_MEZZ_LOM3_SDA"
				( objectStatus "@baseboard_fab2_lib.baseboard_fab2(sch_1):smb_pch_mezz_lom3_sda" )
			)
			( signal "FM_MB_SLOT_ID1"
				( objectStatus "@baseboard_fab2_lib.baseboard_fab2(sch_1):fm_mb_slot_id1" )
			)
			( signal "SMB_PCH_MEZZ_LOM1_SCL"
				( objectStatus "@baseboard_fab2_lib.baseboard_fab2(sch_1):smb_pch_mezz_lom1_scl" )
			)
			( signal "SMB_PCH_MEZZ_LOM3_SCL"
				( objectStatus "@baseboard_fab2_lib.baseboard_fab2(sch_1):smb_pch_mezz_lom3_scl" )
			)
			( signal "PD_SMB_M2_EN"
				( objectStatus "@baseboard_fab2_lib.baseboard_fab2(sch_1):pd_smb_m2_en" )
			)
			( signal "SMB_VR_STBY_LVC3_SDA_R1"
				( objectStatus "@baseboard_fab2_lib.baseboard_fab2(sch_1):smb_vr_stby_lvc3_sda_r1" )
			)
			( signal "SMB_VR_STBY_LVC3_SCL_R1"
				( objectStatus "@baseboard_fab2_lib.baseboard_fab2(sch_1):smb_vr_stby_lvc3_scl_r1" )
			)
			( signal "FM_MB_SLOT_ID2"
				( objectStatus "@baseboard_fab2_lib.baseboard_fab2(sch_1):fm_mb_slot_id2" )
			)
			( signal "BMC_DEBUG_EN_N"
				( objectStatus "@baseboard_fab2_lib.baseboard_fab2(sch_1):bmc_debug_en_n" )
			)
			( signal "FM_ME_RECOVER_N"
				( objectStatus "@baseboard_fab2_lib.baseboard_fab2(sch_1):fm_me_recover_n" )
			)
			( signal "FM_OCP_MEZZA_PRES_N"
				( objectStatus "@baseboard_fab2_lib.baseboard_fab2(sch_1):fm_ocp_mezza_pres_n" )
			)
			( signal "FM_OCP_MEZZA_PRES"
				( objectStatus "@baseboard_fab2_lib.baseboard_fab2(sch_1):fm_ocp_mezza_pres" )
			)
			( signal "FM_PASSWORD_CLEAR_N"
				( objectStatus "@baseboard_fab2_lib.baseboard_fab2(sch_1):fm_password_clear_n" )
			)
			( signal "FM_PCH_BMC_THERMTRIP_EXI_STRAP_"
				( objectStatus "@baseboard_fab2_lib.baseboard_fab2(sch_1):fm_pch_bmc_thermtrip_exi_strap_n" )
			)
			( signal "FM_PCH_PLD_DATA"
				( objectStatus "@baseboard_fab2_lib.baseboard_fab2(sch_1):fm_pch_pld_data" )
			)
			( signal "FM_PCH_PLD_DATA_R"
				( objectStatus "@baseboard_fab2_lib.baseboard_fab2(sch_1):fm_pch_pld_data_r" )
			)
			( signal "FM_PCH_PWRBTN_OUT_N"
				( objectStatus "@baseboard_fab2_lib.baseboard_fab2(sch_1):fm_pch_pwrbtn_out_n" )
			)
			( signal "FM_PCH_SATA_RAID_KEY"
				( objectStatus "@baseboard_fab2_lib.baseboard_fab2(sch_1):fm_pch_sata_raid_key" )
			)
			( signal "FM_PMBUS_ALERT_BUF_EN_N"
				( objectStatus "@baseboard_fab2_lib.baseboard_fab2(sch_1):fm_pmbus_alert_buf_en_n" )
			)
			( signal "FM_POST_CARD_PRES_BMC_N"
				( objectStatus "@baseboard_fab2_lib.baseboard_fab2(sch_1):fm_post_card_pres_bmc_n" )
			)
			( signal "FM_PWR_BTN_N"
				( objectStatus "@baseboard_fab2_lib.baseboard_fab2(sch_1):fm_pwr_btn_n" )
			)
			( signal "FM_PWR_LED"
				( objectStatus "@baseboard_fab2_lib.baseboard_fab2(sch_1):fm_pwr_led" )
			)
			( signal "FM_PWR_LED_A"
				( objectStatus "@baseboard_fab2_lib.baseboard_fab2(sch_1):fm_pwr_led_a" )
			)
			( signal "FM_PWR_LED_K"
				( objectStatus "@baseboard_fab2_lib.baseboard_fab2(sch_1):fm_pwr_led_k" )
			)
			( signal "FM_PWR_LED_N"
				( objectStatus "@baseboard_fab2_lib.baseboard_fab2(sch_1):fm_pwr_led_n" )
			)
			( signal "FM_QAT_EN_N"
				( objectStatus "@baseboard_fab2_lib.baseboard_fab2(sch_1):fm_qat_en_n" )
			)
			( signal "FM_SLT_CFG2_R"
				( objectStatus "@baseboard_fab2_lib.baseboard_fab2(sch_1):fm_slt_cfg2_r" )
			)
			( signal "FM_PE_BMC_WAKE_N"
				( objectStatus "@baseboard_fab2_lib.baseboard_fab2(sch_1):fm_pe_bmc_wake_n" )
			)
			( signal "NIC_MDI_SPRV_RJ45_3_R_DP"
				( objectStatus "@baseboard_fab2_lib.baseboard_fab2(sch_1):nic_mdi_sprv_rj45_3_r_dp" )
			)
			( signal "FM_XRC_READY_N"
				( objectStatus "@baseboard_fab2_lib.baseboard_fab2(sch_1):fm_xrc_ready_n" )
			)
			( signal "SGPIO_BMC_LD_N"
				( objectStatus "@baseboard_fab2_lib.baseboard_fab2(sch_1):sgpio_bmc_ld_n" )
			)
			( signal "SMB_LAN_STBY_LVC3_SDA_R"
				( objectStatus "@baseboard_fab2_lib.baseboard_fab2(sch_1):smb_lan_stby_lvc3_sda_r" )
			)
			( signal "FM_UART_PRES_N"
				( objectStatus "@baseboard_fab2_lib.baseboard_fab2(sch_1):fm_uart_pres_n" )
			)
			( signal "P1V2_AUX_BMC"
				( attribute "VOLTAGE" "1.5"
					( Units "uVoltage" "V" 1.000000)
					( Status sAliasFlattened )
					( Origin gFrontEnd )
				)
				( objectStatus "@baseboard_fab2_lib.baseboard_fab2(sch_1):p1v2_aux_bmc" )
			)
			( signal "FM_USB_P0_EN_BOOT_BIOS_STRAP_N"
				( objectStatus "@baseboard_fab2_lib.baseboard_fab2(sch_1):fm_usb_p0_en_boot_bios_strap_n" )
			)
			( signal "BMC_MIOZ"
				( objectStatus "@baseboard_fab2_lib.baseboard_fab2(sch_1):bmc_mioz" )
			)
			( signal "FM_UV_ADR_TRIGGER_EN"
				( objectStatus "@baseboard_fab2_lib.baseboard_fab2(sch_1):fm_uv_adr_trigger_en" )
			)
			( signal "FM_XRC_PRESENT_N"
				( objectStatus "@baseboard_fab2_lib.baseboard_fab2(sch_1):fm_xrc_present_n" )
			)
			( signal "FP_NMI_BTN_N"
				( objectStatus "@baseboard_fab2_lib.baseboard_fab2(sch_1):fp_nmi_btn_n" )
			)
			( signal "H_CPU0_FAST_WAKE_LVT3_N"
				( objectStatus "@baseboard_fab2_lib.baseboard_fab2(sch_1):h_cpu0_fast_wake_lvt3_n" )
			)
			( signal "IRQ_BMC_PCH_NMI_STBY_R_N"
				( objectStatus "@baseboard_fab2_lib.baseboard_fab2(sch_1):irq_bmc_pch_nmi_stby_r_n" )
			)
			( signal "IRQ_BMC_PCH_SCI_LPC_N"
				( objectStatus "@baseboard_fab2_lib.baseboard_fab2(sch_1):irq_bmc_pch_sci_lpc_n" )
			)
			( signal "IRQ_BMC_PCH_SMI_LPC_N"
				( objectStatus "@baseboard_fab2_lib.baseboard_fab2(sch_1):irq_bmc_pch_smi_lpc_n" )
			)
			( signal "IRQ_FORCE_NM_THROTTLE_N"
				( objectStatus "@baseboard_fab2_lib.baseboard_fab2(sch_1):irq_force_nm_throttle_n" )
			)
			( signal "IRQ_HSC_FAULT_N"
				( objectStatus "@baseboard_fab2_lib.baseboard_fab2(sch_1):irq_hsc_fault_n" )
			)
			( signal "IRQ_LOM_ALERT_N"
				( objectStatus "@baseboard_fab2_lib.baseboard_fab2(sch_1):irq_lom_alert_n" )
			)
			( signal "FM_BMC_ONCTL_R_N"
				( objectStatus "@baseboard_fab2_lib.baseboard_fab2(sch_1):fm_bmc_onctl_r_n" )
			)
			( signal "IRQ_LPC_SERIRQ_N"
				( objectStatus "@baseboard_fab2_lib.baseboard_fab2(sch_1):irq_lpc_serirq_n" )
			)
			( signal "IRQ_MEZZ_LAN_ALERT_N"
				( objectStatus "@baseboard_fab2_lib.baseboard_fab2(sch_1):irq_mezz_lan_alert_n" )
			)
			( signal "IRQ_PCH_NIC_ALERT_N"
				( objectStatus "@baseboard_fab2_lib.baseboard_fab2(sch_1):irq_pch_nic_alert_n" )
			)
			( signal "VR_PVDDQ_KLM_PH1_RC"
				( objectStatus "@baseboard_fab2_lib.baseboard_fab2(sch_1):vr_pvddq_klm_ph1_rc" )
			)
			( signal "IRQ_PIRQA_SPI_TPM_N"
				( objectStatus "@baseboard_fab2_lib.baseboard_fab2(sch_1):irq_pirqa_spi_tpm_n" )
			)
			( signal "IRQ_SML0_ALERT_N"
				( objectStatus "@baseboard_fab2_lib.baseboard_fab2(sch_1):irq_sml0_alert_n" )
			)
			( signal "LPC_LAD0_IO0"
				( objectStatus "@baseboard_fab2_lib.baseboard_fab2(sch_1):lpc_lad0_io0" )
			)
			( signal "LPC_LAD1_IO1"
				( objectStatus "@baseboard_fab2_lib.baseboard_fab2(sch_1):lpc_lad1_io1" )
			)
			( signal "LPC_LAD2_IO2"
				( objectStatus "@baseboard_fab2_lib.baseboard_fab2(sch_1):lpc_lad2_io2" )
			)
			( signal "LPC_LAD3_IO3"
				( objectStatus "@baseboard_fab2_lib.baseboard_fab2(sch_1):lpc_lad3_io3" )
			)
			( signal "LPC_LFRAME_N_CS0_N"
				( objectStatus "@baseboard_fab2_lib.baseboard_fab2(sch_1):lpc_lframe_n_cs0_n" )
			)
			( signal "PU_FM_RCIN_N"
				( objectStatus "@baseboard_fab2_lib.baseboard_fab2(sch_1):pu_fm_rcin_n" )
			)
			( signal "PU_IRQ_PCH_SCI_WHEA_N"
				( objectStatus "@baseboard_fab2_lib.baseboard_fab2(sch_1):pu_irq_pch_sci_whea_n" )
			)
			( signal "PU_IRQ_VRALERT_N"
				( objectStatus "@baseboard_fab2_lib.baseboard_fab2(sch_1):pu_irq_vralert_n" )
			)
			( signal "PU_LPC_CLKRUN_N"
				( objectStatus "@baseboard_fab2_lib.baseboard_fab2(sch_1):pu_lpc_clkrun_n" )
			)
			( signal "PU_LPC_PME_N"
				( objectStatus "@baseboard_fab2_lib.baseboard_fab2(sch_1):pu_lpc_pme_n" )
			)
			( signal "PU_PCH_TLS_ENABLE_STRAP"
				( objectStatus "@baseboard_fab2_lib.baseboard_fab2(sch_1):pu_pch_tls_enable_strap" )
			)
			( signal "RST_PCH_SYSRST_BTN_OUT_N"
				( objectStatus "@baseboard_fab2_lib.baseboard_fab2(sch_1):rst_pch_sysrst_btn_out_n" )
			)
			( signal "RST_PLTRST_N"
				( objectStatus "@baseboard_fab2_lib.baseboard_fab2(sch_1):rst_pltrst_n" )
			)
			( signal "RST_SYSTEM_BTN_N"
				( objectStatus "@baseboard_fab2_lib.baseboard_fab2(sch_1):rst_system_btn_n" )
			)
			( signal "SGPIO_PCH_SSATA_DOUT0"
				( objectStatus "@baseboard_fab2_lib.baseboard_fab2(sch_1):sgpio_pch_ssata_dout0" )
			)
			( signal "SMB_HOST_STBY_LVC3_SCL_R1"
				( objectStatus "@baseboard_fab2_lib.baseboard_fab2(sch_1):smb_host_stby_lvc3_scl_r1" )
			)
			( signal "SMB_HOST_STBY_LVC3_SDA_R1"
				( objectStatus "@baseboard_fab2_lib.baseboard_fab2(sch_1):smb_host_stby_lvc3_sda_r1" )
			)
			( signal "SMB_PMBUS_BMC_STBY_LVC3_SCL_R1"
				( objectStatus "@baseboard_fab2_lib.baseboard_fab2(sch_1):smb_pmbus_bmc_stby_lvc3_scl_r1" )
			)
			( signal "SMB_PMBUS_BMC_STBY_LVC3_SDA_R1"
				( objectStatus "@baseboard_fab2_lib.baseboard_fab2(sch_1):smb_pmbus_bmc_stby_lvc3_sda_r1" )
			)
			( signal "SMB_SMLINK0_STBY_LVC3_SCL_R1"
				( objectStatus "@baseboard_fab2_lib.baseboard_fab2(sch_1):smb_smlink0_stby_lvc3_scl_r1" )
			)
			( signal "SMB_SMLINK0_STBY_LVC3_SDA_R1"
				( objectStatus "@baseboard_fab2_lib.baseboard_fab2(sch_1):smb_smlink0_stby_lvc3_sda_r1" )
			)
			( signal "SP2_BMC_CM_UART_RX"
				( objectStatus "@baseboard_fab2_lib.baseboard_fab2(sch_1):sp2_bmc_cm_uart_rx" )
			)
			( signal "SP2_BMC_CM_UART_TX"
				( objectStatus "@baseboard_fab2_lib.baseboard_fab2(sch_1):sp2_bmc_cm_uart_tx" )
			)
			( signal "VID_PCH_CORE_PVNN_AUX_VID_0"
				( objectStatus "@baseboard_fab2_lib.baseboard_fab2(sch_1):vid_pch_core_pvnn_aux_vid_0" )
			)
			( signal "VID_PCH_CORE_PVNN_AUX_VID_1"
				( objectStatus "@baseboard_fab2_lib.baseboard_fab2(sch_1):vid_pch_core_pvnn_aux_vid_1" )
			)
			( signal "A_P3V_BAT_SCALED"
				( attribute "VOLTAGE" "+1V"
					( Units "uVoltage" "V" 1.000000)
					( Status sAliasFlattened )
					( Origin gFrontEnd )
				)
				( objectStatus "@baseboard_fab2_lib.baseboard_fab2(sch_1):a_p3v_bat_scaled" )
			)
			( signal "A_RCOMP_3P3"
				( objectStatus "@baseboard_fab2_lib.baseboard_fab2(sch_1):a_rcomp_3p3" )
			)
			( signal "A_P5V_STBY_SCALED"
				( attribute "VOLTAGE" "+2V"
					( Units "uVoltage" "V" 1.000000)
					( Status sAliasFlattened )
					( Origin gFrontEnd )
				)
				( objectStatus "@baseboard_fab2_lib.baseboard_fab2(sch_1):a_p5v_stby_scaled" )
			)
			( signal "A_P3V3_SCALED"
				( attribute "VOLTAGE" "+2V"
					( Units "uVoltage" "V" 1.000000)
					( Status sAliasFlattened )
					( Origin gFrontEnd )
				)
				( objectStatus "@baseboard_fab2_lib.baseboard_fab2(sch_1):a_p3v3_scaled" )
			)
			( signal "RMII_BMC_PCH_SPRNGVLLE_TXD1_R"
				( objectStatus "@baseboard_fab2_lib.baseboard_fab2(sch_1):rmii_bmc_pch_sprngvlle_txd1_r" )
			)
			( signal "FAN_TACH0"
				( objectStatus "@baseboard_fab2_lib.baseboard_fab2(sch_1):fan_tach0" )
			)
			( signal "A_P1V05_STBY_PCH_SENSOR"
				( attribute "VOLTAGE" "+1.2V"
					( Units "uVoltage" "V" 1.000000)
					( Status sAliasFlattened )
					( Origin gFrontEnd )
				)
				( objectStatus "@baseboard_fab2_lib.baseboard_fab2(sch_1):a_p1v05_stby_pch_sensor" )
			)
			( signal "SPI_BMC_BT_CS_R_N"
				( objectStatus "@baseboard_fab2_lib.baseboard_fab2(sch_1):spi_bmc_bt_cs_r_n" )
			)
			( signal "A_P12V_STBY_SCALED"
				( attribute "VOLTAGE" "+2V"
					( Units "uVoltage" "V" 1.000000)
					( Status sAliasFlattened )
					( Origin gFrontEnd )
				)
				( objectStatus "@baseboard_fab2_lib.baseboard_fab2(sch_1):a_p12v_stby_scaled" )
			)
			( signal "FM_BIOS_SPI_BMC_CTRL"
				( objectStatus "@baseboard_fab2_lib.baseboard_fab2(sch_1):fm_bios_spi_bmc_ctrl" )
			)
			( signal "RMII_BMC_OCP_TXEN_R"
				( objectStatus "@baseboard_fab2_lib.baseboard_fab2(sch_1):rmii_bmc_ocp_txen_r" )
			)
			( signal "FAN_TACH1"
				( objectStatus "@baseboard_fab2_lib.baseboard_fab2(sch_1):fan_tach1" )
			)
			( signal "PU_TPM_SPI_BMC_HOLD_N"
				( objectStatus "@baseboard_fab2_lib.baseboard_fab2(sch_1):pu_tpm_spi_bmc_hold_n" )
			)
			( signal "FAN_TACH2"
				( objectStatus "@baseboard_fab2_lib.baseboard_fab2(sch_1):fan_tach2" )
			)
			( signal "SPI_BMC_BT_DI"
				( objectStatus "@baseboard_fab2_lib.baseboard_fab2(sch_1):spi_bmc_bt_di" )
			)
			( signal "RMII_BMC_OCP_RXD0"
				( objectStatus "@baseboard_fab2_lib.baseboard_fab2(sch_1):rmii_bmc_ocp_rxd0" )
			)
			( signal "FAN_TACH3"
				( objectStatus "@baseboard_fab2_lib.baseboard_fab2(sch_1):fan_tach3" )
			)
			( signal "RMII_BMC_OCP_RXER"
				( objectStatus "@baseboard_fab2_lib.baseboard_fab2(sch_1):rmii_bmc_ocp_rxer" )
			)
			( signal "SPI_BMC_BT_CLK"
				( objectStatus "@baseboard_fab2_lib.baseboard_fab2(sch_1):spi_bmc_bt_clk" )
			)
			( signal "RMII_BMC_OCP_TXEN"
				( objectStatus "@baseboard_fab2_lib.baseboard_fab2(sch_1):rmii_bmc_ocp_txen" )
			)
			( signal "RMII_BMC_OCP_TXD0"
				( objectStatus "@baseboard_fab2_lib.baseboard_fab2(sch_1):rmii_bmc_ocp_txd0" )
			)
			( signal "SPI_BMC_BT_CS_N"
				( objectStatus "@baseboard_fab2_lib.baseboard_fab2(sch_1):spi_bmc_bt_cs_n" )
			)
			( signal "FM_ADR_COMPLETE_R1"
				( objectStatus "@baseboard_fab2_lib.baseboard_fab2(sch_1):fm_adr_complete_r1" )
			)
			( signal "P3V3_STBY_BMC_ADCVREFN"
				( attribute "VOLTAGE" "+3.3V"
					( Units "uVoltage" "V" 1.000000)
					( Status sAliasFlattened )
					( Origin gFrontEnd )
				)
				( objectStatus "@baseboard_fab2_lib.baseboard_fab2(sch_1):p3v3_stby_bmc_adcvrefn" )
			)
			( signal "PD_ADCREXT"
				( objectStatus "@baseboard_fab2_lib.baseboard_fab2(sch_1):pd_adcrext" )
			)
			( signal "FM_BACKUP_BIOS_SEL_N"
				( objectStatus "@baseboard_fab2_lib.baseboard_fab2(sch_1):fm_backup_bios_sel_n" )
			)
			( signal "FM_HEARTBEAT_LED_A"
				( objectStatus "@baseboard_fab2_lib.baseboard_fab2(sch_1):fm_heartbeat_led_a" )
			)
			( signal "FM_BIOS_MRC_DEBUG_MSG_DIS_N"
				( objectStatus "@baseboard_fab2_lib.baseboard_fab2(sch_1):fm_bios_mrc_debug_msg_dis_n" )
			)
			( signal "PD_PEREXT"
				( objectStatus "@baseboard_fab2_lib.baseboard_fab2(sch_1):pd_perext" )
			)
			( signal "FM_BIOS_SMI_ACTIVE_N"
				( objectStatus "@baseboard_fab2_lib.baseboard_fab2(sch_1):fm_bios_smi_active_n" )
			)
			( signal "FM_BIOS_TOP_SWAP"
				( objectStatus "@baseboard_fab2_lib.baseboard_fab2(sch_1):fm_bios_top_swap" )
			)
			( signal "FM_BIOS_USB_RECOVERY"
				( objectStatus "@baseboard_fab2_lib.baseboard_fab2(sch_1):fm_bios_usb_recovery" )
			)
			( signal "FM_BMC_NMI_N"
				( objectStatus "@baseboard_fab2_lib.baseboard_fab2(sch_1):fm_bmc_nmi_n" )
			)
			( signal "FM_BOARD_SKU_ID0"
				( objectStatus "@baseboard_fab2_lib.baseboard_fab2(sch_1):fm_board_sku_id0" )
			)
			( signal "PCA9554_A1"
				( objectStatus "@baseboard_fab2_lib.baseboard_fab2(sch_1):pca9554_a1" )
			)
			( signal "PCA9555_A1"
				( objectStatus "@baseboard_fab2_lib.baseboard_fab2(sch_1):pca9555_a1" )
			)
			( signal "FM_BOARD_SKU_ID1"
				( objectStatus "@baseboard_fab2_lib.baseboard_fab2(sch_1):fm_board_sku_id1" )
			)
			( signal "SPA_MID_DBG2_RX"
				( objectStatus "@baseboard_fab2_lib.baseboard_fab2(sch_1):spa_mid_dbg2_rx" )
			)
			( signal "PCA9555_A2"
				( objectStatus "@baseboard_fab2_lib.baseboard_fab2(sch_1):pca9555_a2" )
			)
			( signal "FM_BOARD_SKU_ID2"
				( objectStatus "@baseboard_fab2_lib.baseboard_fab2(sch_1):fm_board_sku_id2" )
			)
			( signal "FM_BOARD_SKU_ID3"
				( objectStatus "@baseboard_fab2_lib.baseboard_fab2(sch_1):fm_board_sku_id3" )
			)
			( signal "BMC_TPM_HW_C_RST"
				( objectStatus "@baseboard_fab2_lib.baseboard_fab2(sch_1):bmc_tpm_hw_c_rst" )
			)
			( signal "FM_BOARD_SKU_ID4"
				( objectStatus "@baseboard_fab2_lib.baseboard_fab2(sch_1):fm_board_sku_id4" )
			)
			( signal "UV_HIGH_SET"
				( objectStatus "@baseboard_fab2_lib.baseboard_fab2(sch_1):uv_high_set" )
			)
			( signal "FM_CPLD_ADR_TRIGGER_N"
				( objectStatus "@baseboard_fab2_lib.baseboard_fab2(sch_1):fm_cpld_adr_trigger_n" )
			)
			( signal "FM_CPLD_ADR_TRIGGER_R_N"
				( objectStatus "@baseboard_fab2_lib.baseboard_fab2(sch_1):fm_cpld_adr_trigger_r_n" )
			)
			( signal "FM_CPU0_FIVR_FAULT_LVT3_N"
				( objectStatus "@baseboard_fab2_lib.baseboard_fab2(sch_1):fm_cpu0_fivr_fault_lvt3_n" )
			)
			( signal "FM_CPU0_RC_EN"
				( objectStatus "@baseboard_fab2_lib.baseboard_fab2(sch_1):fm_cpu0_rc_en" )
			)
			( signal "FM_CPU1_FIVR_FAULT_LVT3_N"
				( objectStatus "@baseboard_fab2_lib.baseboard_fab2(sch_1):fm_cpu1_fivr_fault_lvt3_n" )
			)
			( signal "FM_CPU1_THERMTRIP_LATCH_LVT3_N"
				( objectStatus "@baseboard_fab2_lib.baseboard_fab2(sch_1):fm_cpu1_thermtrip_latch_lvt3_n" )
			)
			( signal "FM_FLASH_ATTACH_CFG_STRAP"
				( objectStatus "@baseboard_fab2_lib.baseboard_fab2(sch_1):fm_flash_attach_cfg_strap" )
			)
			( signal "FM_FORCE_ADR_N"
				( objectStatus "@baseboard_fab2_lib.baseboard_fab2(sch_1):fm_force_adr_n" )
			)
			( signal "FM_GBE0_LVC3_MOD_ABS"
				( objectStatus "@baseboard_fab2_lib.baseboard_fab2(sch_1):fm_gbe0_lvc3_mod_abs" )
			)
			( signal "FM_GBE1_LVC3_MOD_ABS"
				( objectStatus "@baseboard_fab2_lib.baseboard_fab2(sch_1):fm_gbe1_lvc3_mod_abs" )
			)
			( signal "FM_GBE2_LVC3_MOD_ABS"
				( objectStatus "@baseboard_fab2_lib.baseboard_fab2(sch_1):fm_gbe2_lvc3_mod_abs" )
			)
			( signal "FM_GBE3_LVC3_MOD_ABS"
				( objectStatus "@baseboard_fab2_lib.baseboard_fab2(sch_1):fm_gbe3_lvc3_mod_abs" )
			)
			( signal "SMB_HOST_STBY_LVC3_SDA_R"
				( objectStatus "@baseboard_fab2_lib.baseboard_fab2(sch_1):smb_host_stby_lvc3_sda_r" )
			)
			( signal "FM_HSC_TIMER_EXP_N"
				( objectStatus "@baseboard_fab2_lib.baseboard_fab2(sch_1):fm_hsc_timer_exp_n" )
			)
			( signal "SMB_HOST_STBY_LVC3_SCL_R"
				( objectStatus "@baseboard_fab2_lib.baseboard_fab2(sch_1):smb_host_stby_lvc3_scl_r" )
			)
			( signal "FM_IE_DISABLE_N"
				( objectStatus "@baseboard_fab2_lib.baseboard_fab2(sch_1):fm_ie_disable_n" )
			)
			( signal "SMB_OCP_FRU_STBY_LVC3_SCL_R"
				( objectStatus "@baseboard_fab2_lib.baseboard_fab2(sch_1):smb_ocp_fru_stby_lvc3_scl_r" )
			)
			( signal "SMB_OCP_LAN_STBY_LVC3_SCL_R"
				( objectStatus "@baseboard_fab2_lib.baseboard_fab2(sch_1):smb_ocp_lan_stby_lvc3_scl_r" )
			)
			( signal "FM_MEM_THERM_EVENT_PCH_N"
				( objectStatus "@baseboard_fab2_lib.baseboard_fab2(sch_1):fm_mem_therm_event_pch_n" )
			)
			( signal "FM_MP_PS_FAIL_N"
				( objectStatus "@baseboard_fab2_lib.baseboard_fab2(sch_1):fm_mp_ps_fail_n" )
			)
			( signal "BMC_M_WE_N"
				( objectStatus "@baseboard_fab2_lib.baseboard_fab2(sch_1):bmc_m_we_n" )
			)
			( signal "FM_MP_PS_REDUNDANT_LOST_N"
				( objectStatus "@baseboard_fab2_lib.baseboard_fab2(sch_1):fm_mp_ps_redundant_lost_n" )
			)
			( signal "FM_NMI_EVENT_N"
				( objectStatus "@baseboard_fab2_lib.baseboard_fab2(sch_1):fm_nmi_event_n" )
			)
			( signal "FM_OC0_USB_N"
				( objectStatus "@baseboard_fab2_lib.baseboard_fab2(sch_1):fm_oc0_usb_n" )
			)
			( signal "FM_OC_DETECT_EN_N"
				( objectStatus "@baseboard_fab2_lib.baseboard_fab2(sch_1):fm_oc_detect_en_n" )
			)
			( signal "FM_PCH_BMC_THERMTRIP_N"
				( objectStatus "@baseboard_fab2_lib.baseboard_fab2(sch_1):fm_pch_bmc_thermtrip_n" )
			)
			( signal "FM_SOL_UART_CH_SEL"
				( objectStatus "@baseboard_fab2_lib.baseboard_fab2(sch_1):fm_sol_uart_ch_sel" )
			)
			( signal "FM_SSATA_PCIE_M2_SEL"
				( objectStatus "@baseboard_fab2_lib.baseboard_fab2(sch_1):fm_ssata_pcie_m2_sel" )
			)
			( signal "FM_UARTSW_LSB_N"
				( objectStatus "@baseboard_fab2_lib.baseboard_fab2(sch_1):fm_uartsw_lsb_n" )
			)
			( signal "FM_UARTSW_MSB_N"
				( objectStatus "@baseboard_fab2_lib.baseboard_fab2(sch_1):fm_uartsw_msb_n" )
			)
			( signal "FP_PWR_ID_LED_N"
				( objectStatus "@baseboard_fab2_lib.baseboard_fab2(sch_1):fp_pwr_id_led_n" )
			)
			( signal "IRQ_BMC_PCH_NMI_STBY_N"
				( objectStatus "@baseboard_fab2_lib.baseboard_fab2(sch_1):irq_bmc_pch_nmi_stby_n" )
			)
			( signal "IRQ_BOARD_BMC_ALERT_N"
				( objectStatus "@baseboard_fab2_lib.baseboard_fab2(sch_1):irq_board_bmc_alert_n" )
			)
			( signal "IRQ_OC_DETECT_N"
				( objectStatus "@baseboard_fab2_lib.baseboard_fab2(sch_1):irq_oc_detect_n" )
			)
			( signal "IRQ_UV_DETECT_N"
				( objectStatus "@baseboard_fab2_lib.baseboard_fab2(sch_1):irq_uv_detect_n" )
			)
			( signal "JTAG_PCH_GBE_CLK"
				( objectStatus "@baseboard_fab2_lib.baseboard_fab2(sch_1):jtag_pch_gbe_clk" )
			)
			( signal "JTAG_PCH_GBE_TDI"
				( objectStatus "@baseboard_fab2_lib.baseboard_fab2(sch_1):jtag_pch_gbe_tdi" )
			)
			( signal "JTAG_PCH_GBE_TDO"
				( objectStatus "@baseboard_fab2_lib.baseboard_fab2(sch_1):jtag_pch_gbe_tdo" )
			)
			( signal "JTAG_PCH_GBE_TMS"
				( objectStatus "@baseboard_fab2_lib.baseboard_fab2(sch_1):jtag_pch_gbe_tms" )
			)
			( signal "JTAG_PCH_GBE_TRST_N"
				( objectStatus "@baseboard_fab2_lib.baseboard_fab2(sch_1):jtag_pch_gbe_trst_n" )
			)
			( signal "JTAG_PCH_PLD_TCK"
				( objectStatus "@baseboard_fab2_lib.baseboard_fab2(sch_1):jtag_pch_pld_tck" )
			)
			( signal "JTAG_PCH_PLD_TDI"
				( objectStatus "@baseboard_fab2_lib.baseboard_fab2(sch_1):jtag_pch_pld_tdi" )
			)
			( signal "JTAG_PCH_PLD_TDO"
				( objectStatus "@baseboard_fab2_lib.baseboard_fab2(sch_1):jtag_pch_pld_tdo" )
			)
			( signal "JTAG_PCH_PLD_TMS"
				( objectStatus "@baseboard_fab2_lib.baseboard_fab2(sch_1):jtag_pch_pld_tms" )
			)
			( signal "LED_GBE_P0_0"
				( objectStatus "@baseboard_fab2_lib.baseboard_fab2(sch_1):led_gbe_p0_0" )
			)
			( signal "LED_GBE_P0_1"
				( objectStatus "@baseboard_fab2_lib.baseboard_fab2(sch_1):led_gbe_p0_1" )
			)
			( signal "LED_GBE_P1_0"
				( objectStatus "@baseboard_fab2_lib.baseboard_fab2(sch_1):led_gbe_p1_0" )
			)
			( signal "LED_GBE_P1_1"
				( objectStatus "@baseboard_fab2_lib.baseboard_fab2(sch_1):led_gbe_p1_1" )
			)
			( signal "LED_GBE_P2_0"
				( objectStatus "@baseboard_fab2_lib.baseboard_fab2(sch_1):led_gbe_p2_0" )
			)
			( signal "LED_GBE_P2_1"
				( objectStatus "@baseboard_fab2_lib.baseboard_fab2(sch_1):led_gbe_p2_1" )
			)
			( signal "LED_GBE_P3_0"
				( objectStatus "@baseboard_fab2_lib.baseboard_fab2(sch_1):led_gbe_p3_0" )
			)
			( signal "LED_GBE_P3_1"
				( objectStatus "@baseboard_fab2_lib.baseboard_fab2(sch_1):led_gbe_p3_1" )
			)
			( signal "LED_PCH_SATA_HDD_N"
				( objectStatus "@baseboard_fab2_lib.baseboard_fab2(sch_1):led_pch_sata_hdd_n" )
			)
			( signal "LED_PCH_SSATA_HDD_N"
				( objectStatus "@baseboard_fab2_lib.baseboard_fab2(sch_1):led_pch_ssata_hdd_n" )
			)
			( signal "LED_POSTCODE_0"
				( objectStatus "@baseboard_fab2_lib.baseboard_fab2(sch_1):led_postcode_0" )
			)
			( signal "LED_POSTCODE_1"
				( objectStatus "@baseboard_fab2_lib.baseboard_fab2(sch_1):led_postcode_1" )
			)
			( signal "LED_POSTCODE_2"
				( objectStatus "@baseboard_fab2_lib.baseboard_fab2(sch_1):led_postcode_2" )
			)
			( signal "LED_POSTCODE_3"
				( objectStatus "@baseboard_fab2_lib.baseboard_fab2(sch_1):led_postcode_3" )
			)
			( signal "LED_POSTCODE_4"
				( objectStatus "@baseboard_fab2_lib.baseboard_fab2(sch_1):led_postcode_4" )
			)
			( signal "LED_POSTCODE_5"
				( objectStatus "@baseboard_fab2_lib.baseboard_fab2(sch_1):led_postcode_5" )
			)
			( signal "LED_POSTCODE_6"
				( objectStatus "@baseboard_fab2_lib.baseboard_fab2(sch_1):led_postcode_6" )
			)
			( signal "LED_POSTCODE_7"
				( objectStatus "@baseboard_fab2_lib.baseboard_fab2(sch_1):led_postcode_7" )
			)
			( signal "PU_10GBE_LOM_PCI_DISABLE_N"
				( objectStatus "@baseboard_fab2_lib.baseboard_fab2(sch_1):pu_10gbe_lom_pci_disable_n" )
			)
			( signal "PU_ADR_TIMER_HOLD_OFF_N"
				( objectStatus "@baseboard_fab2_lib.baseboard_fab2(sch_1):pu_adr_timer_hold_off_n" )
			)
			( signal "SGPIO_PCH_SATA_CLOCK"
				( objectStatus "@baseboard_fab2_lib.baseboard_fab2(sch_1):sgpio_pch_sata_clock" )
			)
			( signal "SGPIO_PCH_SATA_DOUT0"
				( objectStatus "@baseboard_fab2_lib.baseboard_fab2(sch_1):sgpio_pch_sata_dout0" )
			)
			( signal "SGPIO_PCH_SATA_LOAD"
				( objectStatus "@baseboard_fab2_lib.baseboard_fab2(sch_1):sgpio_pch_sata_load" )
			)
			( signal "SGPIO_PCH_SSATA_CLOCK"
				( objectStatus "@baseboard_fab2_lib.baseboard_fab2(sch_1):sgpio_pch_ssata_clock" )
			)
			( signal "SGPIO_PCH_SSATA_LOAD"
				( objectStatus "@baseboard_fab2_lib.baseboard_fab2(sch_1):sgpio_pch_ssata_load" )
			)
			( signal "SMB_LAN_STBY_LVC3_SCL_R1"
				( objectStatus "@baseboard_fab2_lib.baseboard_fab2(sch_1):smb_lan_stby_lvc3_scl_r1" )
			)
			( signal "SMB_LAN_STBY_LVC3_SCL_R2"
				( objectStatus "@baseboard_fab2_lib.baseboard_fab2(sch_1):smb_lan_stby_lvc3_scl_r2" )
			)
			( signal "SMB_LAN_STBY_LVC3_SDA_R1"
				( objectStatus "@baseboard_fab2_lib.baseboard_fab2(sch_1):smb_lan_stby_lvc3_sda_r1" )
			)
			( signal "SMB_LAN_STBY_LVC3_SDA_R2"
				( objectStatus "@baseboard_fab2_lib.baseboard_fab2(sch_1):smb_lan_stby_lvc3_sda_r2" )
			)
			( signal "SMB_PCH_MEZZ_LOM0_SCL"
				( objectStatus "@baseboard_fab2_lib.baseboard_fab2(sch_1):smb_pch_mezz_lom0_scl" )
			)
			( signal "SMB_PCH_MEZZ_LOM0_SDA"
				( objectStatus "@baseboard_fab2_lib.baseboard_fab2(sch_1):smb_pch_mezz_lom0_sda" )
			)
			( signal "SMB_PCH_MEZZ_LOM1_SDA"
				( objectStatus "@baseboard_fab2_lib.baseboard_fab2(sch_1):smb_pch_mezz_lom1_sda" )
			)
			( signal "SMB_PCH_MEZZ_LOM2_SCL"
				( objectStatus "@baseboard_fab2_lib.baseboard_fab2(sch_1):smb_pch_mezz_lom2_scl" )
			)
			( signal "SMB_PCH_MEZZ_LOM2_SDA"
				( objectStatus "@baseboard_fab2_lib.baseboard_fab2(sch_1):smb_pch_mezz_lom2_sda" )
			)
			( signal "TP_PCH_GPP_J17"
				( objectStatus "@baseboard_fab2_lib.baseboard_fab2(sch_1):tp_pch_gpp_j17" )
			)
			( signal "TP_PCH_GPP_J19"
				( objectStatus "@baseboard_fab2_lib.baseboard_fab2(sch_1):tp_pch_gpp_j19" )
			)
			( signal "TP_PCH_GPP_J21"
				( objectStatus "@baseboard_fab2_lib.baseboard_fab2(sch_1):tp_pch_gpp_j21" )
			)
			( signal "TP_PCH_GPP_J23"
				( objectStatus "@baseboard_fab2_lib.baseboard_fab2(sch_1):tp_pch_gpp_j23" )
			)
			( signal "A_1P8_3P3_RCOMP"
				( objectStatus "@baseboard_fab2_lib.baseboard_fab2(sch_1):a_1p8_3p3_rcomp" )
			)
			( signal "FM_FLASH_DESC_OVERRIDE"
				( objectStatus "@baseboard_fab2_lib.baseboard_fab2(sch_1):fm_flash_desc_override" )
			)
			( signal "FM_INTRUDER_HDR_PCH_N"
				( objectStatus "@baseboard_fab2_lib.baseboard_fab2(sch_1):fm_intruder_hdr_pch_n" )
			)
			( signal "FM_OCP_MEZZB_PRES_N"
				( objectStatus "@baseboard_fab2_lib.baseboard_fab2(sch_1):fm_ocp_mezzb_pres_n" )
			)
			( signal "FM_OCP_MEZZC_PRES_N"
				( objectStatus "@baseboard_fab2_lib.baseboard_fab2(sch_1):fm_ocp_mezzc_pres_n" )
			)
			( signal "FM_PCH_PRSNT_N"
				( objectStatus "@baseboard_fab2_lib.baseboard_fab2(sch_1):fm_pch_prsnt_n" )
			)
			( signal "FM_SINT_PRSNT_N"
				( objectStatus "@baseboard_fab2_lib.baseboard_fab2(sch_1):fm_sint_prsnt_n" )
			)
			( signal "FM_WBG_PRSNT_N"
				( objectStatus "@baseboard_fab2_lib.baseboard_fab2(sch_1):fm_wbg_prsnt_n" )
			)
			( signal "H_CPU0_MEMABC_MEMHOT_PCH_N"
				( objectStatus "@baseboard_fab2_lib.baseboard_fab2(sch_1):h_cpu0_memabc_memhot_pch_n" )
			)
			( signal "H_CPU0_MEMDEF_MEMHOT_PCH_N"
				( objectStatus "@baseboard_fab2_lib.baseboard_fab2(sch_1):h_cpu0_memdef_memhot_pch_n" )
			)
			( signal "H_CPU1_MEMGHJ_MEMHOT_PCH_N"
				( objectStatus "@baseboard_fab2_lib.baseboard_fab2(sch_1):h_cpu1_memghj_memhot_pch_n" )
			)
			( signal "H_CPU1_MEMKLM_MEMHOT_PCH_N"
				( objectStatus "@baseboard_fab2_lib.baseboard_fab2(sch_1):h_cpu1_memklm_memhot_pch_n" )
			)
			( signal "RMII_BMC_PCH_SPRNGVLLE_CRSDV"
				( objectStatus "@baseboard_fab2_lib.baseboard_fab2(sch_1):rmii_bmc_pch_sprngvlle_crsdv" )
			)
			( signal "RMII_BMC_PCH_SPRNGVLLE_CRSDV_R1"
				( objectStatus "@baseboard_fab2_lib.baseboard_fab2(sch_1):rmii_bmc_pch_sprngvlle_crsdv_r1" )
			)
			( signal "RMII_BMC_PCH_SPRNGVLLE_RXER"
				( objectStatus "@baseboard_fab2_lib.baseboard_fab2(sch_1):rmii_bmc_pch_sprngvlle_rxer" )
			)
			( signal "RMII_BMC_PCH_SPRNGVLLE_RXER_R"
				( objectStatus "@baseboard_fab2_lib.baseboard_fab2(sch_1):rmii_bmc_pch_sprngvlle_rxer_r" )
			)
			( signal "RMII_BMC_PCH_SPRNGVLLE_TXD0"
				( objectStatus "@baseboard_fab2_lib.baseboard_fab2(sch_1):rmii_bmc_pch_sprngvlle_txd0" )
			)
			( signal "RMII_BMC_PCH_SPRNGVLLE_TXD1"
				( objectStatus "@baseboard_fab2_lib.baseboard_fab2(sch_1):rmii_bmc_pch_sprngvlle_txd1" )
			)
			( signal "RMII_BMC_PCH_SPRNGVLLE_TXEN"
				( objectStatus "@baseboard_fab2_lib.baseboard_fab2(sch_1):rmii_bmc_pch_sprngvlle_txen" )
			)
			( signal "RMII_PCH_SPRNGVLLE_ARB_IN"
				( objectStatus "@baseboard_fab2_lib.baseboard_fab2(sch_1):rmii_pch_sprngvlle_arb_in" )
			)
			( signal "RMII_PCH_SPRNGVLLE_ARB_OUT"
				( objectStatus "@baseboard_fab2_lib.baseboard_fab2(sch_1):rmii_pch_sprngvlle_arb_out" )
			)
			( signal "RMII_PCH_SPRNGVLLE_ARB_OUT_R"
				( objectStatus "@baseboard_fab2_lib.baseboard_fab2(sch_1):rmii_pch_sprngvlle_arb_out_r" )
			)
			( signal "RMII_SPRNGVLLE_BMC_PCH_RXD0"
				( objectStatus "@baseboard_fab2_lib.baseboard_fab2(sch_1):rmii_sprngvlle_bmc_pch_rxd0" )
			)
			( signal "RMII_SPRNGVLLE_BMC_PCH_RXD0_R1"
				( objectStatus "@baseboard_fab2_lib.baseboard_fab2(sch_1):rmii_sprngvlle_bmc_pch_rxd0_r1" )
			)
			( signal "RMII_SPRNGVLLE_BMC_PCH_RXD1"
				( objectStatus "@baseboard_fab2_lib.baseboard_fab2(sch_1):rmii_sprngvlle_bmc_pch_rxd1" )
			)
			( signal "RMII_SPRNGVLLE_BMC_PCH_RXD1_R1"
				( objectStatus "@baseboard_fab2_lib.baseboard_fab2(sch_1):rmii_sprngvlle_bmc_pch_rxd1_r1" )
			)
			( signal "RST_PCIE_PCH_PERST_N"
				( objectStatus "@baseboard_fab2_lib.baseboard_fab2(sch_1):rst_pcie_pch_perst_n" )
			)
			( signal "RST_RTCRST_N"
				( objectStatus "@baseboard_fab2_lib.baseboard_fab2(sch_1):rst_rtcrst_n" )
			)
			( signal "RST_SRTCRST_N"
				( objectStatus "@baseboard_fab2_lib.baseboard_fab2(sch_1):rst_srtcrst_n" )
			)
			( signal "SPI_PCH_CLK"
				( objectStatus "@baseboard_fab2_lib.baseboard_fab2(sch_1):spi_pch_clk" )
			)
			( signal "SPI_PCH_CS0_N"
				( objectStatus "@baseboard_fab2_lib.baseboard_fab2(sch_1):spi_pch_cs0_n" )
			)
			( signal "SPI_PCH_CS0_R_N"
				( objectStatus "@baseboard_fab2_lib.baseboard_fab2(sch_1):spi_pch_cs0_r_n" )
			)
			( signal "SPI_PCH_IO3"
				( objectStatus "@baseboard_fab2_lib.baseboard_fab2(sch_1):spi_pch_io3" )
			)
			( signal "SPI_PCH_MISO"
				( objectStatus "@baseboard_fab2_lib.baseboard_fab2(sch_1):spi_pch_miso" )
			)
			( signal "SPI_PCH_MOSI_R"
				( objectStatus "@baseboard_fab2_lib.baseboard_fab2(sch_1):spi_pch_mosi_r" )
			)
			( signal "SPI_PCH_TPM_CS_N"
				( objectStatus "@baseboard_fab2_lib.baseboard_fab2(sch_1):spi_pch_tpm_cs_n" )
			)
			( signal "TP_PCH_DISPA_BCLK"
				( objectStatus "@baseboard_fab2_lib.baseboard_fab2(sch_1):tp_pch_dispa_bclk" )
			)
			( signal "TP_PCH_DISPA_SDI"
				( objectStatus "@baseboard_fab2_lib.baseboard_fab2(sch_1):tp_pch_dispa_sdi" )
			)
			( signal "TP_PCH_DISPA_SDO"
				( objectStatus "@baseboard_fab2_lib.baseboard_fab2(sch_1):tp_pch_dispa_sdo" )
			)
			( signal "TP_PCH_GPP_L10"
				( objectStatus "@baseboard_fab2_lib.baseboard_fab2(sch_1):tp_pch_gpp_l10" )
			)
			( signal "TP_PCH_GPP_L11"
				( objectStatus "@baseboard_fab2_lib.baseboard_fab2(sch_1):tp_pch_gpp_l11" )
			)
			( signal "TP_PCH_HDA_BCLK"
				( objectStatus "@baseboard_fab2_lib.baseboard_fab2(sch_1):tp_pch_hda_bclk" )
			)
			( signal "TP_PCH_HDA_SDI_0"
				( objectStatus "@baseboard_fab2_lib.baseboard_fab2(sch_1):tp_pch_hda_sdi_0" )
			)
			( signal "TP_PCH_HDA_SDI_1"
				( objectStatus "@baseboard_fab2_lib.baseboard_fab2(sch_1):tp_pch_hda_sdi_1" )
			)
			( signal "TP_PCH_HDA_SYNC"
				( objectStatus "@baseboard_fab2_lib.baseboard_fab2(sch_1):tp_pch_hda_sync" )
			)
			( signal "TP_PCH_HSA_RST_N"
				( objectStatus "@baseboard_fab2_lib.baseboard_fab2(sch_1):tp_pch_hsa_rst_n" )
			)
			( signal "TP_PCH_RSVD0"
				( objectStatus "@baseboard_fab2_lib.baseboard_fab2(sch_1):tp_pch_rsvd0" )
			)
			( signal "TP_PCH_RSVD1"
				( objectStatus "@baseboard_fab2_lib.baseboard_fab2(sch_1):tp_pch_rsvd1" )
			)
			( signal "TP_PCH_RSVD12"
				( objectStatus "@baseboard_fab2_lib.baseboard_fab2(sch_1):tp_pch_rsvd12" )
			)
			( signal "TP_PCH_RSVD13"
				( objectStatus "@baseboard_fab2_lib.baseboard_fab2(sch_1):tp_pch_rsvd13" )
			)
			( signal "TP_PCH_RSVD14"
				( objectStatus "@baseboard_fab2_lib.baseboard_fab2(sch_1):tp_pch_rsvd14" )
			)
			( signal "TP_PCH_RSVD15"
				( objectStatus "@baseboard_fab2_lib.baseboard_fab2(sch_1):tp_pch_rsvd15" )
			)
			( signal "TP_PCH_RSVD16"
				( objectStatus "@baseboard_fab2_lib.baseboard_fab2(sch_1):tp_pch_rsvd16" )
			)
			( signal "TP_PCH_RSVD17"
				( objectStatus "@baseboard_fab2_lib.baseboard_fab2(sch_1):tp_pch_rsvd17" )
			)
			( signal "TP_PCH_RSVD18"
				( objectStatus "@baseboard_fab2_lib.baseboard_fab2(sch_1):tp_pch_rsvd18" )
			)
			( signal "TP_PCH_RSVD19"
				( objectStatus "@baseboard_fab2_lib.baseboard_fab2(sch_1):tp_pch_rsvd19" )
			)
			( signal "TP_PCH_RSVD2"
				( objectStatus "@baseboard_fab2_lib.baseboard_fab2(sch_1):tp_pch_rsvd2" )
			)
			( signal "TP_PCH_RSVD20"
				( objectStatus "@baseboard_fab2_lib.baseboard_fab2(sch_1):tp_pch_rsvd20" )
			)
			( signal "TP_PCH_RSVD21"
				( objectStatus "@baseboard_fab2_lib.baseboard_fab2(sch_1):tp_pch_rsvd21" )
			)
			( signal "TP_PCH_RSVD22"
				( objectStatus "@baseboard_fab2_lib.baseboard_fab2(sch_1):tp_pch_rsvd22" )
			)
			( signal "TP_PCH_RSVD23"
				( objectStatus "@baseboard_fab2_lib.baseboard_fab2(sch_1):tp_pch_rsvd23" )
			)
			( signal "TP_PCH_RSVD24"
				( objectStatus "@baseboard_fab2_lib.baseboard_fab2(sch_1):tp_pch_rsvd24" )
			)
			( signal "TP_PCH_RSVD25"
				( objectStatus "@baseboard_fab2_lib.baseboard_fab2(sch_1):tp_pch_rsvd25" )
			)
			( signal "TP_PCH_RSVD26"
				( objectStatus "@baseboard_fab2_lib.baseboard_fab2(sch_1):tp_pch_rsvd26" )
			)
			( signal "TP_PCH_RSVD27"
				( objectStatus "@baseboard_fab2_lib.baseboard_fab2(sch_1):tp_pch_rsvd27" )
			)
			( signal "TP_PCH_RSVD3"
				( objectStatus "@baseboard_fab2_lib.baseboard_fab2(sch_1):tp_pch_rsvd3" )
			)
			( signal "TP_PCH_RSVD4"
				( objectStatus "@baseboard_fab2_lib.baseboard_fab2(sch_1):tp_pch_rsvd4" )
			)
			( signal "TP_PCH_RSVD46"
				( objectStatus "@baseboard_fab2_lib.baseboard_fab2(sch_1):tp_pch_rsvd46" )
			)
			( signal "TP_PCH_RSVD5"
				( objectStatus "@baseboard_fab2_lib.baseboard_fab2(sch_1):tp_pch_rsvd5" )
			)
			( signal "TP_PCH_RSVD6"
				( objectStatus "@baseboard_fab2_lib.baseboard_fab2(sch_1):tp_pch_rsvd6" )
			)
			( signal "TP_PCH_RSVD7"
				( objectStatus "@baseboard_fab2_lib.baseboard_fab2(sch_1):tp_pch_rsvd7" )
			)
			( signal "TP_PCH_RSVD8"
				( objectStatus "@baseboard_fab2_lib.baseboard_fab2(sch_1):tp_pch_rsvd8" )
			)
			( signal "TP_PCH_RSVD9"
				( objectStatus "@baseboard_fab2_lib.baseboard_fab2(sch_1):tp_pch_rsvd9" )
			)
			( signal "TP_SPI_PCH_CS1_R1_N"
				( objectStatus "@baseboard_fab2_lib.baseboard_fab2(sch_1):tp_spi_pch_cs1_r1_n" )
			)
			( signal "A_PVCCRTC_EXT_CAP"
				( objectStatus "@baseboard_fab2_lib.baseboard_fab2(sch_1):a_pvccrtc_ext_cap" )
			)
			( signal "P1V05_PCH_STBY_ISCLK_PLL"
				( attribute "VOLTAGE" "1.05V"
					( Units "uVoltage" "V" 1.000000)
					( Status sAliasFlattened )
					( Origin gFrontEnd )
				)
				( objectStatus "@baseboard_fab2_lib.baseboard_fab2(sch_1):p1v05_pch_stby_isclk_pll" )
			)
			( signal "P1V05_PCH_STBY_VCCA_PLL0"
				( attribute "VOLTAGE" "1.05V"
					( Units "uVoltage" "V" 1.000000)
					( Status sAliasFlattened )
					( Origin gFrontEnd )
				)
				( objectStatus "@baseboard_fab2_lib.baseboard_fab2(sch_1):p1v05_pch_stby_vcca_pll0" )
			)
			( signal "P1V05_PCH_STBY_VCCA_PLL1"
				( attribute "VOLTAGE" "1.05V"
					( Units "uVoltage" "V" 1.000000)
					( Status sAliasFlattened )
					( Origin gFrontEnd )
				)
				( objectStatus "@baseboard_fab2_lib.baseboard_fab2(sch_1):p1v05_pch_stby_vcca_pll1" )
			)
			( signal "P1V05_PCH_STBY_VCCA_XTAL"
				( attribute "VOLTAGE" "1.05V"
					( Units "uVoltage" "V" 1.000000)
					( Status sAliasFlattened )
					( Origin gFrontEnd )
				)
				( objectStatus "@baseboard_fab2_lib.baseboard_fab2(sch_1):p1v05_pch_stby_vcca_xtal" )
			)
			( signal "P1V05_PCH_STBY_WM20_PLL"
				( attribute "VOLTAGE" "1.05V"
					( Units "uVoltage" "V" 1.000000)
					( Status sAliasFlattened )
					( Origin gFrontEnd )
				)
				( objectStatus "@baseboard_fab2_lib.baseboard_fab2(sch_1):p1v05_pch_stby_wm20_pll" )
			)
			( signal "P1V05_PCH_STBY_WM26_PLL"
				( attribute "VOLTAGE" "1.05V"
					( Units "uVoltage" "V" 1.000000)
					( Status sAliasFlattened )
					( Origin gFrontEnd )
				)
				( objectStatus "@baseboard_fab2_lib.baseboard_fab2(sch_1):p1v05_pch_stby_wm26_pll" )
			)
			( signal "P1V8_PCH_STBY"
				( attribute "VOLTAGE" "1.8V"
					( Units "uVoltage" "V" 1.000000)
					( Status sAliasFlattened )
					( Origin gFrontEnd )
				)
				( objectStatus "@baseboard_fab2_lib.baseboard_fab2(sch_1):p1v8_pch_stby" )
			)
			( signal "P3V3_RTC_STBY"
				( attribute "VOLTAGE" "3.3V"
					( Units "uVoltage" "V" 1.000000)
					( Status sAliasFlattened )
					( Origin gFrontEnd )
				)
				( objectStatus "@baseboard_fab2_lib.baseboard_fab2(sch_1):p3v3_rtc_stby" )
			)
			( signal "TP_PCH_RSVD28"
				( objectStatus "@baseboard_fab2_lib.baseboard_fab2(sch_1):tp_pch_rsvd28" )
			)
			( signal "TP_PCH_RSVD29"
				( objectStatus "@baseboard_fab2_lib.baseboard_fab2(sch_1):tp_pch_rsvd29" )
			)
			( signal "TP_PCH_RSVD30"
				( objectStatus "@baseboard_fab2_lib.baseboard_fab2(sch_1):tp_pch_rsvd30" )
			)
			( signal "TP_PCH_RSVD31"
				( objectStatus "@baseboard_fab2_lib.baseboard_fab2(sch_1):tp_pch_rsvd31" )
			)
			( signal "TP_PCH_RSVD58"
				( objectStatus "@baseboard_fab2_lib.baseboard_fab2(sch_1):tp_pch_rsvd58" )
			)
			( signal "TP_PCH_RSVD59"
				( objectStatus "@baseboard_fab2_lib.baseboard_fab2(sch_1):tp_pch_rsvd59" )
			)
			( signal "PVNN_PCH_STBY"
				( attribute "VOLTAGE" "1.0V"
					( Units "uVoltage" "V" 1.000000)
					( Status sAliasFlattened )
					( Origin gFrontEnd )
				)
				( objectStatus "@baseboard_fab2_lib.baseboard_fab2(sch_1):pvnn_pch_stby" )
			)
			( signal "VSENSE_PVNN_PCH_STBY_FPK"
				( objectStatus "@baseboard_fab2_lib.baseboard_fab2(sch_1):vsense_pvnn_pch_stby_fpk" )
			)
			( signal "VSENSE_PVNN_PCH_STBY_QAT"
				( objectStatus "@baseboard_fab2_lib.baseboard_fab2(sch_1):vsense_pvnn_pch_stby_qat" )
			)
			( signal "RST_RSMRST_DLY"
				( objectStatus "@baseboard_fab2_lib.baseboard_fab2(sch_1):rst_rsmrst_dly" )
			)
			( signal "FM_THERMTRIP_DLY"
				( objectStatus "@baseboard_fab2_lib.baseboard_fab2(sch_1):fm_thermtrip_dly" )
			)
			( signal "FM_THERMTRIP_DLY_R"
				( objectStatus "@baseboard_fab2_lib.baseboard_fab2(sch_1):fm_thermtrip_dly_r" )
			)
			( signal "RST_PLTRST_BUF_N"
				( objectStatus "@baseboard_fab2_lib.baseboard_fab2(sch_1):rst_pltrst_buf_n" )
			)
			( signal "FM_CPLD_UART_CH_LOCK_N"
				( objectStatus "@baseboard_fab2_lib.baseboard_fab2(sch_1):fm_cpld_uart_ch_lock_n" )
			)
			( signal "FM_DIS_ADR_DLY"
				( objectStatus "@baseboard_fab2_lib.baseboard_fab2(sch_1):fm_dis_adr_dly" )
			)
			( signal "FM_PCH_SATA_RAID_KEY_R"
				( objectStatus "@baseboard_fab2_lib.baseboard_fab2(sch_1):fm_pch_sata_raid_key_r" )
			)
			( signal "PU_KEY_CONN_PIN2_R"
				( objectStatus "@baseboard_fab2_lib.baseboard_fab2(sch_1):pu_key_conn_pin2_r" )
			)
			( signal "TP_JUMPER_BLOCK_1_7"
				( objectStatus "@baseboard_fab2_lib.baseboard_fab2(sch_1):\tp_jumper_block_ 1_7\" )
			)
			( signal "TP_JUMPER_BLOCK_1_1"
				( objectStatus "@baseboard_fab2_lib.baseboard_fab2(sch_1):tp_jumper_block_1_1" )
			)
			( signal "TP_JUMPER_BLOCK_1_2"
				( objectStatus "@baseboard_fab2_lib.baseboard_fab2(sch_1):tp_jumper_block_1_2" )
			)
			( signal "TP_JUMPER_BLOCK_1_8"
				( objectStatus "@baseboard_fab2_lib.baseboard_fab2(sch_1):tp_jumper_block_1_8" )
			)
			( signal "FM_BIOS_TOP_SWAP_SPKR_R"
				( objectStatus "@baseboard_fab2_lib.baseboard_fab2(sch_1):fm_bios_top_swap_spkr_r" )
			)
			( signal "PD_ME_RCVR_N"
				( objectStatus "@baseboard_fab2_lib.baseboard_fab2(sch_1):pd_me_rcvr_n" )
			)
			( signal "PD_PASSWORD_CLEAR"
				( objectStatus "@baseboard_fab2_lib.baseboard_fab2(sch_1):pd_password_clear" )
			)
			( signal "PU_BIOS_RECOVER_BOOT"
				( objectStatus "@baseboard_fab2_lib.baseboard_fab2(sch_1):pu_bios_recover_boot" )
			)
			( signal "PU_BIOS_USB_RECOVERY"
				( objectStatus "@baseboard_fab2_lib.baseboard_fab2(sch_1):pu_bios_usb_recovery" )
			)
			( signal "RST_PLTRST_TOP_SWAP"
				( objectStatus "@baseboard_fab2_lib.baseboard_fab2(sch_1):rst_pltrst_top_swap" )
			)
			( signal "TP_BIOS_RECOVER_BOOT"
				( objectStatus "@baseboard_fab2_lib.baseboard_fab2(sch_1):tp_bios_recover_boot" )
			)
			( signal "TP_BIOS_USB_RECOVERY"
				( objectStatus "@baseboard_fab2_lib.baseboard_fab2(sch_1):tp_bios_usb_recovery" )
			)
			( signal "TP_ME_RCVR_BOOT"
				( objectStatus "@baseboard_fab2_lib.baseboard_fab2(sch_1):tp_me_rcvr_boot" )
			)
			( signal "TP_PASSWORD_CLEAR"
				( objectStatus "@baseboard_fab2_lib.baseboard_fab2(sch_1):tp_password_clear" )
			)
			( signal "PWRGD_P2V5_BMC_STBY_R"
				( objectStatus "@baseboard_fab2_lib.baseboard_fab2(sch_1):pwrgd_p2v5_bmc_stby_r" )
			)
			( signal "PD_IE_DEBUG_MODE"
				( objectStatus "@baseboard_fab2_lib.baseboard_fab2(sch_1):pd_ie_debug_mode" )
			)
			( signal "PD_RST_RTCRST_N"
				( objectStatus "@baseboard_fab2_lib.baseboard_fab2(sch_1):pd_rst_rtcrst_n" )
			)
			( signal "TP_IE_DEBUG_MODE"
				( objectStatus "@baseboard_fab2_lib.baseboard_fab2(sch_1):tp_ie_debug_mode" )
			)
			( signal "PD_SPI_BMC_BT_CS0_N"
				( objectStatus "@baseboard_fab2_lib.baseboard_fab2(sch_1):pd_spi_bmc_bt_cs0_n" )
			)
			( signal "TP_RST_RTCRST_N"
				( objectStatus "@baseboard_fab2_lib.baseboard_fab2(sch_1):tp_rst_rtcrst_n" )
			)
			( signal "SMB_BMC_PMBUS_STBY_LVC3_SCL"
				( objectStatus "@baseboard_fab2_lib.baseboard_fab2(sch_1):smb_bmc_pmbus_stby_lvc3_scl" )
			)
			( signal "SMB_BMC_PMBUS_STBY_LVC3_SDA"
				( objectStatus "@baseboard_fab2_lib.baseboard_fab2(sch_1):smb_bmc_pmbus_stby_lvc3_sda" )
			)
			( signal "SMB_LAN_STBY_LVC3_SCL"
				( objectStatus "@baseboard_fab2_lib.baseboard_fab2(sch_1):smb_lan_stby_lvc3_scl" )
			)
			( signal "SMB_LAN_STBY_LVC3_SDA"
				( objectStatus "@baseboard_fab2_lib.baseboard_fab2(sch_1):smb_lan_stby_lvc3_sda" )
			)
			( signal "SMB_SMLINK0_STBY_LVC3_SCL"
				( objectStatus "@baseboard_fab2_lib.baseboard_fab2(sch_1):smb_smlink0_stby_lvc3_scl" )
			)
			( signal "SMB_SMLINK0_STBY_LVC3_SDA"
				( objectStatus "@baseboard_fab2_lib.baseboard_fab2(sch_1):smb_smlink0_stby_lvc3_sda" )
			)
			( signal "SMB_VR_STBY_LVC3_SCL"
				( objectStatus "@baseboard_fab2_lib.baseboard_fab2(sch_1):smb_vr_stby_lvc3_scl" )
			)
			( signal "SMB_VR_STBY_LVC3_SDA"
				( objectStatus "@baseboard_fab2_lib.baseboard_fab2(sch_1):smb_vr_stby_lvc3_sda" )
			)
			( signal "A_CBOT"
				( objectStatus "@baseboard_fab2_lib.baseboard_fab2(sch_1):a_cbot" )
			)
			( signal "A_CTOP"
				( objectStatus "@baseboard_fab2_lib.baseboard_fab2(sch_1):a_ctop" )
			)
			( signal "FM_PE_SPRV_WAKE_N"
				( objectStatus "@baseboard_fab2_lib.baseboard_fab2(sch_1):fm_pe_sprv_wake_n" )
			)
			( signal "LED_LAN_0_N"
				( objectStatus "@baseboard_fab2_lib.baseboard_fab2(sch_1):led_lan_0_n" )
			)
			( signal "LED_LAN_1_N"
				( objectStatus "@baseboard_fab2_lib.baseboard_fab2(sch_1):led_lan_1_n" )
			)
			( signal "LED_LAN_2_N"
				( objectStatus "@baseboard_fab2_lib.baseboard_fab2(sch_1):led_lan_2_n" )
			)
			( signal "NIC_MDI_SPRV_RJ45_0_DN"
				( objectStatus "@baseboard_fab2_lib.baseboard_fab2(sch_1):nic_mdi_sprv_rj45_0_dn" )
			)
			( signal "NIC_MDI_SPRV_RJ45_0_DP"
				( objectStatus "@baseboard_fab2_lib.baseboard_fab2(sch_1):nic_mdi_sprv_rj45_0_dp" )
			)
			( signal "NIC_MDI_SPRV_RJ45_1_DN"
				( objectStatus "@baseboard_fab2_lib.baseboard_fab2(sch_1):nic_mdi_sprv_rj45_1_dn" )
			)
			( signal "NIC_MDI_SPRV_RJ45_1_DP"
				( objectStatus "@baseboard_fab2_lib.baseboard_fab2(sch_1):nic_mdi_sprv_rj45_1_dp" )
			)
			( signal "NIC_SER_N_MDI_3_DN"
				( objectStatus "@baseboard_fab2_lib.baseboard_fab2(sch_1):nic_ser_n_mdi_3_dn" )
			)
			( signal "NIC_SER_P_MDI_3_DP"
				( objectStatus "@baseboard_fab2_lib.baseboard_fab2(sch_1):nic_ser_p_mdi_3_dp" )
			)
			( signal "NIC_SET_N_MDI_2_DN"
				( objectStatus "@baseboard_fab2_lib.baseboard_fab2(sch_1):nic_set_n_mdi_2_dn" )
			)
			( signal "NIC_SET_P_MDI_2_DP"
				( objectStatus "@baseboard_fab2_lib.baseboard_fab2(sch_1):nic_set_p_mdi_2_dp" )
			)
			( signal "P0V9_LAN"
				( attribute "VOLTAGE" "0.9V"
					( Units "uVoltage" "V" 1.000000)
					( Status sAliasFlattened )
					( Origin gFrontEnd )
				)
				( objectStatus "@baseboard_fab2_lib.baseboard_fab2(sch_1):p0v9_lan" )
			)
			( signal "P0V9_LAN_I210"
				( attribute "VOLTAGE" "0.9"
					( Units "uVoltage" "V" 1.000000)
					( Status sAliasFlattened )
					( Origin gFrontEnd )
				)
				( objectStatus "@baseboard_fab2_lib.baseboard_fab2(sch_1):p0v9_lan_i210" )
			)
			( signal "P1V5_LAN"
				( attribute "VOLTAGE" "1.5V"
					( Units "uVoltage" "V" 1.000000)
					( Status sAliasFlattened )
					( Origin gFrontEnd )
				)
				( objectStatus "@baseboard_fab2_lib.baseboard_fab2(sch_1):p1v5_lan" )
			)
			( signal "P1V5_LAN_I210"
				( attribute "VOLTAGE" "1.5"
					( Units "uVoltage" "V" 1.000000)
					( Status sAliasFlattened )
					( Origin gFrontEnd )
				)
				( objectStatus "@baseboard_fab2_lib.baseboard_fab2(sch_1):p1v5_lan_i210" )
			)
			( signal "P3V3_STBY_P1V5_LAN_I210"
				( attribute "VOLTAGE" "3.3"
					( Units "uVoltage" "V" 1.000000)
					( Status sAliasFlattened )
					( Origin gFrontEnd )
				)
				( objectStatus "@baseboard_fab2_lib.baseboard_fab2(sch_1):p3v3_stby_p1v5_lan_i210" )
			)
			( signal "PD_SPRV_RSET"
				( objectStatus "@baseboard_fab2_lib.baseboard_fab2(sch_1):pd_sprv_rset" )
			)
			( signal "PE_PCH_SPRV_RX_DN"
				( objectStatus "@baseboard_fab2_lib.baseboard_fab2(sch_1):pe_pch_sprv_rx_dn" )
			)
			( signal "PE_PCH_SPRV_RX_DP"
				( objectStatus "@baseboard_fab2_lib.baseboard_fab2(sch_1):pe_pch_sprv_rx_dp" )
			)
			( signal "PE_PCH_SPRV_TX_C_DN"
				( objectStatus "@baseboard_fab2_lib.baseboard_fab2(sch_1):pe_pch_sprv_tx_c_dn" )
			)
			( signal "PE_PCH_SPRV_TX_C_DP"
				( objectStatus "@baseboard_fab2_lib.baseboard_fab2(sch_1):pe_pch_sprv_tx_c_dp" )
			)
			( signal "PU_JTAG_SPRV_TCK"
				( objectStatus "@baseboard_fab2_lib.baseboard_fab2(sch_1):pu_jtag_sprv_tck" )
			)
			( signal "PU_JTAG_SPRV_TDI"
				( objectStatus "@baseboard_fab2_lib.baseboard_fab2(sch_1):pu_jtag_sprv_tdi" )
			)
			( signal "PU_JTAG_SPRV_TDO"
				( objectStatus "@baseboard_fab2_lib.baseboard_fab2(sch_1):pu_jtag_sprv_tdo" )
			)
			( signal "PU_JTAG_SPRV_TMS"
				( objectStatus "@baseboard_fab2_lib.baseboard_fab2(sch_1):pu_jtag_sprv_tms" )
			)
			( signal "PU_SPRV_LAN_PWR_GOOD"
				( objectStatus "@baseboard_fab2_lib.baseboard_fab2(sch_1):pu_sprv_lan_pwr_good" )
			)
			( signal "RMII_BMC_PCH_SPRNGVLLE_CRSDV_R"
				( objectStatus "@baseboard_fab2_lib.baseboard_fab2(sch_1):rmii_bmc_pch_sprngvlle_crsdv_r" )
			)
			( signal "RMII_PCH_SPRNGVLLE_ARB_IN_R"
				( objectStatus "@baseboard_fab2_lib.baseboard_fab2(sch_1):rmii_pch_sprngvlle_arb_in_r" )
			)
			( signal "RMII_SPRNGVLLE_BMC_PCH_RXD0_R"
				( objectStatus "@baseboard_fab2_lib.baseboard_fab2(sch_1):rmii_sprngvlle_bmc_pch_rxd0_r" )
			)
			( signal "RMII_SPRNGVLLE_BMC_PCH_RXD1_R"
				( objectStatus "@baseboard_fab2_lib.baseboard_fab2(sch_1):rmii_sprngvlle_bmc_pch_rxd1_r" )
			)
			( signal "RST_PLTRST_SPRV_R_N"
				( objectStatus "@baseboard_fab2_lib.baseboard_fab2(sch_1):rst_pltrst_sprv_r_n" )
			)
			( signal "SMB_SPRINGVILLE_STBY_LVC3_SCL"
				( objectStatus "@baseboard_fab2_lib.baseboard_fab2(sch_1):smb_springville_stby_lvc3_scl" )
			)
			( signal "SMB_SPRINGVILLE_STBY_LVC3_SDA"
				( objectStatus "@baseboard_fab2_lib.baseboard_fab2(sch_1):smb_springville_stby_lvc3_sda" )
			)
			( signal "SPI_NIC_CS_N"
				( objectStatus "@baseboard_fab2_lib.baseboard_fab2(sch_1):spi_nic_cs_n" )
			)
			( signal "SPI_NIC_CS_R_N"
				( objectStatus "@baseboard_fab2_lib.baseboard_fab2(sch_1):spi_nic_cs_r_n" )
			)
			( signal "SPI_NIC_MISO"
				( objectStatus "@baseboard_fab2_lib.baseboard_fab2(sch_1):spi_nic_miso" )
			)
			( signal "SPI_NIC_MOSI"
				( objectStatus "@baseboard_fab2_lib.baseboard_fab2(sch_1):spi_nic_mosi" )
			)
			( signal "SPI_NIC_MOSI_R"
				( objectStatus "@baseboard_fab2_lib.baseboard_fab2(sch_1):spi_nic_mosi_r" )
			)
			( signal "SPI_NIC_SCLK"
				( objectStatus "@baseboard_fab2_lib.baseboard_fab2(sch_1):spi_nic_sclk" )
			)
			( signal "SPI_NIC_SCLK_R"
				( objectStatus "@baseboard_fab2_lib.baseboard_fab2(sch_1):spi_nic_sclk_r" )
			)
			( signal "TP_SPRV_SDP0"
				( objectStatus "@baseboard_fab2_lib.baseboard_fab2(sch_1):tp_sprv_sdp0" )
			)
			( signal "TP_SPRV_SDP2"
				( objectStatus "@baseboard_fab2_lib.baseboard_fab2(sch_1):tp_sprv_sdp2" )
			)
			( signal "TP_SPRV_SDP3"
				( objectStatus "@baseboard_fab2_lib.baseboard_fab2(sch_1):tp_sprv_sdp3" )
			)
			( signal "XTAL_25MHZ_IN"
				( objectStatus "@baseboard_fab2_lib.baseboard_fab2(sch_1):xtal_25mhz_in" )
			)
			( signal "XTAL_25MHZ_IN_R"
				( objectStatus "@baseboard_fab2_lib.baseboard_fab2(sch_1):xtal_25mhz_in_r" )
			)
			( signal "XTAL_25MHZ_OUT"
				( objectStatus "@baseboard_fab2_lib.baseboard_fab2(sch_1):xtal_25mhz_out" )
			)
			( signal "XTAL_25MHZ_OUT_R"
				( objectStatus "@baseboard_fab2_lib.baseboard_fab2(sch_1):xtal_25mhz_out_r" )
			)
			( signal "PU_NV_HOLD_N"
				( objectStatus "@baseboard_fab2_lib.baseboard_fab2(sch_1):pu_nv_hold_n" )
			)
			( signal "PU_NV_WP_N"
				( objectStatus "@baseboard_fab2_lib.baseboard_fab2(sch_1):pu_nv_wp_n" )
			)
			( signal "SPI_NIC_MISO_R"
				( objectStatus "@baseboard_fab2_lib.baseboard_fab2(sch_1):spi_nic_miso_r" )
			)
			( signal "GND_LAN_TRCT1234_C"
				( attribute "VOLTAGE" "0"
					( Units "uVoltage" "V" 1.000000)
					( Status sAliasFlattened )
					( Origin gFrontEnd )
				)
				( objectStatus "@baseboard_fab2_lib.baseboard_fab2(sch_1):gnd_lan_trct1234_c" )
			)
			( signal "LED_LAN_0_R_N"
				( objectStatus "@baseboard_fab2_lib.baseboard_fab2(sch_1):led_lan_0_r_n" )
			)
			( signal "LED_LAN_1_R_N"
				( objectStatus "@baseboard_fab2_lib.baseboard_fab2(sch_1):led_lan_1_r_n" )
			)
			( signal "LED_LAN_2_R_N"
				( objectStatus "@baseboard_fab2_lib.baseboard_fab2(sch_1):led_lan_2_r_n" )
			)
			( signal "NIC_LED_ACT_ANODE_R"
				( objectStatus "@baseboard_fab2_lib.baseboard_fab2(sch_1):nic_led_act_anode_r" )
			)
			( signal "NIC_MDI_MNG_RX_DN"
				( objectStatus "@baseboard_fab2_lib.baseboard_fab2(sch_1):nic_mdi_mng_rx_dn" )
			)
			( signal "NIC_MDI_MNG_RX_DP"
				( objectStatus "@baseboard_fab2_lib.baseboard_fab2(sch_1):nic_mdi_mng_rx_dp" )
			)
			( signal "NIC_MDI_MNG_TX_DN"
				( objectStatus "@baseboard_fab2_lib.baseboard_fab2(sch_1):nic_mdi_mng_tx_dn" )
			)
			( signal "NIC_MDI_MNG_TX_DP"
				( objectStatus "@baseboard_fab2_lib.baseboard_fab2(sch_1):nic_mdi_mng_tx_dp" )
			)
			( signal "NIC_MDI_SPRV_RJ45_0_R_DN"
				( objectStatus "@baseboard_fab2_lib.baseboard_fab2(sch_1):nic_mdi_sprv_rj45_0_r_dn" )
			)
			( signal "NIC_MDI_SPRV_RJ45_0_R_DP"
				( objectStatus "@baseboard_fab2_lib.baseboard_fab2(sch_1):nic_mdi_sprv_rj45_0_r_dp" )
			)
			( signal "CLK_24M_25M_BMC_CLKIN"
				( objectStatus "@baseboard_fab2_lib.baseboard_fab2(sch_1):clk_24m_25m_bmc_clkin" )
			)
			( signal "NIC_MDI_SPRV_RJ45_1_R_DP"
				( objectStatus "@baseboard_fab2_lib.baseboard_fab2(sch_1):nic_mdi_sprv_rj45_1_r_dp" )
			)
			( signal "TP_RGMII1TXD3_GPIOT5"
				( objectStatus "@baseboard_fab2_lib.baseboard_fab2(sch_1):tp_rgmii1txd3_gpiot5" )
			)
			( signal "RST_BMC_SYSRST_BTN_OUT_N"
				( objectStatus "@baseboard_fab2_lib.baseboard_fab2(sch_1):rst_bmc_sysrst_btn_out_n" )
			)
			( signal "UART_BMC_RXD5"
				( objectStatus "@baseboard_fab2_lib.baseboard_fab2(sch_1):uart_bmc_rxd5" )
			)
			( signal "TP_TPM_SPI_5"
				( objectStatus "@baseboard_fab2_lib.baseboard_fab2(sch_1):tp_tpm_spi_5" )
			)
			( signal "TP_RGMII1TXD2_GPIOT4"
				( objectStatus "@baseboard_fab2_lib.baseboard_fab2(sch_1):tp_rgmii1txd2_gpiot4" )
			)
			( signal "BMC_M_MACT_N"
				( objectStatus "@baseboard_fab2_lib.baseboard_fab2(sch_1):bmc_m_mact_n" )
			)
			( signal "VCC_DACAV3V3"
				( objectStatus "@baseboard_fab2_lib.baseboard_fab2(sch_1):vcc_dacav3v3" )
			)
			( signal "RST_BMC_DDR3_BUF_IN_N"
				( objectStatus "@baseboard_fab2_lib.baseboard_fab2(sch_1):rst_bmc_ddr3_buf_in_n" )
			)
			( signal "NIC_MDI_SPRV_RJ45_2_R_DN"
				( objectStatus "@baseboard_fab2_lib.baseboard_fab2(sch_1):nic_mdi_sprv_rj45_2_r_dn" )
			)
			( signal "NIC_MDI_SPRV_RJ45_2_R_DP"
				( objectStatus "@baseboard_fab2_lib.baseboard_fab2(sch_1):nic_mdi_sprv_rj45_2_r_dp" )
			)
			( signal "NIC_MDI_SPRV_RJ45_3_R_DN"
				( objectStatus "@baseboard_fab2_lib.baseboard_fab2(sch_1):nic_mdi_sprv_rj45_3_r_dn" )
			)
			( signal "FM_ALL_WAKE_N"
				( objectStatus "@baseboard_fab2_lib.baseboard_fab2(sch_1):fm_all_wake_n" )
			)
			( signal "FM_PE_M2_WAKE_N"
				( objectStatus "@baseboard_fab2_lib.baseboard_fab2(sch_1):fm_pe_m2_wake_n" )
			)
			( signal "JTAG_BMC_TDO"
				( objectStatus "@baseboard_fab2_lib.baseboard_fab2(sch_1):jtag_bmc_tdo" )
			)
			( signal "JTAG_BMC_TMS"
				( objectStatus "@baseboard_fab2_lib.baseboard_fab2(sch_1):jtag_bmc_tms" )
			)
			( signal "JTAG_BMC_TRST_N"
				( objectStatus "@baseboard_fab2_lib.baseboard_fab2(sch_1):jtag_bmc_trst_n" )
			)
			( signal "SGPIO_BMC_DOUT"
				( objectStatus "@baseboard_fab2_lib.baseboard_fab2(sch_1):sgpio_bmc_dout" )
			)
			( signal "SMB_BMC_PMBUS_STBY_LVC3_SDA_R"
				( objectStatus "@baseboard_fab2_lib.baseboard_fab2(sch_1):smb_bmc_pmbus_stby_lvc3_sda_r" )
			)
			( signal "SMB_LAN_STBY_LVC3_SCL_R"
				( objectStatus "@baseboard_fab2_lib.baseboard_fab2(sch_1):smb_lan_stby_lvc3_scl_r" )
			)
			( signal "SMB_OCP_FRU_STBY_LVC3_SDA_R"
				( objectStatus "@baseboard_fab2_lib.baseboard_fab2(sch_1):smb_ocp_fru_stby_lvc3_sda_r" )
			)
			( signal "SMB_OCP_LAN_STBY_LVC3_SDA_R"
				( objectStatus "@baseboard_fab2_lib.baseboard_fab2(sch_1):smb_ocp_lan_stby_lvc3_sda_r" )
			)
			( signal "SMB_SENSOR_BMC_STBY_LVC3_SCL"
				( objectStatus "@baseboard_fab2_lib.baseboard_fab2(sch_1):smb_sensor_bmc_stby_lvc3_scl" )
			)
			( signal "SMB_SENSOR_BMC_STBY_LVC3_SDA"
				( objectStatus "@baseboard_fab2_lib.baseboard_fab2(sch_1):smb_sensor_bmc_stby_lvc3_sda" )
			)
			( signal "FM_HEARTBEAT_LED_K"
				( objectStatus "@baseboard_fab2_lib.baseboard_fab2(sch_1):fm_heartbeat_led_k" )
			)
			( signal "BMC_M_DQS1_DN"
				( objectStatus "@baseboard_fab2_lib.baseboard_fab2(sch_1):bmc_m_dqs1_dn" )
			)
			( signal "SMB_SLOTX24_STBY_LVC3_SCL_R"
				( objectStatus "@baseboard_fab2_lib.baseboard_fab2(sch_1):smb_slotx24_stby_lvc3_scl_r" )
			)
			( signal "SMB_SLOTX24_STBY_LVC3_SDA_R"
				( objectStatus "@baseboard_fab2_lib.baseboard_fab2(sch_1):smb_slotx24_stby_lvc3_sda_r" )
			)
			( signal "SMB_SMLINK0_STBY_LVC3_SCL_R"
				( objectStatus "@baseboard_fab2_lib.baseboard_fab2(sch_1):smb_smlink0_stby_lvc3_scl_r" )
			)
			( signal "P2V5_AUX_BMC"
				( objectStatus "@baseboard_fab2_lib.baseboard_fab2(sch_1):p2v5_aux_bmc" )
			)
			( signal "SMB_SMLINK0_STBY_LVC3_SDA_R"
				( objectStatus "@baseboard_fab2_lib.baseboard_fab2(sch_1):smb_smlink0_stby_lvc3_sda_r" )
			)
			( signal "SMB_VR_STBY_LVC3_SCL_R"
				( objectStatus "@baseboard_fab2_lib.baseboard_fab2(sch_1):smb_vr_stby_lvc3_scl_r" )
			)
			( signal "SMB_VR_STBY_LVC3_SDA_R"
				( objectStatus "@baseboard_fab2_lib.baseboard_fab2(sch_1):smb_vr_stby_lvc3_sda_r" )
			)
			( signal "SPI_BMC_CLK"
				( objectStatus "@baseboard_fab2_lib.baseboard_fab2(sch_1):spi_bmc_clk" )
			)
			( signal "SPI_BMC_CS0_N"
				( objectStatus "@baseboard_fab2_lib.baseboard_fab2(sch_1):spi_bmc_cs0_n" )
			)
			( signal "SPI_BMC_DI"
				( objectStatus "@baseboard_fab2_lib.baseboard_fab2(sch_1):spi_bmc_di" )
			)
			( signal "SPI_BMC_DO"
				( objectStatus "@baseboard_fab2_lib.baseboard_fab2(sch_1):spi_bmc_do" )
			)
			( signal "FM_BMC_ONCTL_N"
				( objectStatus "@baseboard_fab2_lib.baseboard_fab2(sch_1):fm_bmc_onctl_n" )
			)
			( signal "FM_BMC_PWRBTN_OUT_N"
				( objectStatus "@baseboard_fab2_lib.baseboard_fab2(sch_1):fm_bmc_pwrbtn_out_n" )
			)
			( signal "H_CPU0_MEMABC_MEMHOT_LVT3_BMC_N"
				( objectStatus "@baseboard_fab2_lib.baseboard_fab2(sch_1):h_cpu0_memabc_memhot_lvt3_bmc_n" )
			)
			( signal "H_CPU0_MEMDEF_MEMHOT_LVT3_BMC_N"
				( objectStatus "@baseboard_fab2_lib.baseboard_fab2(sch_1):h_cpu0_memdef_memhot_lvt3_bmc_n" )
			)
			( signal "FM_CPU1_FIVR_FAULT_LVT3_R_N"
				( objectStatus "@baseboard_fab2_lib.baseboard_fab2(sch_1):fm_cpu1_fivr_fault_lvt3_r_n" )
			)
			( signal "H_CPU1_MEMGHJ_MEMHOT_LVT3_BMC_N"
				( objectStatus "@baseboard_fab2_lib.baseboard_fab2(sch_1):h_cpu1_memghj_memhot_lvt3_bmc_n" )
			)
			( signal "FM_CPU0_FIVR_FAULT_LVT3_R_N"
				( objectStatus "@baseboard_fab2_lib.baseboard_fab2(sch_1):fm_cpu0_fivr_fault_lvt3_r_n" )
			)
			( signal "H_CPU1_MEMKLM_MEMHOT_LVT3_BMC_N"
				( objectStatus "@baseboard_fab2_lib.baseboard_fab2(sch_1):h_cpu1_memklm_memhot_lvt3_bmc_n" )
			)
			( signal "P2E_SSB_BMC_RX_DN"
				( objectStatus "@baseboard_fab2_lib.baseboard_fab2(sch_1):p2e_ssb_bmc_rx_dn" )
			)
			( signal "CLK_24M_BMC_CLKIN_R"
				( objectStatus "@baseboard_fab2_lib.baseboard_fab2(sch_1):clk_24m_bmc_clkin_r" )
			)
			( signal "UART_BMC_TXD5"
				( objectStatus "@baseboard_fab2_lib.baseboard_fab2(sch_1):uart_bmc_txd5" )
			)
			( signal "TP_TPM_SPI_4"
				( objectStatus "@baseboard_fab2_lib.baseboard_fab2(sch_1):tp_tpm_spi_4" )
			)
			( signal "TP_TPM_SPI_1"
				( objectStatus "@baseboard_fab2_lib.baseboard_fab2(sch_1):tp_tpm_spi_1" )
			)
			( signal "TP_TPM_SPI_0"
				( objectStatus "@baseboard_fab2_lib.baseboard_fab2(sch_1):tp_tpm_spi_0" )
			)
			( signal "PU_TPM_SPI_FLASH_RESET_2_N"
				( objectStatus "@baseboard_fab2_lib.baseboard_fab2(sch_1):pu_tpm_spi_flash_reset_2_n" )
			)
			( signal "P3V3_USB2A_ALG"
				( objectStatus "@baseboard_fab2_lib.baseboard_fab2(sch_1):p3v3_usb2a_alg" )
			)
			( signal "SPI_BMC_BT_DO_R"
				( objectStatus "@baseboard_fab2_lib.baseboard_fab2(sch_1):spi_bmc_bt_do_r" )
			)
			( signal "BMC_ZQ"
				( objectStatus "@baseboard_fab2_lib.baseboard_fab2(sch_1):bmc_zq" )
			)
			( signal "VCC_ADCAV3V3"
				( attribute "VOLTAGE" "+3.3V"
					( Units "uVoltage" "V" 1.000000)
					( Status sAliasFlattened )
					( Origin gFrontEnd )
				)
				( objectStatus "@baseboard_fab2_lib.baseboard_fab2(sch_1):vcc_adcav3v3" )
			)
			( signal "BMC_M_PAR"
				( objectStatus "@baseboard_fab2_lib.baseboard_fab2(sch_1):bmc_m_par" )
			)
			( signal "H_CPU0_ABC_MEMHOT_LVT3_R_N"
				( objectStatus "@baseboard_fab2_lib.baseboard_fab2(sch_1):h_cpu0_abc_memhot_lvt3_r_n" )
			)
			( signal "H_CPU0_DEF_MEMHOT_LVT3_R_N"
				( objectStatus "@baseboard_fab2_lib.baseboard_fab2(sch_1):h_cpu0_def_memhot_lvt3_r_n" )
			)
			( signal "H_CPU0_MEMABC_MEMHOT_G_PCH_N"
				( objectStatus "@baseboard_fab2_lib.baseboard_fab2(sch_1):h_cpu0_memabc_memhot_g_pch_n" )
			)
			( signal "H_CPU0_MEMABC_MEMHOT_G_R_N"
				( objectStatus "@baseboard_fab2_lib.baseboard_fab2(sch_1):h_cpu0_memabc_memhot_g_r_n" )
			)
			( signal "H_CPU0_MEMABC_MEMHOT_LVT3_K_N"
				( objectStatus "@baseboard_fab2_lib.baseboard_fab2(sch_1):h_cpu0_memabc_memhot_lvt3_k_n" )
			)
			( signal "H_CPU0_MEMABC_MEMHOT_LVT3_N"
				( objectStatus "@baseboard_fab2_lib.baseboard_fab2(sch_1):h_cpu0_memabc_memhot_lvt3_n" )
			)
			( signal "H_CPU0_MEMDEF_MEMHOT_G_PCH_N"
				( objectStatus "@baseboard_fab2_lib.baseboard_fab2(sch_1):h_cpu0_memdef_memhot_g_pch_n" )
			)
			( signal "H_CPU0_MEMDEF_MEMHOT_G_R_N"
				( objectStatus "@baseboard_fab2_lib.baseboard_fab2(sch_1):h_cpu0_memdef_memhot_g_r_n" )
			)
			( signal "H_CPU0_MEMDEF_MEMHOT_LVT3_K_N"
				( objectStatus "@baseboard_fab2_lib.baseboard_fab2(sch_1):h_cpu0_memdef_memhot_lvt3_k_n" )
			)
			( signal "H_CPU0_MEMDEF_MEMHOT_LVT3_N"
				( objectStatus "@baseboard_fab2_lib.baseboard_fab2(sch_1):h_cpu0_memdef_memhot_lvt3_n" )
			)
			( signal "H_CPU1_GHJ_MEMHOT_LVT3_R_N"
				( objectStatus "@baseboard_fab2_lib.baseboard_fab2(sch_1):h_cpu1_ghj_memhot_lvt3_r_n" )
			)
			( signal "H_CPU1_KLM_MEMHOT_LVT3_R_N"
				( objectStatus "@baseboard_fab2_lib.baseboard_fab2(sch_1):h_cpu1_klm_memhot_lvt3_r_n" )
			)
			( signal "H_CPU1_MEMGHJ_MEMHOT_G_PCH_N"
				( objectStatus "@baseboard_fab2_lib.baseboard_fab2(sch_1):h_cpu1_memghj_memhot_g_pch_n" )
			)
			( signal "H_CPU1_MEMGHJ_MEMHOT_G_R_N"
				( objectStatus "@baseboard_fab2_lib.baseboard_fab2(sch_1):h_cpu1_memghj_memhot_g_r_n" )
			)
			( signal "H_CPU1_MEMGHJ_MEMHOT_LVT3_K_N"
				( objectStatus "@baseboard_fab2_lib.baseboard_fab2(sch_1):h_cpu1_memghj_memhot_lvt3_k_n" )
			)
			( signal "H_CPU1_MEMGHJ_MEMHOT_LVT3_N"
				( objectStatus "@baseboard_fab2_lib.baseboard_fab2(sch_1):h_cpu1_memghj_memhot_lvt3_n" )
			)
			( signal "H_CPU1_MEMKLM_MEMHOT_G_PCH_N"
				( objectStatus "@baseboard_fab2_lib.baseboard_fab2(sch_1):h_cpu1_memklm_memhot_g_pch_n" )
			)
			( signal "H_CPU1_MEMKLM_MEMHOT_G_R_N"
				( objectStatus "@baseboard_fab2_lib.baseboard_fab2(sch_1):h_cpu1_memklm_memhot_g_r_n" )
			)
			( signal "H_CPU1_MEMKLM_MEMHOT_LVT3_K_N"
				( objectStatus "@baseboard_fab2_lib.baseboard_fab2(sch_1):h_cpu1_memklm_memhot_lvt3_k_n" )
			)
			( signal "H_CPU1_MEMKLM_MEMHOT_LVT3_N"
				( objectStatus "@baseboard_fab2_lib.baseboard_fab2(sch_1):h_cpu1_memklm_memhot_lvt3_n" )
			)
			( signal "P0V7_GTL2014_2"
				( attribute "VOLTAGE" "+0.7"
					( Units "uVoltage" "V" 1.000000)
					( Status sAliasFlattened )
					( Origin gFrontEnd )
				)
				( objectStatus "@baseboard_fab2_lib.baseboard_fab2(sch_1):p0v7_gtl2014_2" )
			)
			( signal "PD_DIR_2"
				( objectStatus "@baseboard_fab2_lib.baseboard_fab2(sch_1):pd_dir_2" )
			)
			( signal "PU_BIOS_SPI_HOLD0_N"
				( objectStatus "@baseboard_fab2_lib.baseboard_fab2(sch_1):pu_bios_spi_hold0_n" )
			)
			( signal "PU_BIOS_SPI_HOLD1_N"
				( objectStatus "@baseboard_fab2_lib.baseboard_fab2(sch_1):pu_bios_spi_hold1_n" )
			)
			( signal "PU_BIOS_SPI_WP0_N"
				( objectStatus "@baseboard_fab2_lib.baseboard_fab2(sch_1):pu_bios_spi_wp0_n" )
			)
			( signal "PU_BIOS_SPI_WP1_N"
				( objectStatus "@baseboard_fab2_lib.baseboard_fab2(sch_1):pu_bios_spi_wp1_n" )
			)
			( signal "PU_SPI0_RST"
				( objectStatus "@baseboard_fab2_lib.baseboard_fab2(sch_1):pu_spi0_rst" )
			)
			( signal "PU_SPI1_RST"
				( objectStatus "@baseboard_fab2_lib.baseboard_fab2(sch_1):pu_spi1_rst" )
			)
			( signal "SPI_BIOS_SOCKET_IO2"
				( objectStatus "@baseboard_fab2_lib.baseboard_fab2(sch_1):spi_bios_socket_io2" )
			)
			( signal "SPI_BIOS_SOCKET_IO3"
				( objectStatus "@baseboard_fab2_lib.baseboard_fab2(sch_1):spi_bios_socket_io3" )
			)
			( signal "SPI_CLK_R0"
				( objectStatus "@baseboard_fab2_lib.baseboard_fab2(sch_1):spi_clk_r0" )
			)
			( signal "SPI_CLK_R1"
				( objectStatus "@baseboard_fab2_lib.baseboard_fab2(sch_1):spi_clk_r1" )
			)
			( signal "SPI_CS0_PRIMARY_R_N"
				( objectStatus "@baseboard_fab2_lib.baseboard_fab2(sch_1):spi_cs0_primary_r_n" )
			)
			( signal "SPI_CS0_SECONDARY_R_N"
				( objectStatus "@baseboard_fab2_lib.baseboard_fab2(sch_1):spi_cs0_secondary_r_n" )
			)
			( signal "SPI_MISO_R0"
				( objectStatus "@baseboard_fab2_lib.baseboard_fab2(sch_1):spi_miso_r0" )
			)
			( signal "SPI_MISO_R1"
				( objectStatus "@baseboard_fab2_lib.baseboard_fab2(sch_1):spi_miso_r1" )
			)
			( signal "SPI_SWITCH_CLK"
				( objectStatus "@baseboard_fab2_lib.baseboard_fab2(sch_1):spi_switch_clk" )
			)
			( signal "SPI_SWITCH_MISO"
				( objectStatus "@baseboard_fab2_lib.baseboard_fab2(sch_1):spi_switch_miso" )
			)
			( signal "SPI_SWITCH_MOSI"
				( objectStatus "@baseboard_fab2_lib.baseboard_fab2(sch_1):spi_switch_mosi" )
			)
			( signal "SPI_SWITCH_MOSI_R0"
				( objectStatus "@baseboard_fab2_lib.baseboard_fab2(sch_1):spi_switch_mosi_r0" )
			)
			( signal "SPI_SWITCH_MOSI_R1"
				( objectStatus "@baseboard_fab2_lib.baseboard_fab2(sch_1):spi_switch_mosi_r1" )
			)
			( signal "TP_SPI_0_0"
				( objectStatus "@baseboard_fab2_lib.baseboard_fab2(sch_1):tp_spi_0_0" )
			)
			( signal "TP_SPI_0_1"
				( objectStatus "@baseboard_fab2_lib.baseboard_fab2(sch_1):tp_spi_0_1" )
			)
			( signal "TP_SPI_0_2"
				( objectStatus "@baseboard_fab2_lib.baseboard_fab2(sch_1):tp_spi_0_2" )
			)
			( signal "TP_SPI_0_3"
				( objectStatus "@baseboard_fab2_lib.baseboard_fab2(sch_1):tp_spi_0_3" )
			)
			( signal "TP_SPI_0_4"
				( objectStatus "@baseboard_fab2_lib.baseboard_fab2(sch_1):tp_spi_0_4" )
			)
			( signal "TP_SPI_0_5"
				( objectStatus "@baseboard_fab2_lib.baseboard_fab2(sch_1):tp_spi_0_5" )
			)
			( signal "TP_SPI_0_6"
				( objectStatus "@baseboard_fab2_lib.baseboard_fab2(sch_1):tp_spi_0_6" )
			)
			( signal "TP_SPI_1_0"
				( objectStatus "@baseboard_fab2_lib.baseboard_fab2(sch_1):tp_spi_1_0" )
			)
			( signal "TP_SPI_1_1"
				( objectStatus "@baseboard_fab2_lib.baseboard_fab2(sch_1):tp_spi_1_1" )
			)
			( signal "TP_SPI_1_2"
				( objectStatus "@baseboard_fab2_lib.baseboard_fab2(sch_1):tp_spi_1_2" )
			)
			( signal "TP_SPI_1_3"
				( objectStatus "@baseboard_fab2_lib.baseboard_fab2(sch_1):tp_spi_1_3" )
			)
			( signal "TP_SPI_1_4"
				( objectStatus "@baseboard_fab2_lib.baseboard_fab2(sch_1):tp_spi_1_4" )
			)
			( signal "TP_SPI_1_5"
				( objectStatus "@baseboard_fab2_lib.baseboard_fab2(sch_1):tp_spi_1_5" )
			)
			( signal "TP_SPI_1_6"
				( objectStatus "@baseboard_fab2_lib.baseboard_fab2(sch_1):tp_spi_1_6" )
			)
			( signal "FM_DUAL_BIOS_SEL_N"
				( objectStatus "@baseboard_fab2_lib.baseboard_fab2(sch_1):fm_dual_bios_sel_n" )
			)
			( signal "SPI_CS0_PRIMARY_N"
				( objectStatus "@baseboard_fab2_lib.baseboard_fab2(sch_1):spi_cs0_primary_n" )
			)
			( signal "SPI_CS0_SECONDARY_N"
				( objectStatus "@baseboard_fab2_lib.baseboard_fab2(sch_1):spi_cs0_secondary_n" )
			)
			( signal "SPI_PCH_IO2_R1"
				( objectStatus "@baseboard_fab2_lib.baseboard_fab2(sch_1):spi_pch_io2_r1" )
			)
			( signal "SPI_PCH_IO3_R1"
				( objectStatus "@baseboard_fab2_lib.baseboard_fab2(sch_1):spi_pch_io3_r1" )
			)
			( signal "SPI_PCH_MISO_R"
				( objectStatus "@baseboard_fab2_lib.baseboard_fab2(sch_1):spi_pch_miso_r" )
			)
			( signal "SPI_SWITCH_CS0_N"
				( objectStatus "@baseboard_fab2_lib.baseboard_fab2(sch_1):spi_switch_cs0_n" )
			)
			( signal "TP_SPI_SWITCH1_10"
				( objectStatus "@baseboard_fab2_lib.baseboard_fab2(sch_1):tp_spi_switch1_10" )
			)
			( signal "TP_SPI_SWITCH1_11"
				( objectStatus "@baseboard_fab2_lib.baseboard_fab2(sch_1):tp_spi_switch1_11" )
			)
			( signal "TP_SPI_SWITCH1_12"
				( objectStatus "@baseboard_fab2_lib.baseboard_fab2(sch_1):tp_spi_switch1_12" )
			)
			( signal "TP_SPI_SWITCH1_13"
				( objectStatus "@baseboard_fab2_lib.baseboard_fab2(sch_1):tp_spi_switch1_13" )
			)
			( signal "TP_SPI_SWITCH1_14"
				( objectStatus "@baseboard_fab2_lib.baseboard_fab2(sch_1):tp_spi_switch1_14" )
			)
			( signal "TP_SPI_SWITCH1_3"
				( objectStatus "@baseboard_fab2_lib.baseboard_fab2(sch_1):tp_spi_switch1_3" )
			)
			( signal "TP_SPI_SWITCH1_6"
				( objectStatus "@baseboard_fab2_lib.baseboard_fab2(sch_1):tp_spi_switch1_6" )
			)
			( signal "TP_SPI_SWITCH1_9"
				( objectStatus "@baseboard_fab2_lib.baseboard_fab2(sch_1):tp_spi_switch1_9" )
			)
			( signal "FM_CPLD_DBG_PWR_EN"
				( objectStatus "@baseboard_fab2_lib.baseboard_fab2(sch_1):fm_cpld_dbg_pwr_en" )
			)
			( signal "FM_CPLD_DBG_PWR_EN_N"
				( objectStatus "@baseboard_fab2_lib.baseboard_fab2(sch_1):fm_cpld_dbg_pwr_en_n" )
			)
			( signal "FM_CPLD_DBG_PWR_EN_R_N"
				( objectStatus "@baseboard_fab2_lib.baseboard_fab2(sch_1):fm_cpld_dbg_pwr_en_r_n" )
			)
			( signal "FM_UART_SWITCH_N"
				( objectStatus "@baseboard_fab2_lib.baseboard_fab2(sch_1):fm_uart_switch_n" )
			)
			( signal "LED_POSTCODE_0_R"
				( objectStatus "@baseboard_fab2_lib.baseboard_fab2(sch_1):led_postcode_0_r" )
			)
			( signal "LED_POSTCODE_1_R"
				( objectStatus "@baseboard_fab2_lib.baseboard_fab2(sch_1):led_postcode_1_r" )
			)
			( signal "LED_POSTCODE_2_R"
				( objectStatus "@baseboard_fab2_lib.baseboard_fab2(sch_1):led_postcode_2_r" )
			)
			( signal "LED_POSTCODE_3_R"
				( objectStatus "@baseboard_fab2_lib.baseboard_fab2(sch_1):led_postcode_3_r" )
			)
			( signal "LED_POSTCODE_4_R"
				( objectStatus "@baseboard_fab2_lib.baseboard_fab2(sch_1):led_postcode_4_r" )
			)
			( signal "LED_POSTCODE_5_R"
				( objectStatus "@baseboard_fab2_lib.baseboard_fab2(sch_1):led_postcode_5_r" )
			)
			( signal "LED_POSTCODE_6_R"
				( objectStatus "@baseboard_fab2_lib.baseboard_fab2(sch_1):led_postcode_6_r" )
			)
			( signal "LED_POSTCODE_7_R"
				( objectStatus "@baseboard_fab2_lib.baseboard_fab2(sch_1):led_postcode_7_r" )
			)
			( signal "P12V_STBY"
				( attribute "VOLTAGE" "12.0V"
					( Units "uVoltage" "V" 1.000000)
					( Status sAliasFlattened )
					( Origin gFrontEnd )
				)
				( objectStatus "@baseboard_fab2_lib.baseboard_fab2(sch_1):p12v_stby" )
			)
			( signal "SPA_MID_DBG1_RX"
				( objectStatus "@baseboard_fab2_lib.baseboard_fab2(sch_1):spa_mid_dbg1_rx" )
			)
			( signal "P5V_STBY"
				( attribute "VOLTAGE" "5.0V"
					( Units "uVoltage" "V" 1.000000)
					( Status sAliasFlattened )
					( Status sAliasConflict )
					( Origin gFrontEnd )
				)
				( objectStatus "@baseboard_fab2_lib.baseboard_fab2(sch_1):p5v_stby" )
			)
			( signal "PCA9554_A2"
				( objectStatus "@baseboard_fab2_lib.baseboard_fab2(sch_1):pca9554_a2" )
			)
			( signal "PUMP_PWM_OUT_BUF"
				( objectStatus "@baseboard_fab2_lib.baseboard_fab2(sch_1):pump_pwm_out_buf" )
			)
			( signal "P5V_STBY_DBG"
				( attribute "VOLTAGE" "5"
					( Units "uVoltage" "V" 1.000000)
					( Status sAliasFlattened )
					( Origin gFrontEnd )
				)
				( objectStatus "@baseboard_fab2_lib.baseboard_fab2(sch_1):p5v_stby_dbg" )
			)
			( signal "P5V_STBY_DGB_FS"
				( attribute "VOLTAGE" "5"
					( Units "uVoltage" "V" 1.000000)
					( Status sAliasFlattened )
					( Origin gFrontEnd )
				)
				( objectStatus "@baseboard_fab2_lib.baseboard_fab2(sch_1):p5v_stby_dgb_fs" )
			)
			( signal "SPA_5V_SIN_SW"
				( objectStatus "@baseboard_fab2_lib.baseboard_fab2(sch_1):spa_5v_sin_sw" )
			)
			( signal "SPA_MID_DBG_RX"
				( objectStatus "@baseboard_fab2_lib.baseboard_fab2(sch_1):spa_mid_dbg_rx" )
			)
			( signal "SPA_MID_DBG_TX"
				( objectStatus "@baseboard_fab2_lib.baseboard_fab2(sch_1):spa_mid_dbg_tx" )
			)
			( signal "SPA_SIN_SW_R"
				( objectStatus "@baseboard_fab2_lib.baseboard_fab2(sch_1):spa_sin_sw_r" )
			)
			( signal "FM_PCH_PWRBTN_R_N"
				( objectStatus "@baseboard_fab2_lib.baseboard_fab2(sch_1):fm_pch_pwrbtn_r_n" )
			)
			( signal "RST_BMC_SYSRST_BTN_OUT_B_R_N"
				( objectStatus "@baseboard_fab2_lib.baseboard_fab2(sch_1):rst_bmc_sysrst_btn_out_b_r_n" )
			)
			( signal "FP_NMI_BTN"
				( objectStatus "@baseboard_fab2_lib.baseboard_fab2(sch_1):fp_nmi_btn" )
			)
			( signal "FP_NMI_BTN_OUT_N"
				( objectStatus "@baseboard_fab2_lib.baseboard_fab2(sch_1):fp_nmi_btn_out_n" )
			)
			( signal "FP_NMI_BTN_OUT_R_N"
				( objectStatus "@baseboard_fab2_lib.baseboard_fab2(sch_1):fp_nmi_btn_out_r_n" )
			)
			( signal "FP_NMI_BTN_R_N"
				( objectStatus "@baseboard_fab2_lib.baseboard_fab2(sch_1):fp_nmi_btn_r_n" )
			)
			( signal "H_CPU0_FAST_WAKE"
				( objectStatus "@baseboard_fab2_lib.baseboard_fab2(sch_1):h_cpu0_fast_wake" )
			)
			( signal "H_CPU0_FAST_WAKE_B_N"
				( objectStatus "@baseboard_fab2_lib.baseboard_fab2(sch_1):h_cpu0_fast_wake_b_n" )
			)
			( signal "RST_BMC_SRST_R2_N"
				( objectStatus "@baseboard_fab2_lib.baseboard_fab2(sch_1):rst_bmc_srst_r2_n" )
			)
			( signal "FM_UARTSW_LSB_R_N"
				( objectStatus "@baseboard_fab2_lib.baseboard_fab2(sch_1):fm_uartsw_lsb_r_n" )
			)
			( signal "FM_UARTSW_MSB_R_N"
				( objectStatus "@baseboard_fab2_lib.baseboard_fab2(sch_1):fm_uartsw_msb_r_n" )
			)
			( signal "SP2_BMC_CM_UART_RX_R"
				( objectStatus "@baseboard_fab2_lib.baseboard_fab2(sch_1):sp2_bmc_cm_uart_rx_r" )
			)
			( signal "SP2_BMC_CM_UART_RX_R1"
				( objectStatus "@baseboard_fab2_lib.baseboard_fab2(sch_1):sp2_bmc_cm_uart_rx_r1" )
			)
			( signal "SP2_BMC_CM_UART_TX_R"
				( objectStatus "@baseboard_fab2_lib.baseboard_fab2(sch_1):sp2_bmc_cm_uart_tx_r" )
			)
			( signal "SP2_BMC_CM_UART_TX_R1"
				( objectStatus "@baseboard_fab2_lib.baseboard_fab2(sch_1):sp2_bmc_cm_uart_tx_r1" )
			)
			( signal "UART_MUX_IN_R"
				( objectStatus "@baseboard_fab2_lib.baseboard_fab2(sch_1):uart_mux_in_r" )
			)
			( signal "UART_MUX_OUT_R"
				( objectStatus "@baseboard_fab2_lib.baseboard_fab2(sch_1):uart_mux_out_r" )
			)
			( signal "SMB_OCP_LAN_STBY_LVC3_SCL"
				( objectStatus "@baseboard_fab2_lib.baseboard_fab2(sch_1):smb_ocp_lan_stby_lvc3_scl" )
			)
			( signal "SMB_OCP_LAN_STBY_LVC3_SDA"
				( objectStatus "@baseboard_fab2_lib.baseboard_fab2(sch_1):smb_ocp_lan_stby_lvc3_sda" )
			)
			( signal "FAN_PWM_OUT_SYS0_BUF"
				( objectStatus "@baseboard_fab2_lib.baseboard_fab2(sch_1):fan_pwm_out_sys0_buf" )
			)
			( signal "FAN_PWM_OUT_SYS0_R"
				( objectStatus "@baseboard_fab2_lib.baseboard_fab2(sch_1):fan_pwm_out_sys0_r" )
			)
			( signal "FAN_PWM_OUT_SYS1_BUF"
				( objectStatus "@baseboard_fab2_lib.baseboard_fab2(sch_1):fan_pwm_out_sys1_buf" )
			)
			( signal "FAN_PWM_OUT_SYS1_R"
				( objectStatus "@baseboard_fab2_lib.baseboard_fab2(sch_1):fan_pwm_out_sys1_r" )
			)
			( signal "FAN_TACH0_CPU0_D1"
				( objectStatus "@baseboard_fab2_lib.baseboard_fab2(sch_1):fan_tach0_cpu0_d1" )
			)
			( signal "FAN_TACH0_CPU0_D2"
				( objectStatus "@baseboard_fab2_lib.baseboard_fab2(sch_1):fan_tach0_cpu0_d2" )
			)
			( signal "FAN_TACH2_CPU1_D1"
				( objectStatus "@baseboard_fab2_lib.baseboard_fab2(sch_1):fan_tach2_cpu1_d1" )
			)
			( signal "FAN_TACH2_CPU1_D2"
				( objectStatus "@baseboard_fab2_lib.baseboard_fab2(sch_1):fan_tach2_cpu1_d2" )
			)
			( signal "FM_CTNR_PS_ON"
				( objectStatus "@baseboard_fab2_lib.baseboard_fab2(sch_1):fm_ctnr_ps_on" )
			)
			( signal "FM_DISABLE_FAN_N"
				( objectStatus "@baseboard_fab2_lib.baseboard_fab2(sch_1):fm_disable_fan_n" )
			)
			( signal "FM_ENABLE_FAN_POWER"
				( objectStatus "@baseboard_fab2_lib.baseboard_fab2(sch_1):fm_enable_fan_power" )
			)
			( signal "P12V_FAN"
				( attribute "VOLTAGE" "12.0V"
					( Units "uVoltage" "V" 1.000000)
					( Status sAliasFlattened )
					( Origin gFrontEnd )
				)
				( objectStatus "@baseboard_fab2_lib.baseboard_fab2(sch_1):p12v_fan" )
			)
			( signal "PUMP_PWM_OUT_R"
				( objectStatus "@baseboard_fab2_lib.baseboard_fab2(sch_1):pump_pwm_out_r" )
			)
			( signal "PUMP_TACH0"
				( objectStatus "@baseboard_fab2_lib.baseboard_fab2(sch_1):pump_tach0" )
			)
			( signal "PU_SPI_BMC_BT_HOLD_N"
				( objectStatus "@baseboard_fab2_lib.baseboard_fab2(sch_1):pu_spi_bmc_bt_hold_n" )
			)
			( signal "PU_SPI_BMC_BT_WP_N"
				( objectStatus "@baseboard_fab2_lib.baseboard_fab2(sch_1):pu_spi_bmc_bt_wp_n" )
			)
			( signal "PU_SPI_FLASH_RESET_2_N"
				( objectStatus "@baseboard_fab2_lib.baseboard_fab2(sch_1):pu_spi_flash_reset_2_n" )
			)
			( signal "SPI_BMC_BT_DI_R"
				( objectStatus "@baseboard_fab2_lib.baseboard_fab2(sch_1):spi_bmc_bt_di_r" )
			)
			( signal "TP_SPI_2_0"
				( objectStatus "@baseboard_fab2_lib.baseboard_fab2(sch_1):tp_spi_2_0" )
			)
			( signal "TP_SPI_2_1"
				( objectStatus "@baseboard_fab2_lib.baseboard_fab2(sch_1):tp_spi_2_1" )
			)
			( signal "TP_SPI_2_2"
				( objectStatus "@baseboard_fab2_lib.baseboard_fab2(sch_1):tp_spi_2_2" )
			)
			( signal "TP_SPI_2_3"
				( objectStatus "@baseboard_fab2_lib.baseboard_fab2(sch_1):tp_spi_2_3" )
			)
			( signal "TP_SPI_2_4"
				( objectStatus "@baseboard_fab2_lib.baseboard_fab2(sch_1):tp_spi_2_4" )
			)
			( signal "TP_SPI_2_5"
				( objectStatus "@baseboard_fab2_lib.baseboard_fab2(sch_1):tp_spi_2_5" )
			)
			( signal "TP_SPI_2_6"
				( objectStatus "@baseboard_fab2_lib.baseboard_fab2(sch_1):tp_spi_2_6" )
			)
			( signal "SMB_CPU1_PE_HP_GTL_R_SCL"
				( objectStatus "@baseboard_fab2_lib.baseboard_fab2(sch_1):smb_cpu1_pe_hp_gtl_r_scl" )
			)
			( signal "SMB_CPU1_PE_HP_GTL_R_SDA"
				( objectStatus "@baseboard_fab2_lib.baseboard_fab2(sch_1):smb_cpu1_pe_hp_gtl_r_sda" )
			)
			( signal "SMB_PEHPCPU1_STBY_LVC3_R_SCL"
				( objectStatus "@baseboard_fab2_lib.baseboard_fab2(sch_1):smb_pehpcpu1_stby_lvc3_r_scl" )
			)
			( signal "SMB_PEHPCPU1_STBY_LVC3_R_SDA"
				( objectStatus "@baseboard_fab2_lib.baseboard_fab2(sch_1):smb_pehpcpu1_stby_lvc3_r_sda" )
			)
			( signal "SMB_PEHPCPU1_STBY_LVC3_SCL"
				( objectStatus "@baseboard_fab2_lib.baseboard_fab2(sch_1):smb_pehpcpu1_stby_lvc3_scl" )
			)
			( signal "SMB_PEHPCPU1_STBY_LVC3_SDA"
				( objectStatus "@baseboard_fab2_lib.baseboard_fab2(sch_1):smb_pehpcpu1_stby_lvc3_sda" )
			)
			( signal "TP_SMB_PEHPCPU1_EN"
				( objectStatus "@baseboard_fab2_lib.baseboard_fab2(sch_1):tp_smb_pehpcpu1_en" )
			)
			( signal "ISENSE_TMP421_1_BC"
				( objectStatus "@baseboard_fab2_lib.baseboard_fab2(sch_1):isense_tmp421_1_bc" )
			)
			( signal "ISENSE_TMP421_1_DXN"
				( objectStatus "@baseboard_fab2_lib.baseboard_fab2(sch_1):isense_tmp421_1_dxn" )
			)
			( signal "ISENSE_TMP421_1_DXP"
				( objectStatus "@baseboard_fab2_lib.baseboard_fab2(sch_1):isense_tmp421_1_dxp" )
			)
			( signal "ISENSE_TMP421_1_E"
				( objectStatus "@baseboard_fab2_lib.baseboard_fab2(sch_1):isense_tmp421_1_e" )
			)
			( signal "ISENSE_TMP421_2_BC"
				( objectStatus "@baseboard_fab2_lib.baseboard_fab2(sch_1):isense_tmp421_2_bc" )
			)
			( signal "ISENSE_TMP421_2_DXN"
				( objectStatus "@baseboard_fab2_lib.baseboard_fab2(sch_1):isense_tmp421_2_dxn" )
			)
			( signal "ISENSE_TMP421_2_DXP"
				( objectStatus "@baseboard_fab2_lib.baseboard_fab2(sch_1):isense_tmp421_2_dxp" )
			)
			( signal "ISENSE_TMP421_2_E"
				( objectStatus "@baseboard_fab2_lib.baseboard_fab2(sch_1):isense_tmp421_2_e" )
			)
			( signal "PD_FRU_WP"
				( objectStatus "@baseboard_fab2_lib.baseboard_fab2(sch_1):pd_fru_wp" )
			)
			( signal "PD_TMP421_1_A0"
				( objectStatus "@baseboard_fab2_lib.baseboard_fab2(sch_1):pd_tmp421_1_a0" )
			)
			( signal "PD_TMP421_2_A1"
				( objectStatus "@baseboard_fab2_lib.baseboard_fab2(sch_1):pd_tmp421_2_a1" )
			)
			( signal "PU_AT24C64_A2"
				( objectStatus "@baseboard_fab2_lib.baseboard_fab2(sch_1):pu_at24c64_a2" )
			)
			( signal "PU_TMP421_1_A1"
				( objectStatus "@baseboard_fab2_lib.baseboard_fab2(sch_1):pu_tmp421_1_a1" )
			)
			( signal "PU_TMP421_2_A0"
				( objectStatus "@baseboard_fab2_lib.baseboard_fab2(sch_1):pu_tmp421_2_a0" )
			)
			( signal "SMB_SENSOR_STBY_LVC3_SCL"
				( objectStatus "@baseboard_fab2_lib.baseboard_fab2(sch_1):smb_sensor_stby_lvc3_scl" )
			)
			( signal "SMB_SENSOR_STBY_LVC3_SCL_R2"
				( objectStatus "@baseboard_fab2_lib.baseboard_fab2(sch_1):smb_sensor_stby_lvc3_scl_r2" )
			)
			( signal "SMB_SENSOR_STBY_LVC3_SDA"
				( objectStatus "@baseboard_fab2_lib.baseboard_fab2(sch_1):smb_sensor_stby_lvc3_sda" )
			)
			( signal "SMB_SENSOR_STBY_LVC3_SDA_R2"
				( objectStatus "@baseboard_fab2_lib.baseboard_fab2(sch_1):smb_sensor_stby_lvc3_sda_r2" )
			)
			( signal "SMB_SENSOR_TMP421_1_SCL"
				( objectStatus "@baseboard_fab2_lib.baseboard_fab2(sch_1):smb_sensor_tmp421_1_scl" )
			)
			( signal "SMB_SENSOR_TMP421_1_SDA"
				( objectStatus "@baseboard_fab2_lib.baseboard_fab2(sch_1):smb_sensor_tmp421_1_sda" )
			)
			( signal "SMB_SENSOR_TMP421_2_SCL"
				( objectStatus "@baseboard_fab2_lib.baseboard_fab2(sch_1):smb_sensor_tmp421_2_scl" )
			)
			( signal "SMB_SENSOR_TMP421_2_SDA"
				( objectStatus "@baseboard_fab2_lib.baseboard_fab2(sch_1):smb_sensor_tmp421_2_sda" )
			)
			( signal "FM_DB_PRESENT"
				( objectStatus "@baseboard_fab2_lib.baseboard_fab2(sch_1):fm_db_present" )
			)
			( signal "FM_DB_UART_SEL0_N"
				( objectStatus "@baseboard_fab2_lib.baseboard_fab2(sch_1):fm_db_uart_sel0_n" )
			)
			( signal "FM_DB_UART_SEL1_N"
				( objectStatus "@baseboard_fab2_lib.baseboard_fab2(sch_1):fm_db_uart_sel1_n" )
			)
			( signal "FM_DB_UART_SEL2_N"
				( objectStatus "@baseboard_fab2_lib.baseboard_fab2(sch_1):fm_db_uart_sel2_n" )
			)
			( signal "FM_DB_UART_SEL3_N"
				( objectStatus "@baseboard_fab2_lib.baseboard_fab2(sch_1):fm_db_uart_sel3_n" )
			)
			( signal "FM_DB_UART_SEL4_N"
				( objectStatus "@baseboard_fab2_lib.baseboard_fab2(sch_1):fm_db_uart_sel4_n" )
			)
			( signal "FM_UART_SEL_N"
				( objectStatus "@baseboard_fab2_lib.baseboard_fab2(sch_1):fm_uart_sel_n" )
			)
			( signal "TP_FET_Q56_3"
				( objectStatus "@baseboard_fab2_lib.baseboard_fab2(sch_1):tp_fet_q56_3" )
			)
			( signal "TP_FET_Q56_4"
				( objectStatus "@baseboard_fab2_lib.baseboard_fab2(sch_1):tp_fet_q56_4" )
			)
			( signal "A_P3V_BAT_R"
				( attribute "VOLTAGE" "+3 V"
					( Units "uVoltage" "V" 1.000000)
					( Status sAliasFlattened )
					( Origin gFrontEnd )
				)
				( objectStatus "@baseboard_fab2_lib.baseboard_fab2(sch_1):a_p3v_bat_r" )
			)
			( signal "FM_BATTERY_SENSE_EN"
				( objectStatus "@baseboard_fab2_lib.baseboard_fab2(sch_1):fm_battery_sense_en" )
			)
			( signal "P3V_BAT_SOURCE_R"
				( attribute "VOLTAGE" "+3V"
					( Units "uVoltage" "V" 1.000000)
					( Status sAliasFlattened )
					( Origin gFrontEnd )
				)
				( objectStatus "@baseboard_fab2_lib.baseboard_fab2(sch_1):p3v_bat_source_r" )
			)
			( signal "P5V"
				( attribute "VOLTAGE" "5.0V"
					( Units "uVoltage" "V" 1.000000)
					( Status sAliasFlattened )
					( Status sAliasConflict )
					( Origin gFrontEnd )
				)
				( objectStatus "@baseboard_fab2_lib.baseboard_fab2(sch_1):p5v" )
			)
			( signal "SPI_BMC_BT_WP0_N"
				( objectStatus "@baseboard_fab2_lib.baseboard_fab2(sch_1):spi_bmc_bt_wp0_n" )
			)
			( signal "FM_FAST_PROCHOT_AND_OUT_0_N"
				( objectStatus "@baseboard_fab2_lib.baseboard_fab2(sch_1):fm_fast_prochot_and_out_0_n" )
			)
			( signal "FM_FAST_PROCHOT_AND_OUT_1_N"
				( objectStatus "@baseboard_fab2_lib.baseboard_fab2(sch_1):fm_fast_prochot_and_out_1_n" )
			)
			( signal "FM_FAST_PROCHOT_EN"
				( objectStatus "@baseboard_fab2_lib.baseboard_fab2(sch_1):fm_fast_prochot_en" )
			)
			( signal "FM_FAST_PROCHOT_THROTTLE_DLY_BU"
				( objectStatus "@baseboard_fab2_lib.baseboard_fab2(sch_1):fm_fast_prochot_throttle_dly_buf_n" )
			)
			( signal "FM_FAST_PROCHOT_THROTTLE_DLY_N"
				( objectStatus "@baseboard_fab2_lib.baseboard_fab2(sch_1):fm_fast_prochot_throttle_dly_n" )
			)
			( signal "FM_FAST_PROCHOT_THROTTLE_IN_N"
				( objectStatus "@baseboard_fab2_lib.baseboard_fab2(sch_1):fm_fast_prochot_throttle_in_n" )
			)
			( signal "FM_OC_DETECT_N"
				( objectStatus "@baseboard_fab2_lib.baseboard_fab2(sch_1):fm_oc_detect_n" )
			)
			( signal "FM_PMBUS_ALERT_BUF_EN"
				( objectStatus "@baseboard_fab2_lib.baseboard_fab2(sch_1):fm_pmbus_alert_buf_en" )
			)
			( signal "FM_THROTTLE_R1_N"
				( objectStatus "@baseboard_fab2_lib.baseboard_fab2(sch_1):fm_throttle_r1_n" )
			)
			( signal "IRQ_FORCE_NM_THROTTLE_R_N"
				( objectStatus "@baseboard_fab2_lib.baseboard_fab2(sch_1):irq_force_nm_throttle_r_n" )
			)
			( signal "IRQ_SML1_PMBUS_ALERT_BUF_N"
				( objectStatus "@baseboard_fab2_lib.baseboard_fab2(sch_1):irq_sml1_pmbus_alert_buf_n" )
			)
			( signal "P12V_HDD_SATA"
				( attribute "VOLTAGE" "12"
					( Units "uVoltage" "V" 1.000000)
					( Status sAliasFlattened )
					( Origin gFrontEnd )
				)
				( objectStatus "@baseboard_fab2_lib.baseboard_fab2(sch_1):p12v_hdd_sata" )
			)
			( signal "P5V_HDD_SATA"
				( attribute "VOLTAGE" "5"
					( Units "uVoltage" "V" 1.000000)
					( Status sAliasFlattened )
					( Origin gFrontEnd )
				)
				( objectStatus "@baseboard_fab2_lib.baseboard_fab2(sch_1):p5v_hdd_sata" )
			)
			( signal "SATA6G_S1_RX_C_DN"
				( objectStatus "@baseboard_fab2_lib.baseboard_fab2(sch_1):sata6g_s1_rx_c_dn" )
			)
			( signal "SATA6G_S1_RX_C_DP"
				( objectStatus "@baseboard_fab2_lib.baseboard_fab2(sch_1):sata6g_s1_rx_c_dp" )
			)
			( signal "SATA6G_S1_TX_C_DN"
				( objectStatus "@baseboard_fab2_lib.baseboard_fab2(sch_1):sata6g_s1_tx_c_dn" )
			)
			( signal "SATA6G_S1_TX_C_DP"
				( objectStatus "@baseboard_fab2_lib.baseboard_fab2(sch_1):sata6g_s1_tx_c_dp" )
			)
			( signal "PD_SATA0_CONTROLLER_TYPE_R"
				( objectStatus "@baseboard_fab2_lib.baseboard_fab2(sch_1):pd_sata0_controller_type_r" )
			)
			( signal "PD_SATA1_CONTROLLER_TYPE_R"
				( objectStatus "@baseboard_fab2_lib.baseboard_fab2(sch_1):pd_sata1_controller_type_r" )
			)
			( signal "PU_DATAIN1_SATA_0_R"
				( objectStatus "@baseboard_fab2_lib.baseboard_fab2(sch_1):pu_datain1_sata_0_r" )
			)
			( signal "PU_DATAIN1_SATA_1_R"
				( objectStatus "@baseboard_fab2_lib.baseboard_fab2(sch_1):pu_datain1_sata_1_r" )
			)
			( signal "SATA6G_P0_RX_C_DN"
				( objectStatus "@baseboard_fab2_lib.baseboard_fab2(sch_1):sata6g_p0_rx_c_dn" )
			)
			( signal "SATA6G_P0_RX_C_DP"
				( objectStatus "@baseboard_fab2_lib.baseboard_fab2(sch_1):sata6g_p0_rx_c_dp" )
			)
			( signal "SATA6G_P0_TX_C_DN"
				( objectStatus "@baseboard_fab2_lib.baseboard_fab2(sch_1):sata6g_p0_tx_c_dn" )
			)
			( signal "SATA6G_P0_TX_C_DP"
				( objectStatus "@baseboard_fab2_lib.baseboard_fab2(sch_1):sata6g_p0_tx_c_dp" )
			)
			( signal "SATA6G_P1_RX_C_DN"
				( objectStatus "@baseboard_fab2_lib.baseboard_fab2(sch_1):sata6g_p1_rx_c_dn" )
			)
			( signal "SATA6G_P1_RX_C_DP"
				( objectStatus "@baseboard_fab2_lib.baseboard_fab2(sch_1):sata6g_p1_rx_c_dp" )
			)
			( signal "SATA6G_P1_TX_C_DN"
				( objectStatus "@baseboard_fab2_lib.baseboard_fab2(sch_1):sata6g_p1_tx_c_dn" )
			)
			( signal "SATA6G_P1_TX_C_DP"
				( objectStatus "@baseboard_fab2_lib.baseboard_fab2(sch_1):sata6g_p1_tx_c_dp" )
			)
			( signal "SATA6G_P2_RX_C_DN"
				( objectStatus "@baseboard_fab2_lib.baseboard_fab2(sch_1):sata6g_p2_rx_c_dn" )
			)
			( signal "SATA6G_P2_RX_C_DP"
				( objectStatus "@baseboard_fab2_lib.baseboard_fab2(sch_1):sata6g_p2_rx_c_dp" )
			)
			( signal "SATA6G_P2_TX_C_DN"
				( objectStatus "@baseboard_fab2_lib.baseboard_fab2(sch_1):sata6g_p2_tx_c_dn" )
			)
			( signal "SATA6G_P2_TX_C_DP"
				( objectStatus "@baseboard_fab2_lib.baseboard_fab2(sch_1):sata6g_p2_tx_c_dp" )
			)
			( signal "SATA6G_P3_RX_C_DN"
				( objectStatus "@baseboard_fab2_lib.baseboard_fab2(sch_1):sata6g_p3_rx_c_dn" )
			)
			( signal "SATA6G_P3_RX_C_DP"
				( objectStatus "@baseboard_fab2_lib.baseboard_fab2(sch_1):sata6g_p3_rx_c_dp" )
			)
			( signal "SATA6G_P3_TX_C_DN"
				( objectStatus "@baseboard_fab2_lib.baseboard_fab2(sch_1):sata6g_p3_tx_c_dn" )
			)
			( signal "SATA6G_P3_TX_C_DP"
				( objectStatus "@baseboard_fab2_lib.baseboard_fab2(sch_1):sata6g_p3_tx_c_dp" )
			)
			( signal "SATA6G_P4_RX_C_DN"
				( objectStatus "@baseboard_fab2_lib.baseboard_fab2(sch_1):sata6g_p4_rx_c_dn" )
			)
			( signal "SATA6G_P4_RX_C_DP"
				( objectStatus "@baseboard_fab2_lib.baseboard_fab2(sch_1):sata6g_p4_rx_c_dp" )
			)
			( signal "SATA6G_P4_TX_C_DN"
				( objectStatus "@baseboard_fab2_lib.baseboard_fab2(sch_1):sata6g_p4_tx_c_dn" )
			)
			( signal "SATA6G_P4_TX_C_DP"
				( objectStatus "@baseboard_fab2_lib.baseboard_fab2(sch_1):sata6g_p4_tx_c_dp" )
			)
			( signal "SATA6G_P5_RX_C_DN"
				( objectStatus "@baseboard_fab2_lib.baseboard_fab2(sch_1):sata6g_p5_rx_c_dn" )
			)
			( signal "SATA6G_P5_RX_C_DP"
				( objectStatus "@baseboard_fab2_lib.baseboard_fab2(sch_1):sata6g_p5_rx_c_dp" )
			)
			( signal "SATA6G_P5_TX_C_DN"
				( objectStatus "@baseboard_fab2_lib.baseboard_fab2(sch_1):sata6g_p5_tx_c_dn" )
			)
			( signal "SATA6G_P5_TX_C_DP"
				( objectStatus "@baseboard_fab2_lib.baseboard_fab2(sch_1):sata6g_p5_tx_c_dp" )
			)
			( signal "SATA6G_P6_RX_C_DN"
				( objectStatus "@baseboard_fab2_lib.baseboard_fab2(sch_1):sata6g_p6_rx_c_dn" )
			)
			( signal "SATA6G_P6_RX_C_DP"
				( objectStatus "@baseboard_fab2_lib.baseboard_fab2(sch_1):sata6g_p6_rx_c_dp" )
			)
			( signal "SATA6G_P6_TX_C_DN"
				( objectStatus "@baseboard_fab2_lib.baseboard_fab2(sch_1):sata6g_p6_tx_c_dn" )
			)
			( signal "SATA6G_P6_TX_C_DP"
				( objectStatus "@baseboard_fab2_lib.baseboard_fab2(sch_1):sata6g_p6_tx_c_dp" )
			)
			( signal "SATA6G_P7_RX_C_DN"
				( objectStatus "@baseboard_fab2_lib.baseboard_fab2(sch_1):sata6g_p7_rx_c_dn" )
			)
			( signal "SATA6G_P7_RX_C_DP"
				( objectStatus "@baseboard_fab2_lib.baseboard_fab2(sch_1):sata6g_p7_rx_c_dp" )
			)
			( signal "SATA6G_P7_TX_C_DN"
				( objectStatus "@baseboard_fab2_lib.baseboard_fab2(sch_1):sata6g_p7_tx_c_dn" )
			)
			( signal "SATA6G_P7_TX_C_DP"
				( objectStatus "@baseboard_fab2_lib.baseboard_fab2(sch_1):sata6g_p7_tx_c_dp" )
			)
			( signal "SGPIO_PCH_SATA_CLOCK_R"
				( objectStatus "@baseboard_fab2_lib.baseboard_fab2(sch_1):sgpio_pch_sata_clock_r" )
			)
			( signal "SGPIO_PCH_SATA_DOUT0_R"
				( objectStatus "@baseboard_fab2_lib.baseboard_fab2(sch_1):sgpio_pch_sata_dout0_r" )
			)
			( signal "SGPIO_PCH_SATA_LOAD_R"
				( objectStatus "@baseboard_fab2_lib.baseboard_fab2(sch_1):sgpio_pch_sata_load_r" )
			)
			( signal "TP_FM_QAT_CBL_PRSNT0_R_N"
				( objectStatus "@baseboard_fab2_lib.baseboard_fab2(sch_1):tp_fm_qat_cbl_prsnt0_r_n" )
			)
			( signal "TP_FM_QAT_CBL_PRSNT1_N_R"
				( objectStatus "@baseboard_fab2_lib.baseboard_fab2(sch_1):tp_fm_qat_cbl_prsnt1_n_r" )
			)
			( signal "TP_SGPIO_SATA_CLOCK1_R"
				( objectStatus "@baseboard_fab2_lib.baseboard_fab2(sch_1):tp_sgpio_sata_clock1_r" )
			)
			( signal "TP_SGPIO_SATA_DATA1_R"
				( objectStatus "@baseboard_fab2_lib.baseboard_fab2(sch_1):tp_sgpio_sata_data1_r" )
			)
			( signal "TP_SGPIO_SATA_LOAD1_R"
				( objectStatus "@baseboard_fab2_lib.baseboard_fab2(sch_1):tp_sgpio_sata_load1_r" )
			)
			( signal "SGPIO_PCH_SSATA_CLOCK_R"
				( objectStatus "@baseboard_fab2_lib.baseboard_fab2(sch_1):sgpio_pch_ssata_clock_r" )
			)
			( signal "SGPIO_PCH_SSATA_DOUT0_R"
				( objectStatus "@baseboard_fab2_lib.baseboard_fab2(sch_1):sgpio_pch_ssata_dout0_r" )
			)
			( signal "SGPIO_PCH_SSATA_LOAD_R"
				( objectStatus "@baseboard_fab2_lib.baseboard_fab2(sch_1):sgpio_pch_ssata_load_r" )
			)
			( signal "FM_BEEP_LED_P"
				( objectStatus "@baseboard_fab2_lib.baseboard_fab2(sch_1):fm_beep_led_p" )
			)
			( signal "FM_PWR_BTN_R_N"
				( objectStatus "@baseboard_fab2_lib.baseboard_fab2(sch_1):fm_pwr_btn_r_n" )
			)
			( signal "FM_SPEAKER_PCH_N"
				( objectStatus "@baseboard_fab2_lib.baseboard_fab2(sch_1):fm_speaker_pch_n" )
			)
			( signal "FP_ID_LED_P5V_STBY_N"
				( objectStatus "@baseboard_fab2_lib.baseboard_fab2(sch_1):fp_id_led_p5v_stby_n" )
			)
			( signal "FP_ID_LED_XOR_R"
				( objectStatus "@baseboard_fab2_lib.baseboard_fab2(sch_1):fp_id_led_xor_r" )
			)
			( signal "FP_PWR_BTN_BUF1_N"
				( objectStatus "@baseboard_fab2_lib.baseboard_fab2(sch_1):fp_pwr_btn_buf1_n" )
			)
			( signal "FP_PWR_BTN_R1_N"
				( objectStatus "@baseboard_fab2_lib.baseboard_fab2(sch_1):fp_pwr_btn_r1_n" )
			)
			( signal "FP_PWR_BTN_R_N"
				( objectStatus "@baseboard_fab2_lib.baseboard_fab2(sch_1):fp_pwr_btn_r_n" )
			)
			( signal "FP_RST_BTN_BUF1_N"
				( objectStatus "@baseboard_fab2_lib.baseboard_fab2(sch_1):fp_rst_btn_buf1_n" )
			)
			( signal "FP_RST_BTN_R_N"
				( objectStatus "@baseboard_fab2_lib.baseboard_fab2(sch_1):fp_rst_btn_r_n" )
			)
			( signal "PWRGD_P3V3"
				( objectStatus "@baseboard_fab2_lib.baseboard_fab2(sch_1):pwrgd_p3v3" )
			)
			( signal "PWRGD_P3V3_R"
				( objectStatus "@baseboard_fab2_lib.baseboard_fab2(sch_1):pwrgd_p3v3_r" )
			)
			( signal "RST_SYSTEM_BTN_BUF_N"
				( objectStatus "@baseboard_fab2_lib.baseboard_fab2(sch_1):rst_system_btn_buf_n" )
			)
			( signal "P5V_USB"
				( attribute "VOLTAGE" "5V"
					( Units "uVoltage" "V" 1.000000)
					( Status sAliasFlattened )
					( Origin gFrontEnd )
				)
				( objectStatus "@baseboard_fab2_lib.baseboard_fab2(sch_1):p5v_usb" )
			)
			( signal "TP_USB_ESD_AC2"
				( objectStatus "@baseboard_fab2_lib.baseboard_fab2(sch_1):tp_usb_esd_ac2" )
			)
			( signal "TP_USB_ESD_AC3"
				( objectStatus "@baseboard_fab2_lib.baseboard_fab2(sch_1):tp_usb_esd_ac3" )
			)
			( signal "TP_USB_ESD_OUT2"
				( objectStatus "@baseboard_fab2_lib.baseboard_fab2(sch_1):tp_usb_esd_out2" )
			)
			( signal "TP_USB_ESD_OUT3"
				( objectStatus "@baseboard_fab2_lib.baseboard_fab2(sch_1):tp_usb_esd_out3" )
			)
			( signal "USB2_P01_ESD_DN"
				( objectStatus "@baseboard_fab2_lib.baseboard_fab2(sch_1):usb2_p01_esd_dn" )
			)
			( signal "USB2_P01_ESD_DP"
				( objectStatus "@baseboard_fab2_lib.baseboard_fab2(sch_1):usb2_p01_esd_dp" )
			)
			( signal "FM_BMC_FAULT_LED"
				( objectStatus "@baseboard_fab2_lib.baseboard_fab2(sch_1):fm_bmc_fault_led" )
			)
			( signal "FM_RED_LED_ANODE"
				( objectStatus "@baseboard_fab2_lib.baseboard_fab2(sch_1):fm_red_led_anode" )
			)
			( signal "FM_RED_LED_CATHODE"
				( objectStatus "@baseboard_fab2_lib.baseboard_fab2(sch_1):fm_red_led_cathode" )
			)
			( signal "FP_LED_HDD_ACTIVITY_AND_N"
				( objectStatus "@baseboard_fab2_lib.baseboard_fab2(sch_1):fp_led_hdd_activity_and_n" )
			)
			( signal "FP_LED_HDD_ACTIVITY_AND_R_N"
				( objectStatus "@baseboard_fab2_lib.baseboard_fab2(sch_1):fp_led_hdd_activity_and_r_n" )
			)
			( signal "LED_P5V_STBY"
				( objectStatus "@baseboard_fab2_lib.baseboard_fab2(sch_1):led_p5v_stby" )
			)
			( signal "LED_SAS_ACT_R_N"
				( objectStatus "@baseboard_fab2_lib.baseboard_fab2(sch_1):led_sas_act_r_n" )
			)
			( signal "LED_SATA_ACT_R_N"
				( objectStatus "@baseboard_fab2_lib.baseboard_fab2(sch_1):led_sata_act_r_n" )
			)
			( signal "FAN_PWM_OUT_SYS0_R1"
				( objectStatus "@baseboard_fab2_lib.baseboard_fab2(sch_1):fan_pwm_out_sys0_r1" )
			)
			( signal "FAN_TACH0_R"
				( objectStatus "@baseboard_fab2_lib.baseboard_fab2(sch_1):fan_tach0_r" )
			)
			( signal "FAN_TACH1_R"
				( objectStatus "@baseboard_fab2_lib.baseboard_fab2(sch_1):fan_tach1_r" )
			)
			( signal "FAN_TACH2_R"
				( objectStatus "@baseboard_fab2_lib.baseboard_fab2(sch_1):fan_tach2_r" )
			)
			( signal "FAN_TACH3_R"
				( objectStatus "@baseboard_fab2_lib.baseboard_fab2(sch_1):fan_tach3_r" )
			)
			( signal "FM_CTNR_PS_ON_R"
				( objectStatus "@baseboard_fab2_lib.baseboard_fab2(sch_1):fm_ctnr_ps_on_r" )
			)
			( signal "FM_MATED_IN_D1_N"
				( objectStatus "@baseboard_fab2_lib.baseboard_fab2(sch_1):fm_mated_in_d1_n" )
			)
			( signal "FM_MATED_IN_D2_N"
				( objectStatus "@baseboard_fab2_lib.baseboard_fab2(sch_1):fm_mated_in_d2_n" )
			)
			( signal "FM_MATED_IN_N"
				( objectStatus "@baseboard_fab2_lib.baseboard_fab2(sch_1):fm_mated_in_n" )
			)
			( signal "FM_P12V_HOTSWAP0_EN"
				( objectStatus "@baseboard_fab2_lib.baseboard_fab2(sch_1):fm_p12v_hotswap0_en" )
			)
			( signal "FM_PS_EN"
				( objectStatus "@baseboard_fab2_lib.baseboard_fab2(sch_1):fm_ps_en" )
			)
			( signal "IRQ_SML1_PMBUS_ALERT_R_N"
				( objectStatus "@baseboard_fab2_lib.baseboard_fab2(sch_1):irq_sml1_pmbus_alert_r_n" )
			)
			( signal "P12V_PSU"
				( attribute "VOLTAGE" "12.0"
					( Units "uVoltage" "V" 1.000000)
					( Status sAliasFlattened )
					( Origin gFrontEnd )
				)
				( objectStatus "@baseboard_fab2_lib.baseboard_fab2(sch_1):p12v_psu" )
			)
			( signal "P3E_CPU1_PE3_MP_C_TXN<0>"
				( objectStatus "@baseboard_fab2_lib.baseboard_fab2(sch_1):p3e_cpu1_pe3_mp_c_txn(0)" )
			)
			( signal "P3E_CPU1_PE3_MP_C_TXN<1>"
				( objectStatus "@baseboard_fab2_lib.baseboard_fab2(sch_1):p3e_cpu1_pe3_mp_c_txn(1)" )
			)
			( signal "P3E_CPU1_PE3_MP_C_TXN<2>"
				( objectStatus "@baseboard_fab2_lib.baseboard_fab2(sch_1):p3e_cpu1_pe3_mp_c_txn(2)" )
			)
			( signal "P3E_CPU1_PE3_MP_C_TXN<3>"
				( objectStatus "@baseboard_fab2_lib.baseboard_fab2(sch_1):p3e_cpu1_pe3_mp_c_txn(3)" )
			)
			( signal "P3E_CPU1_PE3_MP_C_TXN<4>"
				( objectStatus "@baseboard_fab2_lib.baseboard_fab2(sch_1):p3e_cpu1_pe3_mp_c_txn(4)" )
			)
			( signal "P3E_CPU1_PE3_MP_C_TXN<5>"
				( objectStatus "@baseboard_fab2_lib.baseboard_fab2(sch_1):p3e_cpu1_pe3_mp_c_txn(5)" )
			)
			( signal "P3E_CPU1_PE3_MP_C_TXN<6>"
				( objectStatus "@baseboard_fab2_lib.baseboard_fab2(sch_1):p3e_cpu1_pe3_mp_c_txn(6)" )
			)
			( signal "P3E_CPU1_PE3_MP_C_TXN<7>"
				( objectStatus "@baseboard_fab2_lib.baseboard_fab2(sch_1):p3e_cpu1_pe3_mp_c_txn(7)" )
			)
			( signal "P3E_CPU1_PE3_MP_C_TXP<0>"
				( objectStatus "@baseboard_fab2_lib.baseboard_fab2(sch_1):p3e_cpu1_pe3_mp_c_txp(0)" )
			)
			( signal "P3E_CPU1_PE3_MP_C_TXP<1>"
				( objectStatus "@baseboard_fab2_lib.baseboard_fab2(sch_1):p3e_cpu1_pe3_mp_c_txp(1)" )
			)
			( signal "P3E_CPU1_PE3_MP_C_TXP<2>"
				( objectStatus "@baseboard_fab2_lib.baseboard_fab2(sch_1):p3e_cpu1_pe3_mp_c_txp(2)" )
			)
			( signal "P3E_CPU1_PE3_MP_C_TXP<3>"
				( objectStatus "@baseboard_fab2_lib.baseboard_fab2(sch_1):p3e_cpu1_pe3_mp_c_txp(3)" )
			)
			( signal "P3E_CPU1_PE3_MP_C_TXP<4>"
				( objectStatus "@baseboard_fab2_lib.baseboard_fab2(sch_1):p3e_cpu1_pe3_mp_c_txp(4)" )
			)
			( signal "P3E_CPU1_PE3_MP_C_TXP<5>"
				( objectStatus "@baseboard_fab2_lib.baseboard_fab2(sch_1):p3e_cpu1_pe3_mp_c_txp(5)" )
			)
			( signal "P3E_CPU1_PE3_MP_C_TXP<6>"
				( objectStatus "@baseboard_fab2_lib.baseboard_fab2(sch_1):p3e_cpu1_pe3_mp_c_txp(6)" )
			)
			( signal "P3E_CPU1_PE3_MP_C_TXP<7>"
				( objectStatus "@baseboard_fab2_lib.baseboard_fab2(sch_1):p3e_cpu1_pe3_mp_c_txp(7)" )
			)
			( signal "PWRGD_P12V_HSC_DLY"
				( objectStatus "@baseboard_fab2_lib.baseboard_fab2(sch_1):pwrgd_p12v_hsc_dly" )
			)
			( signal "RST_PCIE_MIDPLANE_N"
				( objectStatus "@baseboard_fab2_lib.baseboard_fab2(sch_1):rst_pcie_midplane_n" )
			)
			( signal "SPA_MID_DBG_RX_R"
				( objectStatus "@baseboard_fab2_lib.baseboard_fab2(sch_1):spa_mid_dbg_rx_r" )
			)
			( signal "SPA_MID_DBG_TX_R"
				( objectStatus "@baseboard_fab2_lib.baseboard_fab2(sch_1):spa_mid_dbg_tx_r" )
			)
			( signal "P3E_CPU1_PE3_MP_C_TXN<8>"
				( objectStatus "@baseboard_fab2_lib.baseboard_fab2(sch_1):p3e_cpu1_pe3_mp_c_txn(8)" )
			)
			( signal "P3E_CPU1_PE3_MP_C_TXN<9>"
				( objectStatus "@baseboard_fab2_lib.baseboard_fab2(sch_1):p3e_cpu1_pe3_mp_c_txn(9)" )
			)
			( signal "P3E_CPU1_PE3_MP_C_TXN<10>"
				( objectStatus "@baseboard_fab2_lib.baseboard_fab2(sch_1):p3e_cpu1_pe3_mp_c_txn(10)" )
			)
			( signal "P3E_CPU1_PE3_MP_C_TXN<11>"
				( objectStatus "@baseboard_fab2_lib.baseboard_fab2(sch_1):p3e_cpu1_pe3_mp_c_txn(11)" )
			)
			( signal "P3E_CPU1_PE3_MP_C_TXN<12>"
				( objectStatus "@baseboard_fab2_lib.baseboard_fab2(sch_1):p3e_cpu1_pe3_mp_c_txn(12)" )
			)
			( signal "P3E_CPU1_PE3_MP_C_TXN<13>"
				( objectStatus "@baseboard_fab2_lib.baseboard_fab2(sch_1):p3e_cpu1_pe3_mp_c_txn(13)" )
			)
			( signal "P3E_CPU1_PE3_MP_C_TXN<14>"
				( objectStatus "@baseboard_fab2_lib.baseboard_fab2(sch_1):p3e_cpu1_pe3_mp_c_txn(14)" )
			)
			( signal "P3E_CPU1_PE3_MP_C_TXN<15>"
				( objectStatus "@baseboard_fab2_lib.baseboard_fab2(sch_1):p3e_cpu1_pe3_mp_c_txn(15)" )
			)
			( signal "P3E_CPU1_PE3_MP_C_TXP<8>"
				( objectStatus "@baseboard_fab2_lib.baseboard_fab2(sch_1):p3e_cpu1_pe3_mp_c_txp(8)" )
			)
			( signal "P3E_CPU1_PE3_MP_C_TXP<9>"
				( objectStatus "@baseboard_fab2_lib.baseboard_fab2(sch_1):p3e_cpu1_pe3_mp_c_txp(9)" )
			)
			( signal "P3E_CPU1_PE3_MP_C_TXP<10>"
				( objectStatus "@baseboard_fab2_lib.baseboard_fab2(sch_1):p3e_cpu1_pe3_mp_c_txp(10)" )
			)
			( signal "P3E_CPU1_PE3_MP_C_TXP<11>"
				( objectStatus "@baseboard_fab2_lib.baseboard_fab2(sch_1):p3e_cpu1_pe3_mp_c_txp(11)" )
			)
			( signal "P3E_CPU1_PE3_MP_C_TXP<12>"
				( objectStatus "@baseboard_fab2_lib.baseboard_fab2(sch_1):p3e_cpu1_pe3_mp_c_txp(12)" )
			)
			( signal "P3E_CPU1_PE3_MP_C_TXP<13>"
				( objectStatus "@baseboard_fab2_lib.baseboard_fab2(sch_1):p3e_cpu1_pe3_mp_c_txp(13)" )
			)
			( signal "P3E_CPU1_PE3_MP_C_TXP<14>"
				( objectStatus "@baseboard_fab2_lib.baseboard_fab2(sch_1):p3e_cpu1_pe3_mp_c_txp(14)" )
			)
			( signal "P3E_CPU1_PE3_MP_C_TXP<15>"
				( objectStatus "@baseboard_fab2_lib.baseboard_fab2(sch_1):p3e_cpu1_pe3_mp_c_txp(15)" )
			)
			( signal "TP_FM_WAKE_N"
				( objectStatus "@baseboard_fab2_lib.baseboard_fab2(sch_1):tp_fm_wake_n" )
			)
			( signal "TP_IOA5"
				( objectStatus "@baseboard_fab2_lib.baseboard_fab2(sch_1):tp_ioa5" )
			)
			( signal "TP_IOE4"
				( objectStatus "@baseboard_fab2_lib.baseboard_fab2(sch_1):tp_ioe4" )
			)
			( signal "TP_IOF4"
				( objectStatus "@baseboard_fab2_lib.baseboard_fab2(sch_1):tp_iof4" )
			)
			( signal "TP_IOG3"
				( objectStatus "@baseboard_fab2_lib.baseboard_fab2(sch_1):tp_iog3" )
			)
			( signal "TP_IOH3"
				( objectStatus "@baseboard_fab2_lib.baseboard_fab2(sch_1):tp_ioh3" )
			)
			( signal "TP_IOH4"
				( objectStatus "@baseboard_fab2_lib.baseboard_fab2(sch_1):tp_ioh4" )
			)
			( signal "TP_IOI4"
				( objectStatus "@baseboard_fab2_lib.baseboard_fab2(sch_1):tp_ioi4" )
			)
			( signal "IRQ_SPI_TPM_N_R"
				( objectStatus "@baseboard_fab2_lib.baseboard_fab2(sch_1):irq_spi_tpm_n_r" )
			)
			( signal "SPI_PCH_TPM_CLK_R"
				( objectStatus "@baseboard_fab2_lib.baseboard_fab2(sch_1):spi_pch_tpm_clk_r" )
			)
			( signal "SPI_PCH_TPM_CS_R_N"
				( objectStatus "@baseboard_fab2_lib.baseboard_fab2(sch_1):spi_pch_tpm_cs_r_n" )
			)
			( signal "SPI_PCH_TPM_MISO_R"
				( objectStatus "@baseboard_fab2_lib.baseboard_fab2(sch_1):spi_pch_tpm_miso_r" )
			)
			( signal "SPI_PCH_TPM_MOSI_R"
				( objectStatus "@baseboard_fab2_lib.baseboard_fab2(sch_1):spi_pch_tpm_mosi_r" )
			)
			( signal "FM_M2_DET_LVC3"
				( objectStatus "@baseboard_fab2_lib.baseboard_fab2(sch_1):fm_m2_det_lvc3" )
			)
			( signal "FM_M2_SSD_PEDET"
				( objectStatus "@baseboard_fab2_lib.baseboard_fab2(sch_1):fm_m2_ssd_pedet" )
			)
			( signal "NC_M2<0>"
				( objectStatus "@baseboard_fab2_lib.baseboard_fab2(sch_1):nc_m2(0)" )
			)
			( signal "NC_M2<1>"
				( objectStatus "@baseboard_fab2_lib.baseboard_fab2(sch_1):nc_m2(1)" )
			)
			( signal "P3E_PCH_M2_SATA6G_RX_R_DN"
				( objectStatus "@baseboard_fab2_lib.baseboard_fab2(sch_1):p3e_pch_m2_sata6g_rx_r_dn" )
			)
			( signal "P3E_PCH_M2_SATA6G_RX_R_DP"
				( objectStatus "@baseboard_fab2_lib.baseboard_fab2(sch_1):p3e_pch_m2_sata6g_rx_r_dp" )
			)
			( signal "P3E_PCH_M2_SATA6G_TX_R_DN"
				( objectStatus "@baseboard_fab2_lib.baseboard_fab2(sch_1):p3e_pch_m2_sata6g_tx_r_dn" )
			)
			( signal "P3E_PCH_M2_SATA6G_TX_R_DP"
				( objectStatus "@baseboard_fab2_lib.baseboard_fab2(sch_1):p3e_pch_m2_sata6g_tx_r_dp" )
			)
			( signal "P3E_PCH_M2_TX_C_DN<1>"
				( objectStatus "@baseboard_fab2_lib.baseboard_fab2(sch_1):p3e_pch_m2_tx_c_dn(1)" )
			)
			( signal "P3E_PCH_M2_TX_C_DN<2>"
				( objectStatus "@baseboard_fab2_lib.baseboard_fab2(sch_1):p3e_pch_m2_tx_c_dn(2)" )
			)
			( signal "P3E_PCH_M2_TX_C_DN<3>"
				( objectStatus "@baseboard_fab2_lib.baseboard_fab2(sch_1):p3e_pch_m2_tx_c_dn(3)" )
			)
			( signal "P3E_PCH_M2_TX_C_DP<1>"
				( objectStatus "@baseboard_fab2_lib.baseboard_fab2(sch_1):p3e_pch_m2_tx_c_dp(1)" )
			)
			( signal "P3E_PCH_M2_TX_C_DP<2>"
				( objectStatus "@baseboard_fab2_lib.baseboard_fab2(sch_1):p3e_pch_m2_tx_c_dp(2)" )
			)
			( signal "P3E_PCH_M2_TX_C_DP<3>"
				( objectStatus "@baseboard_fab2_lib.baseboard_fab2(sch_1):p3e_pch_m2_tx_c_dp(3)" )
			)
			( signal "PU_M2_CLK_REQ_N"
				( objectStatus "@baseboard_fab2_lib.baseboard_fab2(sch_1):pu_m2_clk_req_n" )
			)
			( signal "RST_PCIE_M2_DEV_N"
				( objectStatus "@baseboard_fab2_lib.baseboard_fab2(sch_1):rst_pcie_m2_dev_n" )
			)
			( signal "TP_LED_M2_ACT_N"
				( objectStatus "@baseboard_fab2_lib.baseboard_fab2(sch_1):tp_led_m2_act_n" )
			)
			( signal "TP_M2_32M_SUSCLK"
				( objectStatus "@baseboard_fab2_lib.baseboard_fab2(sch_1):tp_m2_32m_susclk" )
			)
			( signal "TP_M2_DEVSLP"
				( objectStatus "@baseboard_fab2_lib.baseboard_fab2(sch_1):tp_m2_devslp" )
			)
			( signal "FM_MEZZA_PRSNT1_N"
				( objectStatus "@baseboard_fab2_lib.baseboard_fab2(sch_1):fm_mezza_prsnt1_n" )
			)
			( signal "RMII_BMC_OCP_CRSDV_R"
				( objectStatus "@baseboard_fab2_lib.baseboard_fab2(sch_1):rmii_bmc_ocp_crsdv_r" )
			)
			( signal "RMII_BMC_OCP_RXD0_R"
				( objectStatus "@baseboard_fab2_lib.baseboard_fab2(sch_1):rmii_bmc_ocp_rxd0_r" )
			)
			( signal "RMII_BMC_OCP_RXD1_R"
				( objectStatus "@baseboard_fab2_lib.baseboard_fab2(sch_1):rmii_bmc_ocp_rxd1_r" )
			)
			( signal "RMII_BMC_OCP_RXER_R"
				( objectStatus "@baseboard_fab2_lib.baseboard_fab2(sch_1):rmii_bmc_ocp_rxer_r" )
			)
			( signal "RST_PCIE_CPU_DEV0_N"
				( objectStatus "@baseboard_fab2_lib.baseboard_fab2(sch_1):rst_pcie_cpu_dev0_n" )
			)
			( signal "RST_PCIE_CPU_DEV0_R_N"
				( objectStatus "@baseboard_fab2_lib.baseboard_fab2(sch_1):rst_pcie_cpu_dev0_r_n" )
			)
			( signal "RST_PCIE_CPU_DEV1_N"
				( objectStatus "@baseboard_fab2_lib.baseboard_fab2(sch_1):rst_pcie_cpu_dev1_n" )
			)
			( signal "RST_PCIE_CPU_DEV1_R_N"
				( objectStatus "@baseboard_fab2_lib.baseboard_fab2(sch_1):rst_pcie_cpu_dev1_r_n" )
			)
			( signal "RST_PCIE_CPU_DEV2_N"
				( objectStatus "@baseboard_fab2_lib.baseboard_fab2(sch_1):rst_pcie_cpu_dev2_n" )
			)
			( signal "RST_PCIE_CPU_DEV2_R_N"
				( objectStatus "@baseboard_fab2_lib.baseboard_fab2(sch_1):rst_pcie_cpu_dev2_r_n" )
			)
			( signal "RST_PCIE_CPU_DEV3_N"
				( objectStatus "@baseboard_fab2_lib.baseboard_fab2(sch_1):rst_pcie_cpu_dev3_n" )
			)
			( signal "RST_PCIE_CPU_DEV3_R_N"
				( objectStatus "@baseboard_fab2_lib.baseboard_fab2(sch_1):rst_pcie_cpu_dev3_r_n" )
			)
			( signal "TP_RSVD_B1"
				( objectStatus "@baseboard_fab2_lib.baseboard_fab2(sch_1):tp_rsvd_b1" )
			)
			( signal "KR_P0_OCP_RX_DN"
				( objectStatus "@baseboard_fab2_lib.baseboard_fab2(sch_1):kr_p0_ocp_rx_dn" )
			)
			( signal "KR_P0_OCP_RX_DP"
				( objectStatus "@baseboard_fab2_lib.baseboard_fab2(sch_1):kr_p0_ocp_rx_dp" )
			)
			( signal "V_IO_R_J"
				( objectStatus "@baseboard_fab2_lib.baseboard_fab2(sch_1):v_io_r_j" )
			)
			( signal "V_IO_G_J"
				( objectStatus "@baseboard_fab2_lib.baseboard_fab2(sch_1):v_io_g_j" )
			)
			( signal "V_IO_B_J"
				( objectStatus "@baseboard_fab2_lib.baseboard_fab2(sch_1):v_io_b_j" )
			)
			( signal "BMC_VGA_RED"
				( objectStatus "@baseboard_fab2_lib.baseboard_fab2(sch_1):bmc_vga_red" )
			)
			( signal "BMC_VGA_GREEN"
				( objectStatus "@baseboard_fab2_lib.baseboard_fab2(sch_1):bmc_vga_green" )
			)
			( signal "BMC_VGA_BLUE"
				( objectStatus "@baseboard_fab2_lib.baseboard_fab2(sch_1):bmc_vga_blue" )
			)
			( signal "TP_RSVD<0>"
				( objectStatus "@baseboard_fab2_lib.baseboard_fab2(sch_1):tp_rsvd(0)" )
			)
			( signal "TP_SHARED_KR_MDC_0"
				( objectStatus "@baseboard_fab2_lib.baseboard_fab2(sch_1):tp_shared_kr_mdc_0" )
			)
			( signal "TP_SHARED_KR_MDIO_0"
				( objectStatus "@baseboard_fab2_lib.baseboard_fab2(sch_1):tp_shared_kr_mdio_0" )
			)
			( signal "FM_JTAG_PLD_EN_DEBUG"
				( objectStatus "@baseboard_fab2_lib.baseboard_fab2(sch_1):fm_jtag_pld_en_debug" )
			)
			( signal "JTAG_PLD_TCK"
				( objectStatus "@baseboard_fab2_lib.baseboard_fab2(sch_1):jtag_pld_tck" )
			)
			( signal "JTAG_PLD_TDI"
				( objectStatus "@baseboard_fab2_lib.baseboard_fab2(sch_1):jtag_pld_tdi" )
			)
			( signal "JTAG_PLD_TDO"
				( objectStatus "@baseboard_fab2_lib.baseboard_fab2(sch_1):jtag_pld_tdo" )
			)
			( signal "JTAG_PLD_TMS"
				( objectStatus "@baseboard_fab2_lib.baseboard_fab2(sch_1):jtag_pld_tms" )
			)
			( signal "JTAG_TCK"
				( objectStatus "@baseboard_fab2_lib.baseboard_fab2(sch_1):jtag_tck" )
			)
			( signal "JTAG_TCK_R"
				( objectStatus "@baseboard_fab2_lib.baseboard_fab2(sch_1):jtag_tck_r" )
			)
			( signal "JTAG_TDI"
				( objectStatus "@baseboard_fab2_lib.baseboard_fab2(sch_1):jtag_tdi" )
			)
			( signal "JTAG_TDI_R"
				( objectStatus "@baseboard_fab2_lib.baseboard_fab2(sch_1):jtag_tdi_r" )
			)
			( signal "JTAG_TDO"
				( objectStatus "@baseboard_fab2_lib.baseboard_fab2(sch_1):jtag_tdo" )
			)
			( signal "JTAG_TDO_R"
				( objectStatus "@baseboard_fab2_lib.baseboard_fab2(sch_1):jtag_tdo_r" )
			)
			( signal "JTAG_TMS"
				( objectStatus "@baseboard_fab2_lib.baseboard_fab2(sch_1):jtag_tms" )
			)
			( signal "JTAG_TMS_R"
				( objectStatus "@baseboard_fab2_lib.baseboard_fab2(sch_1):jtag_tms_r" )
			)
			( signal "JTAG_TRST_N"
				( objectStatus "@baseboard_fab2_lib.baseboard_fab2(sch_1):jtag_trst_n" )
			)
			( signal "P3V3_STBY_PLD_D"
				( attribute "VOLTAGE" "3.3"
					( Units "uVoltage" "V" 1.000000)
					( Status sAliasFlattened )
					( Origin gFrontEnd )
				)
				( objectStatus "@baseboard_fab2_lib.baseboard_fab2(sch_1):p3v3_stby_pld_d" )
			)
			( signal "FM_MEM_EVENT_FUNC"
				( objectStatus "@baseboard_fab2_lib.baseboard_fab2(sch_1):fm_mem_event_func" )
			)
			( signal "FM_PVCCIO_CPU0_EN"
				( objectStatus "@baseboard_fab2_lib.baseboard_fab2(sch_1):fm_pvccio_cpu0_en" )
			)
			( signal "FM_PVCCIO_CPU1_EN"
				( objectStatus "@baseboard_fab2_lib.baseboard_fab2(sch_1):fm_pvccio_cpu1_en" )
			)
			( signal "FM_PVCCIOMCP_CPU0_EN"
				( objectStatus "@baseboard_fab2_lib.baseboard_fab2(sch_1):fm_pvcciomcp_cpu0_en" )
			)
			( signal "FM_PVCCIOMCP_CPU1_EN"
				( objectStatus "@baseboard_fab2_lib.baseboard_fab2(sch_1):fm_pvcciomcp_cpu1_en" )
			)
			( signal "FM_PVCCMCP_CPU0_EN"
				( objectStatus "@baseboard_fab2_lib.baseboard_fab2(sch_1):fm_pvccmcp_cpu0_en" )
			)
			( signal "FM_PVCCMCP_CPU1_EN"
				( objectStatus "@baseboard_fab2_lib.baseboard_fab2(sch_1):fm_pvccmcp_cpu1_en" )
			)
			( signal "PU_RST_PERST_BIT0"
				( objectStatus "@baseboard_fab2_lib.baseboard_fab2(sch_1):pu_rst_perst_bit0" )
			)
			( signal "PWRGD_P5V"
				( objectStatus "@baseboard_fab2_lib.baseboard_fab2(sch_1):pwrgd_p5v" )
			)
			( signal "PWRGD_PVCCIN_CPU1"
				( objectStatus "@baseboard_fab2_lib.baseboard_fab2(sch_1):pwrgd_pvccin_cpu1" )
			)
			( signal "PWRGD_PVCCIOMCP_CPU0"
				( objectStatus "@baseboard_fab2_lib.baseboard_fab2(sch_1):pwrgd_pvcciomcp_cpu0" )
			)
			( signal "PWRGD_PVCCIOMCP_CPU1"
				( objectStatus "@baseboard_fab2_lib.baseboard_fab2(sch_1):pwrgd_pvcciomcp_cpu1" )
			)
			( signal "PWRGD_PVCCMCP_CPU0"
				( objectStatus "@baseboard_fab2_lib.baseboard_fab2(sch_1):pwrgd_pvccmcp_cpu0" )
			)
			( signal "PWRGD_PVCCMCP_CPU1"
				( objectStatus "@baseboard_fab2_lib.baseboard_fab2(sch_1):pwrgd_pvccmcp_cpu1" )
			)
			( signal "PWRGD_PVNN_P1V05_PCH"
				( objectStatus "@baseboard_fab2_lib.baseboard_fab2(sch_1):pwrgd_pvnn_p1v05_pch" )
			)
			( signal "PWRGD_PVPP_DEF"
				( objectStatus "@baseboard_fab2_lib.baseboard_fab2(sch_1):pwrgd_pvpp_def" )
			)
			( signal "PWRGD_PVPP_GHJ"
				( objectStatus "@baseboard_fab2_lib.baseboard_fab2(sch_1):pwrgd_pvpp_ghj" )
			)
			( signal "PWRGD_PVPP_KLM"
				( objectStatus "@baseboard_fab2_lib.baseboard_fab2(sch_1):pwrgd_pvpp_klm" )
			)
			( signal "PWRGD_PVSA_CPU0"
				( objectStatus "@baseboard_fab2_lib.baseboard_fab2(sch_1):pwrgd_pvsa_cpu0" )
			)
			( signal "PWRGD_PVSA_CPU1"
				( objectStatus "@baseboard_fab2_lib.baseboard_fab2(sch_1):pwrgd_pvsa_cpu1" )
			)
			( signal "PWRGD_PVTT_CPU1"
				( objectStatus "@baseboard_fab2_lib.baseboard_fab2(sch_1):pwrgd_pvtt_cpu1" )
			)
			( signal "RST_CPU0_LVC3_R1_N"
				( objectStatus "@baseboard_fab2_lib.baseboard_fab2(sch_1):rst_cpu0_lvc3_r1_n" )
			)
			( signal "RST_CPU1_LVC3_R1_N"
				( objectStatus "@baseboard_fab2_lib.baseboard_fab2(sch_1):rst_cpu1_lvc3_r1_n" )
			)
			( signal "RST_RSMRST_R_N"
				( objectStatus "@baseboard_fab2_lib.baseboard_fab2(sch_1):rst_rsmrst_r_n" )
			)
			( signal "PVCCIO_CPU0_R"
				( objectStatus "@baseboard_fab2_lib.baseboard_fab2(sch_1):pvccio_cpu0_r" )
			)
			( signal "TP_CPLD1_PB16A_PCLKT2_1"
				( objectStatus "@baseboard_fab2_lib.baseboard_fab2(sch_1):tp_cpld1_pb16a_pclkt2_1" )
			)
			( signal "TP_CPLD1_PB16B_PCLKC2_1"
				( objectStatus "@baseboard_fab2_lib.baseboard_fab2(sch_1):tp_cpld1_pb16b_pclkc2_1" )
			)
			( signal "TP_CPLD1_PB25B_SI_SISPI"
				( objectStatus "@baseboard_fab2_lib.baseboard_fab2(sch_1):tp_cpld1_pb25b_si_sispi" )
			)
			( signal "TP_CPLD1_PB5A_CSSPIN"
				( objectStatus "@baseboard_fab2_lib.baseboard_fab2(sch_1):tp_cpld1_pb5a_csspin" )
			)
			( signal "TP_CPLD1_PB8A_MCLK_CCLK"
				( objectStatus "@baseboard_fab2_lib.baseboard_fab2(sch_1):tp_cpld1_pb8a_mclk_cclk" )
			)
			( signal "TP_CPLD1_PB8B_SO_SPISO"
				( objectStatus "@baseboard_fab2_lib.baseboard_fab2(sch_1):tp_cpld1_pb8b_so_spiso" )
			)
			( signal "FM_CPLD_USB_P0_EN_N"
				( objectStatus "@baseboard_fab2_lib.baseboard_fab2(sch_1):fm_cpld_usb_p0_en_n" )
			)
			( signal "TP_CPLD1_PL11A"
				( objectStatus "@baseboard_fab2_lib.baseboard_fab2(sch_1):tp_cpld1_pl11a" )
			)
			( signal "TP_CPLD1_PL1A_L_GPLLT_FB"
				( objectStatus "@baseboard_fab2_lib.baseboard_fab2(sch_1):tp_cpld1_pl1a_l_gpllt_fb" )
			)
			( signal "TP_CPLD1_PL1B_L_GPLLC_FB"
				( objectStatus "@baseboard_fab2_lib.baseboard_fab2(sch_1):tp_cpld1_pl1b_l_gpllc_fb" )
			)
			( signal "TP_CPLD1_PL2B_L_GPLLC_IN"
				( objectStatus "@baseboard_fab2_lib.baseboard_fab2(sch_1):tp_cpld1_pl2b_l_gpllc_in" )
			)
			( signal "TP_CPLD1_PL7D_PCLKT4_0"
				( objectStatus "@baseboard_fab2_lib.baseboard_fab2(sch_1):tp_cpld1_pl7d_pclkt4_0" )
			)
			( signal "FM_ADR_SMI_GPIO_R_N"
				( objectStatus "@baseboard_fab2_lib.baseboard_fab2(sch_1):fm_adr_smi_gpio_r_n" )
			)
			( signal "FM_P12V_MAIN_SW_EN"
				( objectStatus "@baseboard_fab2_lib.baseboard_fab2(sch_1):fm_p12v_main_sw_en" )
			)
			( signal "FM_P1V8MCP_CPU0_EN"
				( objectStatus "@baseboard_fab2_lib.baseboard_fab2(sch_1):fm_p1v8mcp_cpu0_en" )
			)
			( signal "FM_P1V8MCP_CPU1_EN"
				( objectStatus "@baseboard_fab2_lib.baseboard_fab2(sch_1):fm_p1v8mcp_cpu1_en" )
			)
			( signal "FM_P3V3_CPLD_EN"
				( objectStatus "@baseboard_fab2_lib.baseboard_fab2(sch_1):fm_p3v3_cpld_en" )
			)
			( signal "FM_PLD_DEBUG_MODE_N"
				( objectStatus "@baseboard_fab2_lib.baseboard_fab2(sch_1):fm_pld_debug_mode_n" )
			)
			( signal "FM_PVCCIN_PVCCSA_CPU0_EN_LVC1"
				( objectStatus "@baseboard_fab2_lib.baseboard_fab2(sch_1):fm_pvccin_pvccsa_cpu0_en_lvc1" )
			)
			( signal "FM_PVCCIN_PVCCSA_CPU1_EN_LVC1"
				( objectStatus "@baseboard_fab2_lib.baseboard_fab2(sch_1):fm_pvccin_pvccsa_cpu1_en_lvc1" )
			)
			( signal "FM_PVDDQ_ABC_EN"
				( objectStatus "@baseboard_fab2_lib.baseboard_fab2(sch_1):fm_pvddq_abc_en" )
			)
			( signal "FM_PVDDQ_DEF_EN"
				( objectStatus "@baseboard_fab2_lib.baseboard_fab2(sch_1):fm_pvddq_def_en" )
			)
			( signal "FM_PVDDQ_GHJ_EN"
				( objectStatus "@baseboard_fab2_lib.baseboard_fab2(sch_1):fm_pvddq_ghj_en" )
			)
			( signal "FM_PVDDQ_KLM_EN"
				( objectStatus "@baseboard_fab2_lib.baseboard_fab2(sch_1):fm_pvddq_klm_en" )
			)
			( signal "FM_PVPP_CPU0_EN"
				( objectStatus "@baseboard_fab2_lib.baseboard_fab2(sch_1):fm_pvpp_cpu0_en" )
			)
			( signal "FM_PVPP_CPU1_EN"
				( objectStatus "@baseboard_fab2_lib.baseboard_fab2(sch_1):fm_pvpp_cpu1_en" )
			)
			( signal "FM_UV_ADR_TRIGGER_N"
				( objectStatus "@baseboard_fab2_lib.baseboard_fab2(sch_1):fm_uv_adr_trigger_n" )
			)
			( signal "PU_FAB2_MARKER_CPLD"
				( objectStatus "@baseboard_fab2_lib.baseboard_fab2(sch_1):pu_fab2_marker_cpld" )
			)
			( signal "PU_RST_PERST_BIT1"
				( objectStatus "@baseboard_fab2_lib.baseboard_fab2(sch_1):pu_rst_perst_bit1" )
			)
			( signal "PU_THERMTRIP_FORCE_N"
				( objectStatus "@baseboard_fab2_lib.baseboard_fab2(sch_1):pu_thermtrip_force_n" )
			)
			( signal "PWRGD_P12V_MAIN"
				( objectStatus "@baseboard_fab2_lib.baseboard_fab2(sch_1):pwrgd_p12v_main" )
			)
			( signal "PWRGD_P1V15_BMC_STBY"
				( objectStatus "@baseboard_fab2_lib.baseboard_fab2(sch_1):pwrgd_p1v15_bmc_stby" )
			)
			( signal "PWRGD_P1V8MCP_CPU0"
				( objectStatus "@baseboard_fab2_lib.baseboard_fab2(sch_1):pwrgd_p1v8mcp_cpu0" )
			)
			( signal "PWRGD_P1V8MCP_CPU1"
				( objectStatus "@baseboard_fab2_lib.baseboard_fab2(sch_1):pwrgd_p1v8mcp_cpu1" )
			)
			( signal "PWRGD_PVCCIO_CPU1"
				( objectStatus "@baseboard_fab2_lib.baseboard_fab2(sch_1):pwrgd_pvccio_cpu1" )
			)
			( signal "PWRGD_PVTT_CPU0"
				( objectStatus "@baseboard_fab2_lib.baseboard_fab2(sch_1):pwrgd_pvtt_cpu0" )
			)
			( signal "SGPIO_BMC_DIN_R"
				( objectStatus "@baseboard_fab2_lib.baseboard_fab2(sch_1):sgpio_bmc_din_r" )
			)
			( signal "TP_CPLD1_PR10C"
				( objectStatus "@baseboard_fab2_lib.baseboard_fab2(sch_1):tp_cpld1_pr10c" )
			)
			( signal "TP_CPLD1_PR11B"
				( objectStatus "@baseboard_fab2_lib.baseboard_fab2(sch_1):tp_cpld1_pr11b" )
			)
			( signal "TP_CPLD1_PR12D"
				( objectStatus "@baseboard_fab2_lib.baseboard_fab2(sch_1):tp_cpld1_pr12d" )
			)
			( signal "TP_CPLD1_PR7A_PCLKT1_0"
				( objectStatus "@baseboard_fab2_lib.baseboard_fab2(sch_1):tp_cpld1_pr7a_pclkt1_0" )
			)
			( signal "TP_CPLD1_PR7B_PCLKC1_0"
				( objectStatus "@baseboard_fab2_lib.baseboard_fab2(sch_1):tp_cpld1_pr7b_pclkc1_0" )
			)
			( signal "TP_CPLD1_PR7C"
				( objectStatus "@baseboard_fab2_lib.baseboard_fab2(sch_1):tp_cpld1_pr7c" )
			)
			( signal "TP_CPLD1_PR7D"
				( objectStatus "@baseboard_fab2_lib.baseboard_fab2(sch_1):tp_cpld1_pr7d" )
			)
			( signal "TP_CPLD1_PR9A"
				( objectStatus "@baseboard_fab2_lib.baseboard_fab2(sch_1):tp_cpld1_pr9a" )
			)
			( signal "TP_CPLD1_PR9C"
				( objectStatus "@baseboard_fab2_lib.baseboard_fab2(sch_1):tp_cpld1_pr9c" )
			)
			( signal "TP_CPLD1_PR9D"
				( objectStatus "@baseboard_fab2_lib.baseboard_fab2(sch_1):tp_cpld1_pr9d" )
			)
			( signal "TP_CPLD1_PT11A"
				( objectStatus "@baseboard_fab2_lib.baseboard_fab2(sch_1):tp_cpld1_pt11a" )
			)
			( signal "TP_CPLD1_PT11B"
				( objectStatus "@baseboard_fab2_lib.baseboard_fab2(sch_1):tp_cpld1_pt11b" )
			)
			( signal "TP_CPLD1_PT13A"
				( objectStatus "@baseboard_fab2_lib.baseboard_fab2(sch_1):tp_cpld1_pt13a" )
			)
			( signal "TP_CPLD1_PT16B"
				( objectStatus "@baseboard_fab2_lib.baseboard_fab2(sch_1):tp_cpld1_pt16b" )
			)
			( signal "TP_CPLD1_PT17B_PCLKC0_1"
				( objectStatus "@baseboard_fab2_lib.baseboard_fab2(sch_1):tp_cpld1_pt17b_pclkc0_1" )
			)
			( signal "TP_CPLD1_PT17C"
				( objectStatus "@baseboard_fab2_lib.baseboard_fab2(sch_1):tp_cpld1_pt17c" )
			)
			( signal "TP_CPLD1_PT19D"
				( objectStatus "@baseboard_fab2_lib.baseboard_fab2(sch_1):tp_cpld1_pt19d" )
			)
			( signal "TP_CPLD1_PT20A"
				( objectStatus "@baseboard_fab2_lib.baseboard_fab2(sch_1):tp_cpld1_pt20a" )
			)
			( signal "TP_CPLD1_PT20B"
				( objectStatus "@baseboard_fab2_lib.baseboard_fab2(sch_1):tp_cpld1_pt20b" )
			)
			( signal "TP_CPLD1_PT22C"
				( objectStatus "@baseboard_fab2_lib.baseboard_fab2(sch_1):tp_cpld1_pt22c" )
			)
			( signal "TP_CPLD1_PT22D"
				( objectStatus "@baseboard_fab2_lib.baseboard_fab2(sch_1):tp_cpld1_pt22d" )
			)
			( signal "TP_CPLD1_PT24B"
				( objectStatus "@baseboard_fab2_lib.baseboard_fab2(sch_1):tp_cpld1_pt24b" )
			)
			( signal "TP_CPLD1_PT24C_INITN"
				( objectStatus "@baseboard_fab2_lib.baseboard_fab2(sch_1):tp_cpld1_pt24c_initn" )
			)
			( signal "TP_CPLD1_PT24D_DONE"
				( objectStatus "@baseboard_fab2_lib.baseboard_fab2(sch_1):tp_cpld1_pt24d_done" )
			)
			( signal "VR_PVCCIOMCP_CPU1_XADDR1"
				( objectStatus "@baseboard_fab2_lib.baseboard_fab2(sch_1):vr_pvcciomcp_cpu1_xaddr1" )
			)
			( signal "VR_PVCCMCP_CPU1_XADDR2"
				( objectStatus "@baseboard_fab2_lib.baseboard_fab2(sch_1):vr_pvccmcp_cpu1_xaddr2" )
			)
			( signal "VR_PVCCIOMCP_CPU0_XADDR1"
				( objectStatus "@baseboard_fab2_lib.baseboard_fab2(sch_1):vr_pvcciomcp_cpu0_xaddr1" )
			)
			( signal "VR_PVCCMCP_CPU0_XADDR2"
				( objectStatus "@baseboard_fab2_lib.baseboard_fab2(sch_1):vr_pvccmcp_cpu0_xaddr2" )
			)
			( signal "A_ADM1085_CEXT"
				( objectStatus "@baseboard_fab2_lib.baseboard_fab2(sch_1):a_adm1085_cext" )
			)
			( signal "A_PG_P12V_MAIN"
				( objectStatus "@baseboard_fab2_lib.baseboard_fab2(sch_1):a_pg_p12v_main" )
			)
			( signal "A_PG_P5V"
				( objectStatus "@baseboard_fab2_lib.baseboard_fab2(sch_1):a_pg_p5v" )
			)
			( signal "P3V_BAT_SOURCE"
				( attribute "VOLTAGE" "+3 V"
					( Units "uVoltage" "V" 1.000000)
					( Status sAliasFlattened )
					( Origin gFrontEnd )
				)
				( objectStatus "@baseboard_fab2_lib.baseboard_fab2(sch_1):p3v_bat_source" )
			)
			( signal "PWRGD_P12V_HSC"
				( objectStatus "@baseboard_fab2_lib.baseboard_fab2(sch_1):pwrgd_p12v_hsc" )
			)
			( signal "PWRGD_P12V_HSC_DLY_R"
				( objectStatus "@baseboard_fab2_lib.baseboard_fab2(sch_1):pwrgd_p12v_hsc_dly_r" )
			)
			( signal "PWRGD_P12V_MAIN_R"
				( objectStatus "@baseboard_fab2_lib.baseboard_fab2(sch_1):pwrgd_p12v_main_r" )
			)
			( signal "PWRGD_P3V3_R1"
				( objectStatus "@baseboard_fab2_lib.baseboard_fab2(sch_1):pwrgd_p3v3_r1" )
			)
			( signal "PWRGD_P5V_N"
				( objectStatus "@baseboard_fab2_lib.baseboard_fab2(sch_1):pwrgd_p5v_n" )
			)
			( signal "PWRGD_P5V_R"
				( objectStatus "@baseboard_fab2_lib.baseboard_fab2(sch_1):pwrgd_p5v_r" )
			)
			( signal "VSENSE_P12V_ADM1085"
				( objectStatus "@baseboard_fab2_lib.baseboard_fab2(sch_1):vsense_p12v_adm1085" )
			)
			( signal "VR_PVDDQ_ABC_AIINSEN"
				( objectStatus "@baseboard_fab2_lib.baseboard_fab2(sch_1):vr_pvddq_abc_aiinsen" )
			)
			( signal "PWRGD_PVDDQ_DEF_N"
				( objectStatus "@baseboard_fab2_lib.baseboard_fab2(sch_1):pwrgd_pvddq_def_n" )
			)
			( signal "VR_PVDDQ_DEF_AIINSEN"
				( objectStatus "@baseboard_fab2_lib.baseboard_fab2(sch_1):vr_pvddq_def_aiinsen" )
			)
			( signal "P12V_NVDIMM_KLM_D"
				( objectStatus "@baseboard_fab2_lib.baseboard_fab2(sch_1):p12v_nvdimm_klm_d" )
			)
			( signal "VR_PVDDQ_GHJ_AIINSEN"
				( objectStatus "@baseboard_fab2_lib.baseboard_fab2(sch_1):vr_pvddq_ghj_aiinsen" )
			)
			( signal "P12V_NVDIMM_GHJ_D"
				( objectStatus "@baseboard_fab2_lib.baseboard_fab2(sch_1):p12v_nvdimm_ghj_d" )
			)
			( signal "VR_PVDDQ_KLM_AIINSEN"
				( objectStatus "@baseboard_fab2_lib.baseboard_fab2(sch_1):vr_pvddq_klm_aiinsen" )
			)
			( signal "P12V_NVDIMM_DEF_D"
				( objectStatus "@baseboard_fab2_lib.baseboard_fab2(sch_1):p12v_nvdimm_def_d" )
			)
			( signal "P12V_FAN_SWITCH_G"
				( attribute "VOLTAGE" "+5V"
					( Units "uVoltage" "V" 1.000000)
					( Status sAliasFlattened )
					( Origin gFrontEnd )
				)
				( objectStatus "@baseboard_fab2_lib.baseboard_fab2(sch_1):p12v_fan_switch_g" )
			)
			( signal "P12V_SWITCH_G"
				( attribute "VOLTAGE" "+3.3V"
					( Units "uVoltage" "V" 1.000000)
					( Status sAliasFlattened )
					( Origin gFrontEnd )
				)
				( objectStatus "@baseboard_fab2_lib.baseboard_fab2(sch_1):p12v_switch_g" )
			)
			( signal "P3V3_SWITCH_G"
				( attribute "VOLTAGE" "3.3"
					( Units "uVoltage" "V" 1.000000)
					( Status sAliasFlattened )
					( Origin gFrontEnd )
				)
				( objectStatus "@baseboard_fab2_lib.baseboard_fab2(sch_1):p3v3_switch_g" )
			)
			( signal "P5V_SWITCH_G"
				( attribute "VOLTAGE" "+5V"
					( Units "uVoltage" "V" 1.000000)
					( Status sAliasFlattened )
					( Origin gFrontEnd )
				)
				( objectStatus "@baseboard_fab2_lib.baseboard_fab2(sch_1):p5v_switch_g" )
			)
			( signal "TP_SLG55021_P12V_FAN_8"
				( objectStatus "@baseboard_fab2_lib.baseboard_fab2(sch_1):tp_slg55021_p12v_fan_8" )
			)
			( signal "TP_SLG55021_P12V_MAIN_8"
				( objectStatus "@baseboard_fab2_lib.baseboard_fab2(sch_1):tp_slg55021_p12v_main_8" )
			)
			( signal "TP_SLG55021_P3V3_8"
				( objectStatus "@baseboard_fab2_lib.baseboard_fab2(sch_1):tp_slg55021_p3v3_8" )
			)
			( signal "TP_SLG55021_P5V_8"
				( objectStatus "@baseboard_fab2_lib.baseboard_fab2(sch_1):tp_slg55021_p5v_8" )
			)
			( signal "A_HSC_CSOUT"
				( objectStatus "@baseboard_fab2_lib.baseboard_fab2(sch_1):a_hsc_csout" )
			)
			( signal "A_HSC_GATE"
				( objectStatus "@baseboard_fab2_lib.baseboard_fab2(sch_1):a_hsc_gate" )
			)
			( signal "A_HSC_HIGH_EN"
				( objectStatus "@baseboard_fab2_lib.baseboard_fab2(sch_1):a_hsc_high_en" )
			)
			( signal "A_HSC_HSN"
				( objectStatus "@baseboard_fab2_lib.baseboard_fab2(sch_1):a_hsc_hsn" )
			)
			( signal "A_HSC_HSP"
				( objectStatus "@baseboard_fab2_lib.baseboard_fab2(sch_1):a_hsc_hsp" )
			)
			( signal "A_HSC_ISET"
				( objectStatus "@baseboard_fab2_lib.baseboard_fab2(sch_1):a_hsc_iset" )
			)
			( signal "A_HSC_ISET_S"
				( objectStatus "@baseboard_fab2_lib.baseboard_fab2(sch_1):a_hsc_iset_s" )
			)
			( signal "A_HSC_ISET_S2"
				( objectStatus "@baseboard_fab2_lib.baseboard_fab2(sch_1):a_hsc_iset_s2" )
			)
			( signal "A_HSC_ISTART"
				( objectStatus "@baseboard_fab2_lib.baseboard_fab2(sch_1):a_hsc_istart" )
			)
			( signal "A_HSC_LOW_EN"
				( objectStatus "@baseboard_fab2_lib.baseboard_fab2(sch_1):a_hsc_low_en" )
			)
			( signal "A_HSC_MON"
				( objectStatus "@baseboard_fab2_lib.baseboard_fab2(sch_1):a_hsc_mon" )
			)
			( signal "A_HSC_MOP"
				( objectStatus "@baseboard_fab2_lib.baseboard_fab2(sch_1):a_hsc_mop" )
			)
			( signal "A_HSC_OCP_SEL"
				( objectStatus "@baseboard_fab2_lib.baseboard_fab2(sch_1):a_hsc_ocp_sel" )
			)
			( signal "A_HSC_OV"
				( objectStatus "@baseboard_fab2_lib.baseboard_fab2(sch_1):a_hsc_ov" )
			)
			( signal "A_HSC_PSET"
				( objectStatus "@baseboard_fab2_lib.baseboard_fab2(sch_1):a_hsc_pset" )
			)
			( signal "A_HSC_PWGIN"
				( objectStatus "@baseboard_fab2_lib.baseboard_fab2(sch_1):a_hsc_pwgin" )
			)
			( signal "A_HSC_TEMP"
				( objectStatus "@baseboard_fab2_lib.baseboard_fab2(sch_1):a_hsc_temp" )
			)
			( signal "A_HSC_TIMER"
				( objectStatus "@baseboard_fab2_lib.baseboard_fab2(sch_1):a_hsc_timer" )
			)
			( signal "A_HSC_UV"
				( objectStatus "@baseboard_fab2_lib.baseboard_fab2(sch_1):a_hsc_uv" )
			)
			( signal "A_HSC_VCAP"
				( objectStatus "@baseboard_fab2_lib.baseboard_fab2(sch_1):a_hsc_vcap" )
			)
			( signal "A_HSC_VOUT"
				( objectStatus "@baseboard_fab2_lib.baseboard_fab2(sch_1):a_hsc_vout" )
			)
			( signal "AGND_HSC"
				( attribute "VOLTAGE" "0"
					( Units "uVoltage" "V" 1.000000)
					( Status sAliasFlattened )
					( Origin gFrontEnd )
				)
				( objectStatus "@baseboard_fab2_lib.baseboard_fab2(sch_1):agnd_hsc" )
			)
			( signal "FM_P12V_HSC_ADR1"
				( objectStatus "@baseboard_fab2_lib.baseboard_fab2(sch_1):fm_p12v_hsc_adr1" )
			)
			( signal "FM_P12V_HSC_ADR2"
				( objectStatus "@baseboard_fab2_lib.baseboard_fab2(sch_1):fm_p12v_hsc_adr2" )
			)
			( signal "IRQ_HSC_FAULT_R_N"
				( objectStatus "@baseboard_fab2_lib.baseboard_fab2(sch_1):irq_hsc_fault_r_n" )
			)
			( signal "P12V_HSC_VCC"
				( attribute "VOLTAGE" "+12V"
					( Units "uVoltage" "V" 1.000000)
					( Status sAliasFlattened )
					( Origin gFrontEnd )
				)
				( objectStatus "@baseboard_fab2_lib.baseboard_fab2(sch_1):p12v_hsc_vcc" )
			)
			( signal "PD_HSC_RETRY_N"
				( objectStatus "@baseboard_fab2_lib.baseboard_fab2(sch_1):pd_hsc_retry_n" )
			)
			( signal "PWRGD_P12V_R"
				( objectStatus "@baseboard_fab2_lib.baseboard_fab2(sch_1):pwrgd_p12v_r" )
			)
			( signal "SMB_3V3SB_HSC_SCL_R"
				( objectStatus "@baseboard_fab2_lib.baseboard_fab2(sch_1):smb_3v3sb_hsc_scl_r" )
			)
			( signal "SMB_3V3SB_HSC_SDA_R"
				( objectStatus "@baseboard_fab2_lib.baseboard_fab2(sch_1):smb_3v3sb_hsc_sda_r" )
			)
			( signal "TP_HSC_ALERT2_N"
				( objectStatus "@baseboard_fab2_lib.baseboard_fab2(sch_1):tp_hsc_alert2_n" )
			)
			( signal "TP_HSC_MCLK"
				( objectStatus "@baseboard_fab2_lib.baseboard_fab2(sch_1):tp_hsc_mclk" )
			)
			( signal "TP_HSC_MDAT"
				( objectStatus "@baseboard_fab2_lib.baseboard_fab2(sch_1):tp_hsc_mdat" )
			)
			( signal "TP_HSC_SPISSN"
				( objectStatus "@baseboard_fab2_lib.baseboard_fab2(sch_1):tp_hsc_spissn" )
			)
			( signal "A_HSC_C"
				( objectStatus "@baseboard_fab2_lib.baseboard_fab2(sch_1):a_hsc_c" )
			)
			( signal "A_HSC_GATE1_R"
				( objectStatus "@baseboard_fab2_lib.baseboard_fab2(sch_1):a_hsc_gate1_r" )
			)
			( signal "A_HSC_GATE2_R"
				( objectStatus "@baseboard_fab2_lib.baseboard_fab2(sch_1):a_hsc_gate2_r" )
			)
			( signal "A_HSC_GATE3_R"
				( objectStatus "@baseboard_fab2_lib.baseboard_fab2(sch_1):a_hsc_gate3_r" )
			)
			( signal "A_HSC_HIGH"
				( objectStatus "@baseboard_fab2_lib.baseboard_fab2(sch_1):a_hsc_high" )
			)
			( signal "A_HSC_INAP"
				( objectStatus "@baseboard_fab2_lib.baseboard_fab2(sch_1):a_hsc_inap" )
			)
			( signal "A_HSC_LOW"
				( objectStatus "@baseboard_fab2_lib.baseboard_fab2(sch_1):a_hsc_low" )
			)
			( signal "A_HSC_LOW_DRAIN"
				( objectStatus "@baseboard_fab2_lib.baseboard_fab2(sch_1):a_hsc_low_drain" )
			)
			( signal "A_HSC_LOW_GATE"
				( objectStatus "@baseboard_fab2_lib.baseboard_fab2(sch_1):a_hsc_low_gate" )
			)
			( signal "A_HSC_TIMER_R"
				( objectStatus "@baseboard_fab2_lib.baseboard_fab2(sch_1):a_hsc_timer_r" )
			)
			( signal "A_P12V_STBY_ADR_TRIGGER"
				( objectStatus "@baseboard_fab2_lib.baseboard_fab2(sch_1):a_p12v_stby_adr_trigger" )
			)
			( signal "A_P12V_STBY_FP_TRIGGER"
				( objectStatus "@baseboard_fab2_lib.baseboard_fab2(sch_1):a_p12v_stby_fp_trigger" )
			)
			( signal "A_P12V_STBY_FPH_GATE"
				( objectStatus "@baseboard_fab2_lib.baseboard_fab2(sch_1):a_p12v_stby_fph_gate" )
			)
			( signal "FM_OC_DETECT_EN"
				( objectStatus "@baseboard_fab2_lib.baseboard_fab2(sch_1):fm_oc_detect_en" )
			)
			( signal "P12V_HSC_SENN0"
				( attribute "VOLTAGE" "+12V"
					( Units "uVoltage" "V" 1.000000)
					( Status sAliasFlattened )
					( Origin gFrontEnd )
				)
				( objectStatus "@baseboard_fab2_lib.baseboard_fab2(sch_1):p12v_hsc_senn0" )
			)
			( signal "P12V_HSC_SENN1"
				( attribute "VOLTAGE" "+12V"
					( Units "uVoltage" "V" 1.000000)
					( Status sAliasFlattened )
					( Origin gFrontEnd )
				)
				( objectStatus "@baseboard_fab2_lib.baseboard_fab2(sch_1):p12v_hsc_senn1" )
			)
			( signal "P12V_HSC_SENP0"
				( attribute "VOLTAGE" "+12V"
					( Units "uVoltage" "V" 1.000000)
					( Status sAliasFlattened )
					( Origin gFrontEnd )
				)
				( objectStatus "@baseboard_fab2_lib.baseboard_fab2(sch_1):p12v_hsc_senp0" )
			)
			( signal "P12V_HSC_SENP1"
				( attribute "VOLTAGE" "+12V"
					( Units "uVoltage" "V" 1.000000)
					( Status sAliasFlattened )
					( Origin gFrontEnd )
				)
				( objectStatus "@baseboard_fab2_lib.baseboard_fab2(sch_1):p12v_hsc_senp1" )
			)
			( signal "P12V_MB0_SW"
				( attribute "VOLTAGE" "+12V"
					( Units "uVoltage" "V" 1.000000)
					( Status sAliasFlattened )
					( Origin gFrontEnd )
				)
				( objectStatus "@baseboard_fab2_lib.baseboard_fab2(sch_1):p12v_mb0_sw" )
			)
			( signal "A_TSENSE_PVCCIN_CPU0"
				( objectStatus "@baseboard_fab2_lib.baseboard_fab2(sch_1):a_tsense_pvccin_cpu0" )
			)
			( signal "A_TSENSE_PVSA_CPU0"
				( objectStatus "@baseboard_fab2_lib.baseboard_fab2(sch_1):a_tsense_pvsa_cpu0" )
			)
			( signal "IRQ_PVCCIN_CPU0_VRHOT_LVC3_R_N"
				( objectStatus "@baseboard_fab2_lib.baseboard_fab2(sch_1):irq_pvccin_cpu0_vrhot_lvc3_r_n" )
			)
			( signal "ISENSE_PVCCIN_CPU0_PH1_IMON"
				( objectStatus "@baseboard_fab2_lib.baseboard_fab2(sch_1):isense_pvccin_cpu0_ph1_imon" )
			)
			( signal "ISENSE_PVCCIN_CPU0_PH2_IMON"
				( objectStatus "@baseboard_fab2_lib.baseboard_fab2(sch_1):isense_pvccin_cpu0_ph2_imon" )
			)
			( signal "ISENSE_PVCCIN_CPU0_PH3_IMON"
				( objectStatus "@baseboard_fab2_lib.baseboard_fab2(sch_1):isense_pvccin_cpu0_ph3_imon" )
			)
			( signal "ISENSE_PVCCIN_CPU0_PH4_IMON"
				( objectStatus "@baseboard_fab2_lib.baseboard_fab2(sch_1):isense_pvccin_cpu0_ph4_imon" )
			)
			( signal "ISENSE_PVCCIN_CPU0_PH5_IMON"
				( objectStatus "@baseboard_fab2_lib.baseboard_fab2(sch_1):isense_pvccin_cpu0_ph5_imon" )
			)
			( signal "ISENSE_PVSA_CPU0_IMON"
				( objectStatus "@baseboard_fab2_lib.baseboard_fab2(sch_1):isense_pvsa_cpu0_imon" )
			)
			( signal "PU_VR_PVCCIN_CPU0_FLT1_SMBALT_N"
				( objectStatus "@baseboard_fab2_lib.baseboard_fab2(sch_1):pu_vr_pvccin_cpu0_flt1_smbalt_n_imon" )
			)
			( signal "PU_VR_PVCCIN_CPU0_IMON"
				( objectStatus "@baseboard_fab2_lib.baseboard_fab2(sch_1):pu_vr_pvccin_cpu0_imon" )
			)
			( signal "PWRGD_PVSA_CPU0_R"
				( objectStatus "@baseboard_fab2_lib.baseboard_fab2(sch_1):pwrgd_pvsa_cpu0_r" )
			)
			( signal "SVID_VALERT_VCCIN_CPU0"
				( objectStatus "@baseboard_fab2_lib.baseboard_fab2(sch_1):svid_valert_vccin_cpu0" )
			)
			( signal "SVID_VCLK_PVCCIN_CPU0"
				( objectStatus "@baseboard_fab2_lib.baseboard_fab2(sch_1):svid_vclk_pvccin_cpu0" )
			)
			( signal "SVID_VDIO_PVCCIN_CPU0"
				( objectStatus "@baseboard_fab2_lib.baseboard_fab2(sch_1):svid_vdio_pvccin_cpu0" )
			)
			( signal "VR_FET_SW_P12V_STBY_PVCCIN_CPU0"
				( objectStatus "@baseboard_fab2_lib.baseboard_fab2(sch_1):vr_fet_sw_p12v_stby_pvccin_cpu0" )
			)
			( signal "VR_PVCCIN_CPU0_AIREF1"
				( objectStatus "@baseboard_fab2_lib.baseboard_fab2(sch_1):vr_pvccin_cpu0_airef1" )
			)
			( signal "VR_PVCCIN_CPU0_AIREF2"
				( objectStatus "@baseboard_fab2_lib.baseboard_fab2(sch_1):vr_pvccin_cpu0_airef2" )
			)
			( signal "VR_PVCCIN_CPU0_AIREF3"
				( objectStatus "@baseboard_fab2_lib.baseboard_fab2(sch_1):vr_pvccin_cpu0_airef3" )
			)
			( signal "VR_PVCCIN_CPU0_AIREF4"
				( objectStatus "@baseboard_fab2_lib.baseboard_fab2(sch_1):vr_pvccin_cpu0_airef4" )
			)
			( signal "VR_PVCCIN_CPU0_AIREF5"
				( objectStatus "@baseboard_fab2_lib.baseboard_fab2(sch_1):vr_pvccin_cpu0_airef5" )
			)
			( signal "VR_PVCCIN_CPU0_AVINSEN"
				( attribute "VOLTAGE" "0.8"
					( Units "uVoltage" "V" 1.000000)
					( Status sAliasFlattened )
					( Origin gFrontEnd )
				)
				( objectStatus "@baseboard_fab2_lib.baseboard_fab2(sch_1):vr_pvccin_cpu0_avinsen" )
			)
			( signal "VR_PVCCIN_CPU0_PWM1"
				( attribute "VOLTAGE" "3.6"
					( Units "uVoltage" "V" 1.000000)
					( Status sAliasFlattened )
					( Origin gFrontEnd )
				)
				( objectStatus "@baseboard_fab2_lib.baseboard_fab2(sch_1):vr_pvccin_cpu0_pwm1" )
			)
			( signal "VR_PVCCIN_CPU0_PWM2"
				( attribute "VOLTAGE" "3.6"
					( Units "uVoltage" "V" 1.000000)
					( Status sAliasFlattened )
					( Origin gFrontEnd )
				)
				( objectStatus "@baseboard_fab2_lib.baseboard_fab2(sch_1):vr_pvccin_cpu0_pwm2" )
			)
			( signal "VR_PVCCIN_CPU0_PWM3"
				( attribute "VOLTAGE" "3.6"
					( Units "uVoltage" "V" 1.000000)
					( Status sAliasFlattened )
					( Origin gFrontEnd )
				)
				( objectStatus "@baseboard_fab2_lib.baseboard_fab2(sch_1):vr_pvccin_cpu0_pwm3" )
			)
			( signal "VR_PVCCIN_CPU0_PWM4"
				( attribute "VOLTAGE" "3.6"
					( Units "uVoltage" "V" 1.000000)
					( Status sAliasFlattened )
					( Origin gFrontEnd )
				)
				( objectStatus "@baseboard_fab2_lib.baseboard_fab2(sch_1):vr_pvccin_cpu0_pwm4" )
			)
			( signal "VR_PVCCIN_CPU0_PWM5"
				( attribute "VOLTAGE" "3.6"
					( Units "uVoltage" "V" 1.000000)
					( Status sAliasFlattened )
					( Origin gFrontEnd )
				)
				( objectStatus "@baseboard_fab2_lib.baseboard_fab2(sch_1):vr_pvccin_cpu0_pwm5" )
			)
			( signal "VR_PVCCIN_CPU0_VD12"
				( objectStatus "@baseboard_fab2_lib.baseboard_fab2(sch_1):vr_pvccin_cpu0_vd12" )
			)
			( signal "VR_PVCCIN_CPU0_VDD"
				( attribute "VOLTAGE" "3.3"
					( Units "uVoltage" "V" 1.000000)
					( Status sAliasFlattened )
					( Origin gFrontEnd )
				)
				( objectStatus "@baseboard_fab2_lib.baseboard_fab2(sch_1):vr_pvccin_cpu0_vdd" )
			)
			( signal "VR_PVCCIN_CPU0_VREN"
				( attribute "VOLTAGE" "3.3"
					( Units "uVoltage" "V" 1.000000)
					( Status sAliasFlattened )
					( Origin gFrontEnd )
				)
				( objectStatus "@baseboard_fab2_lib.baseboard_fab2(sch_1):vr_pvccin_cpu0_vren" )
			)
			( signal "VR_PVCCIN_CPU0_XADDR1"
				( attribute "VOLTAGE" "3.3"
					( Units "uVoltage" "V" 1.000000)
					( Status sAliasFlattened )
					( Origin gFrontEnd )
				)
				( objectStatus "@baseboard_fab2_lib.baseboard_fab2(sch_1):vr_pvccin_cpu0_xaddr1" )
			)
			( signal "VR_PVCCIN_CPU0_XADDR2"
				( attribute "VOLTAGE" "3.3"
					( Units "uVoltage" "V" 1.000000)
					( Status sAliasFlattened )
					( Origin gFrontEnd )
				)
				( objectStatus "@baseboard_fab2_lib.baseboard_fab2(sch_1):vr_pvccin_cpu0_xaddr2" )
			)
			( signal "VR_PVSA_CPU0_BIREF1"
				( objectStatus "@baseboard_fab2_lib.baseboard_fab2(sch_1):vr_pvsa_cpu0_biref1" )
			)
			( signal "VR_PVSA_CPU0_PWM"
				( objectStatus "@baseboard_fab2_lib.baseboard_fab2(sch_1):vr_pvsa_cpu0_pwm" )
			)
			( signal "VR_VRRDY_PVCCIN_CPU0"
				( attribute "VOLTAGE" "3.3"
					( Units "uVoltage" "V" 1.000000)
					( Status sAliasFlattened )
					( Origin gFrontEnd )
				)
				( objectStatus "@baseboard_fab2_lib.baseboard_fab2(sch_1):vr_vrrdy_pvccin_cpu0" )
			)
			( signal "VSENSE_PVCCIN_CPU0_AVSP"
				( objectStatus "@baseboard_fab2_lib.baseboard_fab2(sch_1):vsense_pvccin_cpu0_avsp" )
			)
			( signal "VSENSE_PVCCIN_CPU0_N"
				( objectStatus "@baseboard_fab2_lib.baseboard_fab2(sch_1):vsense_pvccin_cpu0_n" )
			)
			( signal "VSENSE_PVCCIN_CPU0_P"
				( objectStatus "@baseboard_fab2_lib.baseboard_fab2(sch_1):vsense_pvccin_cpu0_p" )
			)
			( signal "VSENSE_PVSA_CPU0_BVSP"
				( objectStatus "@baseboard_fab2_lib.baseboard_fab2(sch_1):vsense_pvsa_cpu0_bvsp" )
			)
			( signal "VSENSE_PVSA_CPU0_N"
				( objectStatus "@baseboard_fab2_lib.baseboard_fab2(sch_1):vsense_pvsa_cpu0_n" )
			)
			( signal "VSENSE_PVSA_CPU0_P"
				( objectStatus "@baseboard_fab2_lib.baseboard_fab2(sch_1):vsense_pvsa_cpu0_p" )
			)
			( signal "TP_PVCCIN_CPU0_PH1_GL_0"
				( objectStatus "@baseboard_fab2_lib.baseboard_fab2(sch_1):tp_pvccin_cpu0_ph1_gl_0" )
			)
			( signal "TP_PVCCIN_CPU0_PH1_GL_1"
				( objectStatus "@baseboard_fab2_lib.baseboard_fab2(sch_1):tp_pvccin_cpu0_ph1_gl_1" )
			)
			( signal "TP_PVCCIN_CPU0_PH2_GL_0"
				( objectStatus "@baseboard_fab2_lib.baseboard_fab2(sch_1):tp_pvccin_cpu0_ph2_gl_0" )
			)
			( signal "TP_PVCCIN_CPU0_PH2_GL_1"
				( objectStatus "@baseboard_fab2_lib.baseboard_fab2(sch_1):tp_pvccin_cpu0_ph2_gl_1" )
			)
			( signal "VR_PVCCIN_CPU0_PH1_BOOT"
				( objectStatus "@baseboard_fab2_lib.baseboard_fab2(sch_1):vr_pvccin_cpu0_ph1_boot" )
			)
			( signal "VR_PVDDQ_DEF_PH1_SW_RC"
				( objectStatus "@baseboard_fab2_lib.baseboard_fab2(sch_1):vr_pvddq_def_ph1_sw_rc" )
			)
			( signal "VR_PVCCIN_CPU0_PH1_OCSET"
				( objectStatus "@baseboard_fab2_lib.baseboard_fab2(sch_1):vr_pvccin_cpu0_ph1_ocset" )
			)
			( signal "VR_PVCCIN_CPU0_PH1_PHASE"
				( attribute "VOLTAGE" "5"
					( Units "uVoltage" "V" 1.000000)
					( Status sAliasFlattened )
					( Origin gFrontEnd )
				)
				( objectStatus "@baseboard_fab2_lib.baseboard_fab2(sch_1):vr_pvccin_cpu0_ph1_phase" )
			)
			( signal "VR_PVCCIN_CPU0_PH1_VCIN"
				( attribute "VOLTAGE" "5"
					( Units "uVoltage" "V" 1.000000)
					( Status sAliasFlattened )
					( Origin gFrontEnd )
				)
				( objectStatus "@baseboard_fab2_lib.baseboard_fab2(sch_1):vr_pvccin_cpu0_ph1_vcin" )
			)
			( signal "VR_PVCCIN_CPU0_PH2_BOOT"
				( attribute "VOLTAGE" "5"
					( Units "uVoltage" "V" 1.000000)
					( Origin gFrontEnd )
				)
				( objectStatus "@baseboard_fab2_lib.baseboard_fab2(sch_1):vr_pvccin_cpu0_ph2_boot" )
			)
			( signal "VR_PVSA_CPU0_PHASE_SW_RC"
				( objectStatus "@baseboard_fab2_lib.baseboard_fab2(sch_1):vr_pvsa_cpu0_phase_sw_rc" )
			)
			( signal "VR_PVCCIN_CPU0_PH2_OCSET"
				( attribute "VOLTAGE" "3.6"
					( Units "uVoltage" "V" 1.000000)
					( Status sAliasFlattened )
					( Origin gFrontEnd )
				)
				( objectStatus "@baseboard_fab2_lib.baseboard_fab2(sch_1):vr_pvccin_cpu0_ph2_ocset" )
			)
			( signal "VR_PVCCIN_CPU0_PH2_PHASE"
				( attribute "VOLTAGE" "5"
					( Units "uVoltage" "V" 1.000000)
					( Status sAliasFlattened )
					( Origin gFrontEnd )
				)
				( objectStatus "@baseboard_fab2_lib.baseboard_fab2(sch_1):vr_pvccin_cpu0_ph2_phase" )
			)
			( signal "VR_PVCCIN_CPU0_PH2_VCIN"
				( attribute "VOLTAGE" "5"
					( Units "uVoltage" "V" 1.000000)
					( Status sAliasFlattened )
					( Origin gFrontEnd )
				)
				( objectStatus "@baseboard_fab2_lib.baseboard_fab2(sch_1):vr_pvccin_cpu0_ph2_vcin" )
			)
			( signal "VR_PVCCIN_CPU0_PHASE1"
				( attribute "VOLTAGE" "5"
					( Units "uVoltage" "V" 1.000000)
					( Status sAliasFlattened )
					( Origin gFrontEnd )
				)
				( objectStatus "@baseboard_fab2_lib.baseboard_fab2(sch_1):vr_pvccin_cpu0_phase1" )
			)
			( signal "VR_PVCCIN_CPU0_PHASE2"
				( attribute "VOLTAGE" "5"
					( Units "uVoltage" "V" 1.000000)
					( Status sAliasFlattened )
					( Origin gFrontEnd )
				)
				( objectStatus "@baseboard_fab2_lib.baseboard_fab2(sch_1):vr_pvccin_cpu0_phase2" )
			)
			( signal "TP_PVCCIN_CPU0_PH3_GL_0"
				( objectStatus "@baseboard_fab2_lib.baseboard_fab2(sch_1):tp_pvccin_cpu0_ph3_gl_0" )
			)
			( signal "TP_PVCCIN_CPU0_PH3_GL_1"
				( objectStatus "@baseboard_fab2_lib.baseboard_fab2(sch_1):tp_pvccin_cpu0_ph3_gl_1" )
			)
			( signal "TP_PVCCIN_CPU0_PH4_GL_0"
				( objectStatus "@baseboard_fab2_lib.baseboard_fab2(sch_1):tp_pvccin_cpu0_ph4_gl_0" )
			)
			( signal "TP_PVCCIN_CPU0_PH4_GL_1"
				( objectStatus "@baseboard_fab2_lib.baseboard_fab2(sch_1):tp_pvccin_cpu0_ph4_gl_1" )
			)
			( signal "VR_PVCCIN_CPU0_PH3_BOOT"
				( objectStatus "@baseboard_fab2_lib.baseboard_fab2(sch_1):vr_pvccin_cpu0_ph3_boot" )
			)
			( signal "VR_PVSA_CPU1_PHASE_SW_RC"
				( objectStatus "@baseboard_fab2_lib.baseboard_fab2(sch_1):vr_pvsa_cpu1_phase_sw_rc" )
			)
			( signal "VR_PVCCIN_CPU0_PH3_OCSET"
				( attribute "VOLTAGE" "3.6"
					( Units "uVoltage" "V" 1.000000)
					( Status sAliasFlattened )
					( Origin gFrontEnd )
				)
				( objectStatus "@baseboard_fab2_lib.baseboard_fab2(sch_1):vr_pvccin_cpu0_ph3_ocset" )
			)
			( signal "VR_PVCCIN_CPU0_PH3_PHASE"
				( attribute "VOLTAGE" "5"
					( Units "uVoltage" "V" 1.000000)
					( Status sAliasFlattened )
					( Origin gFrontEnd )
				)
				( objectStatus "@baseboard_fab2_lib.baseboard_fab2(sch_1):vr_pvccin_cpu0_ph3_phase" )
			)
			( signal "VR_PVCCIN_CPU0_PH3_VCIN"
				( objectStatus "@baseboard_fab2_lib.baseboard_fab2(sch_1):vr_pvccin_cpu0_ph3_vcin" )
			)
			( signal "VR_PVCCIN_CPU0_PH4_BOOT"
				( objectStatus "@baseboard_fab2_lib.baseboard_fab2(sch_1):vr_pvccin_cpu0_ph4_boot" )
			)
			( signal "VR_PVCCIN_CPU0_PH4_OCSET"
				( attribute "VOLTAGE" "3.6"
					( Units "uVoltage" "V" 1.000000)
					( Status sAliasFlattened )
					( Origin gFrontEnd )
				)
				( objectStatus "@baseboard_fab2_lib.baseboard_fab2(sch_1):vr_pvccin_cpu0_ph4_ocset" )
			)
			( signal "VR_PVCCIN_CPU0_PH4_PHASE"
				( attribute "VOLTAGE" "5"
					( Units "uVoltage" "V" 1.000000)
					( Status sAliasFlattened )
					( Origin gFrontEnd )
				)
				( objectStatus "@baseboard_fab2_lib.baseboard_fab2(sch_1):vr_pvccin_cpu0_ph4_phase" )
			)
			( signal "VR_PVCCIN_CPU0_PH4_VCIN"
				( attribute "VOLTAGE" "5"
					( Units "uVoltage" "V" 1.000000)
					( Status sAliasFlattened )
					( Origin gFrontEnd )
				)
				( objectStatus "@baseboard_fab2_lib.baseboard_fab2(sch_1):vr_pvccin_cpu0_ph4_vcin" )
			)
			( signal "VR_PVCCIN_CPU0_PHASE3"
				( attribute "VOLTAGE" "5"
					( Units "uVoltage" "V" 1.000000)
					( Status sAliasFlattened )
					( Origin gFrontEnd )
				)
				( objectStatus "@baseboard_fab2_lib.baseboard_fab2(sch_1):vr_pvccin_cpu0_phase3" )
			)
			( signal "VR_PVCCIN_CPU0_PHASE4"
				( attribute "VOLTAGE" "5"
					( Units "uVoltage" "V" 1.000000)
					( Status sAliasFlattened )
					( Origin gFrontEnd )
				)
				( objectStatus "@baseboard_fab2_lib.baseboard_fab2(sch_1):vr_pvccin_cpu0_phase4" )
			)
			( signal "TP_PVCCIN_CPU0_PH5_GL_0"
				( objectStatus "@baseboard_fab2_lib.baseboard_fab2(sch_1):tp_pvccin_cpu0_ph5_gl_0" )
			)
			( signal "TP_PVCCIN_CPU0_PH5_GL_1"
				( objectStatus "@baseboard_fab2_lib.baseboard_fab2(sch_1):tp_pvccin_cpu0_ph5_gl_1" )
			)
			( signal "VR_PVCCIN_CPU0_PH5_BOOT"
				( objectStatus "@baseboard_fab2_lib.baseboard_fab2(sch_1):vr_pvccin_cpu0_ph5_boot" )
			)
			( signal "VR_PVCCIN_CPU0_PH5_OCSET"
				( attribute "VOLTAGE" "3.6"
					( Units "uVoltage" "V" 1.000000)
					( Status sAliasFlattened )
					( Origin gFrontEnd )
				)
				( objectStatus "@baseboard_fab2_lib.baseboard_fab2(sch_1):vr_pvccin_cpu0_ph5_ocset" )
			)
			( signal "VR_PVCCIN_CPU0_PH5_PHASE"
				( attribute "VOLTAGE" "5"
					( Units "uVoltage" "V" 1.000000)
					( Status sAliasFlattened )
					( Origin gFrontEnd )
				)
				( objectStatus "@baseboard_fab2_lib.baseboard_fab2(sch_1):vr_pvccin_cpu0_ph5_phase" )
			)
			( signal "VR_PVCCIN_CPU0_PH5_VCIN"
				( attribute "VOLTAGE" "5"
					( Units "uVoltage" "V" 1.000000)
					( Status sAliasFlattened )
					( Origin gFrontEnd )
				)
				( objectStatus "@baseboard_fab2_lib.baseboard_fab2(sch_1):vr_pvccin_cpu0_ph5_vcin" )
			)
			( signal "VR_PVCCIN_CPU0_PHASE5"
				( attribute "VOLTAGE" "5"
					( Units "uVoltage" "V" 1.000000)
					( Status sAliasFlattened )
					( Origin gFrontEnd )
				)
				( objectStatus "@baseboard_fab2_lib.baseboard_fab2(sch_1):vr_pvccin_cpu0_phase5" )
			)
			( signal "TP_PVSA_CPU0_GL_0"
				( objectStatus "@baseboard_fab2_lib.baseboard_fab2(sch_1):tp_pvsa_cpu0_gl_0" )
			)
			( signal "TP_PVSA_CPU0_GL_1"
				( objectStatus "@baseboard_fab2_lib.baseboard_fab2(sch_1):tp_pvsa_cpu0_gl_1" )
			)
			( signal "VR_PVSA_CPU0_BOOT"
				( objectStatus "@baseboard_fab2_lib.baseboard_fab2(sch_1):vr_pvsa_cpu0_boot" )
			)
			( signal "VR_PVSA_CPU0_OCSET"
				( objectStatus "@baseboard_fab2_lib.baseboard_fab2(sch_1):vr_pvsa_cpu0_ocset" )
			)
			( signal "VR_PVSA_CPU0_PHASE"
				( attribute "VOLTAGE" "5"
					( Units "uVoltage" "V" 1.000000)
					( Status sAliasFlattened )
					( Origin gFrontEnd )
				)
				( objectStatus "@baseboard_fab2_lib.baseboard_fab2(sch_1):vr_pvsa_cpu0_phase" )
			)
			( signal "VR_PVSA_CPU0_PHASE_SW"
				( attribute "VOLTAGE" "5"
					( Units "uVoltage" "V" 1.000000)
					( Status sAliasFlattened )
					( Origin gFrontEnd )
				)
				( objectStatus "@baseboard_fab2_lib.baseboard_fab2(sch_1):vr_pvsa_cpu0_phase_sw" )
			)
			( signal "VR_PVSA_CPU0_VCIN"
				( attribute "VOLTAGE" "5"
					( Units "uVoltage" "V" 1.000000)
					( Status sAliasFlattened )
					( Origin gFrontEnd )
				)
				( objectStatus "@baseboard_fab2_lib.baseboard_fab2(sch_1):vr_pvsa_cpu0_vcin" )
			)
			( signal "A_TSENSE_PVCCIN_CPU1"
				( attribute "VOLTAGE" "3.6"
					( Units "uVoltage" "V" 1.000000)
					( Status sAliasFlattened )
					( Origin gFrontEnd )
				)
				( objectStatus "@baseboard_fab2_lib.baseboard_fab2(sch_1):a_tsense_pvccin_cpu1" )
			)
			( signal "A_TSENSE_PVSA_CPU1"
				( objectStatus "@baseboard_fab2_lib.baseboard_fab2(sch_1):a_tsense_pvsa_cpu1" )
			)
			( signal "IRQ_PVCCIN_CPU1_VRHOT_LVC3_R_N"
				( objectStatus "@baseboard_fab2_lib.baseboard_fab2(sch_1):irq_pvccin_cpu1_vrhot_lvc3_r_n" )
			)
			( signal "ISENSE_PVCCIN_CPU1_PH1_IMON"
				( objectStatus "@baseboard_fab2_lib.baseboard_fab2(sch_1):isense_pvccin_cpu1_ph1_imon" )
			)
			( signal "ISENSE_PVCCIN_CPU1_PH2_IMON"
				( objectStatus "@baseboard_fab2_lib.baseboard_fab2(sch_1):isense_pvccin_cpu1_ph2_imon" )
			)
			( signal "ISENSE_PVCCIN_CPU1_PH3_IMON"
				( objectStatus "@baseboard_fab2_lib.baseboard_fab2(sch_1):isense_pvccin_cpu1_ph3_imon" )
			)
			( signal "ISENSE_PVCCIN_CPU1_PH4_IMON"
				( objectStatus "@baseboard_fab2_lib.baseboard_fab2(sch_1):isense_pvccin_cpu1_ph4_imon" )
			)
			( signal "ISENSE_PVCCIN_CPU1_PH5_IMON"
				( objectStatus "@baseboard_fab2_lib.baseboard_fab2(sch_1):isense_pvccin_cpu1_ph5_imon" )
			)
			( signal "ISENSE_PVSA_CPU1_IMON"
				( objectStatus "@baseboard_fab2_lib.baseboard_fab2(sch_1):isense_pvsa_cpu1_imon" )
			)
			( signal "PU_VR_PVCCIN_CPU1_FLT1_SMBALT_N"
				( objectStatus "@baseboard_fab2_lib.baseboard_fab2(sch_1):pu_vr_pvccin_cpu1_flt1_smbalt_n_imon" )
			)
			( signal "PU_VR_PVCCIN_CPU1_IMON"
				( objectStatus "@baseboard_fab2_lib.baseboard_fab2(sch_1):pu_vr_pvccin_cpu1_imon" )
			)
			( signal "PWRGD_PVSA_CPU1_R"
				( objectStatus "@baseboard_fab2_lib.baseboard_fab2(sch_1):pwrgd_pvsa_cpu1_r" )
			)
			( signal "SVID_VALERT_VCCIN_CPU1"
				( objectStatus "@baseboard_fab2_lib.baseboard_fab2(sch_1):svid_valert_vccin_cpu1" )
			)
			( signal "SVID_VCLK_PVCCIN_CPU1"
				( objectStatus "@baseboard_fab2_lib.baseboard_fab2(sch_1):svid_vclk_pvccin_cpu1" )
			)
			( signal "SVID_VDIO_PVCCIN_CPU1"
				( objectStatus "@baseboard_fab2_lib.baseboard_fab2(sch_1):svid_vdio_pvccin_cpu1" )
			)
			( signal "VR_FET_SW_P12V_STBY_PVCCIN_CPU1"
				( attribute "VOLTAGE" "12"
					( Units "uVoltage" "V" 1.000000)
					( Status sAliasFlattened )
					( Origin gFrontEnd )
				)
				( objectStatus "@baseboard_fab2_lib.baseboard_fab2(sch_1):vr_fet_sw_p12v_stby_pvccin_cpu1" )
			)
			( signal "VR_PVCCIN_CPU1_AIREF1"
				( objectStatus "@baseboard_fab2_lib.baseboard_fab2(sch_1):vr_pvccin_cpu1_airef1" )
			)
			( signal "VR_PVCCIN_CPU1_AIREF2"
				( objectStatus "@baseboard_fab2_lib.baseboard_fab2(sch_1):vr_pvccin_cpu1_airef2" )
			)
			( signal "VR_PVCCIN_CPU1_AIREF3"
				( objectStatus "@baseboard_fab2_lib.baseboard_fab2(sch_1):vr_pvccin_cpu1_airef3" )
			)
			( signal "VR_PVCCIN_CPU1_AIREF4"
				( objectStatus "@baseboard_fab2_lib.baseboard_fab2(sch_1):vr_pvccin_cpu1_airef4" )
			)
			( signal "VR_PVCCIN_CPU1_AIREF5"
				( objectStatus "@baseboard_fab2_lib.baseboard_fab2(sch_1):vr_pvccin_cpu1_airef5" )
			)
			( signal "VR_PVCCIN_CPU1_AVINSEN"
				( attribute "VOLTAGE" "0.8"
					( Units "uVoltage" "V" 1.000000)
					( Status sAliasFlattened )
					( Origin gFrontEnd )
				)
				( objectStatus "@baseboard_fab2_lib.baseboard_fab2(sch_1):vr_pvccin_cpu1_avinsen" )
			)
			( signal "VR_PVCCIN_CPU1_PWM1"
				( attribute "VOLTAGE" "3.6"
					( Units "uVoltage" "V" 1.000000)
					( Status sAliasFlattened )
					( Origin gFrontEnd )
				)
				( objectStatus "@baseboard_fab2_lib.baseboard_fab2(sch_1):vr_pvccin_cpu1_pwm1" )
			)
			( signal "VR_PVCCIN_CPU1_PWM2"
				( attribute "VOLTAGE" "3.6"
					( Units "uVoltage" "V" 1.000000)
					( Status sAliasFlattened )
					( Origin gFrontEnd )
				)
				( objectStatus "@baseboard_fab2_lib.baseboard_fab2(sch_1):vr_pvccin_cpu1_pwm2" )
			)
			( signal "VR_PVCCIN_CPU1_PWM3"
				( attribute "VOLTAGE" "3.6"
					( Units "uVoltage" "V" 1.000000)
					( Status sAliasFlattened )
					( Origin gFrontEnd )
				)
				( objectStatus "@baseboard_fab2_lib.baseboard_fab2(sch_1):vr_pvccin_cpu1_pwm3" )
			)
			( signal "VR_PVCCIN_CPU1_PWM4"
				( attribute "VOLTAGE" "3.6"
					( Units "uVoltage" "V" 1.000000)
					( Status sAliasFlattened )
					( Origin gFrontEnd )
				)
				( objectStatus "@baseboard_fab2_lib.baseboard_fab2(sch_1):vr_pvccin_cpu1_pwm4" )
			)
			( signal "VR_PVCCIN_CPU1_PWM5"
				( attribute "VOLTAGE" "3.6"
					( Units "uVoltage" "V" 1.000000)
					( Status sAliasFlattened )
					( Origin gFrontEnd )
				)
				( objectStatus "@baseboard_fab2_lib.baseboard_fab2(sch_1):vr_pvccin_cpu1_pwm5" )
			)
			( signal "VR_PVCCIN_CPU1_VD12"
				( objectStatus "@baseboard_fab2_lib.baseboard_fab2(sch_1):vr_pvccin_cpu1_vd12" )
			)
			( signal "VR_PVCCIN_CPU1_VDD"
				( attribute "VOLTAGE" "3.3"
					( Units "uVoltage" "V" 1.000000)
					( Status sAliasFlattened )
					( Origin gFrontEnd )
				)
				( objectStatus "@baseboard_fab2_lib.baseboard_fab2(sch_1):vr_pvccin_cpu1_vdd" )
			)
			( signal "VR_PVCCIN_CPU1_VREN"
				( attribute "VOLTAGE" "3.3"
					( Units "uVoltage" "V" 1.000000)
					( Status sAliasFlattened )
					( Origin gFrontEnd )
				)
				( objectStatus "@baseboard_fab2_lib.baseboard_fab2(sch_1):vr_pvccin_cpu1_vren" )
			)
			( signal "VR_PVCCIN_CPU1_XADDR1"
				( attribute "VOLTAGE" "3.3"
					( Units "uVoltage" "V" 1.000000)
					( Status sAliasFlattened )
					( Origin gFrontEnd )
				)
				( objectStatus "@baseboard_fab2_lib.baseboard_fab2(sch_1):vr_pvccin_cpu1_xaddr1" )
			)
			( signal "VR_PVCCIN_CPU1_XADDR2"
				( attribute "VOLTAGE" "3.3"
					( Units "uVoltage" "V" 1.000000)
					( Status sAliasFlattened )
					( Origin gFrontEnd )
				)
				( objectStatus "@baseboard_fab2_lib.baseboard_fab2(sch_1):vr_pvccin_cpu1_xaddr2" )
			)
			( signal "VR_PVSA_CPU1_BIREF1"
				( objectStatus "@baseboard_fab2_lib.baseboard_fab2(sch_1):vr_pvsa_cpu1_biref1" )
			)
			( signal "VR_PVSA_CPU1_PWM"
				( attribute "VOLTAGE" "3.6"
					( Units "uVoltage" "V" 1.000000)
					( Status sAliasFlattened )
					( Origin gFrontEnd )
				)
				( objectStatus "@baseboard_fab2_lib.baseboard_fab2(sch_1):vr_pvsa_cpu1_pwm" )
			)
			( signal "VR_VRRDY_PVCCIN_CPU1"
				( objectStatus "@baseboard_fab2_lib.baseboard_fab2(sch_1):vr_vrrdy_pvccin_cpu1" )
			)
			( signal "VSENSE_PVCCIN_CPU1_AVSP"
				( objectStatus "@baseboard_fab2_lib.baseboard_fab2(sch_1):vsense_pvccin_cpu1_avsp" )
			)
			( signal "VSENSE_PVCCIN_CPU1_N"
				( objectStatus "@baseboard_fab2_lib.baseboard_fab2(sch_1):vsense_pvccin_cpu1_n" )
			)
			( signal "VSENSE_PVCCIN_CPU1_P"
				( objectStatus "@baseboard_fab2_lib.baseboard_fab2(sch_1):vsense_pvccin_cpu1_p" )
			)
			( signal "VSENSE_PVSA_CPU1_BVSP"
				( objectStatus "@baseboard_fab2_lib.baseboard_fab2(sch_1):vsense_pvsa_cpu1_bvsp" )
			)
			( signal "VSENSE_PVSA_CPU1_N"
				( objectStatus "@baseboard_fab2_lib.baseboard_fab2(sch_1):vsense_pvsa_cpu1_n" )
			)
			( signal "VSENSE_PVSA_CPU1_P"
				( objectStatus "@baseboard_fab2_lib.baseboard_fab2(sch_1):vsense_pvsa_cpu1_p" )
			)
			( signal "TP_PVCCINC_CPU1_PH1_GL_0"
				( objectStatus "@baseboard_fab2_lib.baseboard_fab2(sch_1):tp_pvccinc_cpu1_ph1_gl_0" )
			)
			( signal "TP_PVCCINC_CPU1_PH1_GL_1"
				( objectStatus "@baseboard_fab2_lib.baseboard_fab2(sch_1):tp_pvccinc_cpu1_ph1_gl_1" )
			)
			( signal "TP_PVCCINC_CPU1_PH2_GL_0"
				( objectStatus "@baseboard_fab2_lib.baseboard_fab2(sch_1):tp_pvccinc_cpu1_ph2_gl_0" )
			)
			( signal "TP_PVCCINC_CPU1_PH2_GL_1"
				( objectStatus "@baseboard_fab2_lib.baseboard_fab2(sch_1):tp_pvccinc_cpu1_ph2_gl_1" )
			)
			( signal "VR_PVCCIN_CPU1_PH1_BOOT"
				( objectStatus "@baseboard_fab2_lib.baseboard_fab2(sch_1):vr_pvccin_cpu1_ph1_boot" )
			)
			( signal "VR_PVCCIN_CPU1_PH1_OCSET"
				( objectStatus "@baseboard_fab2_lib.baseboard_fab2(sch_1):vr_pvccin_cpu1_ph1_ocset" )
			)
			( signal "VR_PVCCIN_CPU1_PH1_PHASE"
				( attribute "VOLTAGE" "5"
					( Units "uVoltage" "V" 1.000000)
					( Status sAliasFlattened )
					( Origin gFrontEnd )
				)
				( objectStatus "@baseboard_fab2_lib.baseboard_fab2(sch_1):vr_pvccin_cpu1_ph1_phase" )
			)
			( signal "VR_PVCCIN_CPU1_PH1_VCIN"
				( attribute "VOLTAGE" "5"
					( Units "uVoltage" "V" 1.000000)
					( Status sAliasFlattened )
					( Origin gFrontEnd )
				)
				( objectStatus "@baseboard_fab2_lib.baseboard_fab2(sch_1):vr_pvccin_cpu1_ph1_vcin" )
			)
			( signal "VR_PVCCIN_CPU1_PH2_BOOT"
				( objectStatus "@baseboard_fab2_lib.baseboard_fab2(sch_1):vr_pvccin_cpu1_ph2_boot" )
			)
			( signal "VR_PVCCIN_CPU1_PH2_OCSET"
				( objectStatus "@baseboard_fab2_lib.baseboard_fab2(sch_1):vr_pvccin_cpu1_ph2_ocset" )
			)
			( signal "VR_PVCCIN_CPU1_PH2_PHASE"
				( attribute "VOLTAGE" "5"
					( Units "uVoltage" "V" 1.000000)
					( Status sAliasFlattened )
					( Origin gFrontEnd )
				)
				( objectStatus "@baseboard_fab2_lib.baseboard_fab2(sch_1):vr_pvccin_cpu1_ph2_phase" )
			)
			( signal "VR_PVCCIN_CPU1_PH2_VCIN"
				( objectStatus "@baseboard_fab2_lib.baseboard_fab2(sch_1):vr_pvccin_cpu1_ph2_vcin" )
			)
			( signal "VR_PVCCIN_CPU1_PHASE1"
				( attribute "VOLTAGE" "5"
					( Units "uVoltage" "V" 1.000000)
					( Status sAliasFlattened )
					( Origin gFrontEnd )
				)
				( objectStatus "@baseboard_fab2_lib.baseboard_fab2(sch_1):vr_pvccin_cpu1_phase1" )
			)
			( signal "VR_PVCCIN_CPU1_PHASE2"
				( attribute "VOLTAGE" "5"
					( Units "uVoltage" "V" 1.000000)
					( Status sAliasFlattened )
					( Origin gFrontEnd )
				)
				( objectStatus "@baseboard_fab2_lib.baseboard_fab2(sch_1):vr_pvccin_cpu1_phase2" )
			)
			( signal "TP_PVCCIN_CPU1_PH3_GL_0"
				( objectStatus "@baseboard_fab2_lib.baseboard_fab2(sch_1):tp_pvccin_cpu1_ph3_gl_0" )
			)
			( signal "TP_PVCCIN_CPU1_PH3_GL_1"
				( objectStatus "@baseboard_fab2_lib.baseboard_fab2(sch_1):tp_pvccin_cpu1_ph3_gl_1" )
			)
			( signal "TP_PVCCIN_CPU1_PH4_GL_0"
				( objectStatus "@baseboard_fab2_lib.baseboard_fab2(sch_1):tp_pvccin_cpu1_ph4_gl_0" )
			)
			( signal "TP_PVCCIN_CPU1_PH4_GL_1"
				( objectStatus "@baseboard_fab2_lib.baseboard_fab2(sch_1):tp_pvccin_cpu1_ph4_gl_1" )
			)
			( signal "VR_PVCCIN_CPU1_PH3_BOOT"
				( objectStatus "@baseboard_fab2_lib.baseboard_fab2(sch_1):vr_pvccin_cpu1_ph3_boot" )
			)
			( signal "VR_PVCCIN_CPU1_PH3_OCSET"
				( objectStatus "@baseboard_fab2_lib.baseboard_fab2(sch_1):vr_pvccin_cpu1_ph3_ocset" )
			)
			( signal "VR_PVCCIN_CPU1_PH3_PHASE"
				( objectStatus "@baseboard_fab2_lib.baseboard_fab2(sch_1):vr_pvccin_cpu1_ph3_phase" )
			)
			( signal "VR_PVCCIN_CPU1_PH3_VCIN"
				( attribute "VOLTAGE" "5"
					( Units "uVoltage" "V" 1.000000)
					( Status sAliasFlattened )
					( Origin gFrontEnd )
				)
				( objectStatus "@baseboard_fab2_lib.baseboard_fab2(sch_1):vr_pvccin_cpu1_ph3_vcin" )
			)
			( signal "VR_PVCCIN_CPU1_PH4_BOOT"
				( objectStatus "@baseboard_fab2_lib.baseboard_fab2(sch_1):vr_pvccin_cpu1_ph4_boot" )
			)
			( signal "VR_PVCCIN_CPU1_PH4_OCSET"
				( objectStatus "@baseboard_fab2_lib.baseboard_fab2(sch_1):vr_pvccin_cpu1_ph4_ocset" )
			)
			( signal "VR_PVCCIN_CPU1_PH4_PHASE"
				( attribute "VOLTAGE" "5"
					( Units "uVoltage" "V" 1.000000)
					( Status sAliasFlattened )
					( Origin gFrontEnd )
				)
				( objectStatus "@baseboard_fab2_lib.baseboard_fab2(sch_1):vr_pvccin_cpu1_ph4_phase" )
			)
			( signal "VR_PVCCIN_CPU1_PH4_VCIN"
				( attribute "VOLTAGE" "5"
					( Units "uVoltage" "V" 1.000000)
					( Status sAliasFlattened )
					( Origin gFrontEnd )
				)
				( objectStatus "@baseboard_fab2_lib.baseboard_fab2(sch_1):vr_pvccin_cpu1_ph4_vcin" )
			)
			( signal "VR_PVCCIN_CPU1_PHASE3"
				( attribute "VOLTAGE" "5"
					( Units "uVoltage" "V" 1.000000)
					( Status sAliasFlattened )
					( Origin gFrontEnd )
				)
				( objectStatus "@baseboard_fab2_lib.baseboard_fab2(sch_1):vr_pvccin_cpu1_phase3" )
			)
			( signal "VR_PVCCIN_CPU1_PHASE4"
				( attribute "VOLTAGE" "5"
					( Units "uVoltage" "V" 1.000000)
					( Status sAliasFlattened )
					( Origin gFrontEnd )
				)
				( objectStatus "@baseboard_fab2_lib.baseboard_fab2(sch_1):vr_pvccin_cpu1_phase4" )
			)
			( signal "TP_PVCCIN_CPU1_PH5_GL_0"
				( objectStatus "@baseboard_fab2_lib.baseboard_fab2(sch_1):tp_pvccin_cpu1_ph5_gl_0" )
			)
			( signal "TP_PVCCIN_CPU1_PH5_GL_1"
				( objectStatus "@baseboard_fab2_lib.baseboard_fab2(sch_1):tp_pvccin_cpu1_ph5_gl_1" )
			)
			( signal "VR_PVCCIN_CPU1_PH5_BOOT"
				( objectStatus "@baseboard_fab2_lib.baseboard_fab2(sch_1):vr_pvccin_cpu1_ph5_boot" )
			)
			( signal "VR_PVCCIN_CPU1_PH5_OCSET"
				( objectStatus "@baseboard_fab2_lib.baseboard_fab2(sch_1):vr_pvccin_cpu1_ph5_ocset" )
			)
			( signal "VR_PVCCIN_CPU1_PH5_PHASE"
				( attribute "VOLTAGE" "5"
					( Units "uVoltage" "V" 1.000000)
					( Status sAliasFlattened )
					( Origin gFrontEnd )
				)
				( objectStatus "@baseboard_fab2_lib.baseboard_fab2(sch_1):vr_pvccin_cpu1_ph5_phase" )
			)
			( signal "VR_PVCCIN_CPU1_PH5_VCIN"
				( attribute "VOLTAGE" "5"
					( Units "uVoltage" "V" 1.000000)
					( Status sAliasFlattened )
					( Origin gFrontEnd )
				)
				( objectStatus "@baseboard_fab2_lib.baseboard_fab2(sch_1):vr_pvccin_cpu1_ph5_vcin" )
			)
			( signal "VR_PVCCIN_CPU1_PHASE5"
				( attribute "VOLTAGE" "5"
					( Units "uVoltage" "V" 1.000000)
					( Status sAliasFlattened )
					( Origin gFrontEnd )
				)
				( objectStatus "@baseboard_fab2_lib.baseboard_fab2(sch_1):vr_pvccin_cpu1_phase5" )
			)
			( signal "TP_PVSA_CPU1_GL_0"
				( objectStatus "@baseboard_fab2_lib.baseboard_fab2(sch_1):tp_pvsa_cpu1_gl_0" )
			)
			( signal "TP_PVSA_CPU1_GL_1"
				( objectStatus "@baseboard_fab2_lib.baseboard_fab2(sch_1):tp_pvsa_cpu1_gl_1" )
			)
			( signal "VR_PVSA_CPU1_BOOT"
				( objectStatus "@baseboard_fab2_lib.baseboard_fab2(sch_1):vr_pvsa_cpu1_boot" )
			)
			( signal "VR_PVSA_CPU1_OCSET"
				( objectStatus "@baseboard_fab2_lib.baseboard_fab2(sch_1):vr_pvsa_cpu1_ocset" )
			)
			( signal "VR_PVSA_CPU1_PHASE"
				( attribute "VOLTAGE" "5"
					( Units "uVoltage" "V" 1.000000)
					( Status sAliasFlattened )
					( Origin gFrontEnd )
				)
				( objectStatus "@baseboard_fab2_lib.baseboard_fab2(sch_1):vr_pvsa_cpu1_phase" )
			)
			( signal "VR_PVSA_CPU1_PHASE_SW"
				( attribute "VOLTAGE" "5"
					( Units "uVoltage" "V" 1.000000)
					( Status sAliasFlattened )
					( Origin gFrontEnd )
				)
				( objectStatus "@baseboard_fab2_lib.baseboard_fab2(sch_1):vr_pvsa_cpu1_phase_sw" )
			)
			( signal "VR_PVSA_CPU1_VCIN"
				( attribute "VOLTAGE" "5"
					( Units "uVoltage" "V" 1.000000)
					( Status sAliasFlattened )
					( Origin gFrontEnd )
				)
				( objectStatus "@baseboard_fab2_lib.baseboard_fab2(sch_1):vr_pvsa_cpu1_vcin" )
			)
			( signal "A_TSENSE_PVCCIO_CPU0"
				( attribute "VOLTAGE" "3.6"
					( Units "uVoltage" "V" 1.000000)
					( Status sAliasFlattened )
					( Origin gFrontEnd )
				)
				( objectStatus "@baseboard_fab2_lib.baseboard_fab2(sch_1):a_tsense_pvccio_cpu0" )
			)
			( signal "IRQ_PVCCIO_CPU0_VRHOT_N"
				( objectStatus "@baseboard_fab2_lib.baseboard_fab2(sch_1):irq_pvccio_cpu0_vrhot_n" )
			)
			( signal "ISENSE_PVCCIO_CPU0_PH1_IMON"
				( objectStatus "@baseboard_fab2_lib.baseboard_fab2(sch_1):isense_pvccio_cpu0_ph1_imon" )
			)
			( signal "PU_VR_PVCCIO_CPU0_FAULT1"
				( objectStatus "@baseboard_fab2_lib.baseboard_fab2(sch_1):pu_vr_pvccio_cpu0_fault1" )
			)
			( signal "PWRGD_PVCCIO_CPU0_R"
				( objectStatus "@baseboard_fab2_lib.baseboard_fab2(sch_1):pwrgd_pvccio_cpu0_r" )
			)
			( signal "SVID_ALERT_PVCCIO_CPU0"
				( objectStatus "@baseboard_fab2_lib.baseboard_fab2(sch_1):svid_alert_pvccio_cpu0" )
			)
			( signal "SVID_CLK_PVCCIO_CPU0"
				( objectStatus "@baseboard_fab2_lib.baseboard_fab2(sch_1):svid_clk_pvccio_cpu0" )
			)
			( signal "SVID_VDIO_PVCCIO_CPU0"
				( objectStatus "@baseboard_fab2_lib.baseboard_fab2(sch_1):svid_vdio_pvccio_cpu0" )
			)
			( signal "VR_FET_SW_P12V_STBY_PVCCIO_CPU0"
				( attribute "VOLTAGE" "12"
					( Units "uVoltage" "V" 1.000000)
					( Status sAliasFlattened )
					( Origin gFrontEnd )
				)
				( objectStatus "@baseboard_fab2_lib.baseboard_fab2(sch_1):vr_fet_sw_p12v_stby_pvccio_cpu0" )
			)
			( signal "VR_PVCCIO_CPU0_AIREF1"
				( objectStatus "@baseboard_fab2_lib.baseboard_fab2(sch_1):vr_pvccio_cpu0_airef1" )
			)
			( signal "VR_PVCCIO_CPU0_AVSP"
				( attribute "VOLTAGE" "2"
					( Units "uVoltage" "V" 1.000000)
					( Status sAliasFlattened )
					( Origin gFrontEnd )
				)
				( objectStatus "@baseboard_fab2_lib.baseboard_fab2(sch_1):vr_pvccio_cpu0_avsp" )
			)
			( signal "VR_PVCCIO_CPU0_EN"
				( objectStatus "@baseboard_fab2_lib.baseboard_fab2(sch_1):vr_pvccio_cpu0_en" )
			)
			( signal "VR_PVCCIO_CPU0_PWM1"
				( attribute "VOLTAGE" "3.3"
					( Units "uVoltage" "V" 1.000000)
					( Status sAliasFlattened )
					( Origin gFrontEnd )
				)
				( objectStatus "@baseboard_fab2_lib.baseboard_fab2(sch_1):vr_pvccio_cpu0_pwm1" )
			)
			( signal "VR_PVCCIO_CPU0_VD12"
				( objectStatus "@baseboard_fab2_lib.baseboard_fab2(sch_1):vr_pvccio_cpu0_vd12" )
			)
			( signal "VR_PVCCIO_CPU0_VDD"
				( objectStatus "@baseboard_fab2_lib.baseboard_fab2(sch_1):vr_pvccio_cpu0_vdd" )
			)
			( signal "VR_PVCCIO_CPU0_VINSEN"
				( attribute "VOLTAGE" "0.8"
					( Units "uVoltage" "V" 1.000000)
					( Status sAliasFlattened )
					( Origin gFrontEnd )
				)
				( objectStatus "@baseboard_fab2_lib.baseboard_fab2(sch_1):vr_pvccio_cpu0_vinsen" )
			)
			( signal "VR_PVCCIO_CPU0_XADDR1"
				( attribute "VOLTAGE" "3.3"
					( Units "uVoltage" "V" 1.000000)
					( Status sAliasFlattened )
					( Origin gFrontEnd )
				)
				( objectStatus "@baseboard_fab2_lib.baseboard_fab2(sch_1):vr_pvccio_cpu0_xaddr1" )
			)
			( signal "VR_PVCCIO_CPU0_XADDR2"
				( attribute "VOLTAGE" "3.3V"
					( Units "uVoltage" "V" 1.000000)
					( Status sAliasFlattened )
					( Origin gFrontEnd )
				)
				( objectStatus "@baseboard_fab2_lib.baseboard_fab2(sch_1):vr_pvccio_cpu0_xaddr2" )
			)
			( signal "VSENSE_PVCCIO_CPU0_AVSN"
				( objectStatus "@baseboard_fab2_lib.baseboard_fab2(sch_1):vsense_pvccio_cpu0_avsn" )
			)
			( signal "VSENSE_PVCCIO_CPU0_AVSP"
				( objectStatus "@baseboard_fab2_lib.baseboard_fab2(sch_1):vsense_pvccio_cpu0_avsp" )
			)
			( signal "TP_PVCCIO_CPU0_GL_0"
				( objectStatus "@baseboard_fab2_lib.baseboard_fab2(sch_1):tp_pvccio_cpu0_gl_0" )
			)
			( signal "TP_PVCCIO_CPU0_GL_1"
				( objectStatus "@baseboard_fab2_lib.baseboard_fab2(sch_1):tp_pvccio_cpu0_gl_1" )
			)
			( signal "VR_PVCCIO_CPU0_OCSET"
				( objectStatus "@baseboard_fab2_lib.baseboard_fab2(sch_1):vr_pvccio_cpu0_ocset" )
			)
			( signal "VR_PVCCIO_CPU0_PH1_BOOT"
				( objectStatus "@baseboard_fab2_lib.baseboard_fab2(sch_1):vr_pvccio_cpu0_ph1_boot" )
			)
			( signal "VR_PVCCIO_CPU0_PH1_PHASE"
				( attribute "VOLTAGE" "5"
					( Units "uVoltage" "V" 1.000000)
					( Status sAliasFlattened )
					( Origin gFrontEnd )
				)
				( objectStatus "@baseboard_fab2_lib.baseboard_fab2(sch_1):vr_pvccio_cpu0_ph1_phase" )
			)
			( signal "VR_PVCCIO_CPU0_PH1_SW"
				( attribute "VOLTAGE" "5"
					( Units "uVoltage" "V" 1.000000)
					( Status sAliasFlattened )
					( Origin gFrontEnd )
				)
				( objectStatus "@baseboard_fab2_lib.baseboard_fab2(sch_1):vr_pvccio_cpu0_ph1_sw" )
			)
			( signal "VR_PVCCIO_CPU0_PH1_VCIN"
				( attribute "VOLTAGE" "5"
					( Units "uVoltage" "V" 1.000000)
					( Status sAliasFlattened )
					( Origin gFrontEnd )
				)
				( objectStatus "@baseboard_fab2_lib.baseboard_fab2(sch_1):vr_pvccio_cpu0_ph1_vcin" )
			)
			( signal "A_TSENSE_PVCCIO_CPU1"
				( objectStatus "@baseboard_fab2_lib.baseboard_fab2(sch_1):a_tsense_pvccio_cpu1" )
			)
			( signal "IRQ_PVCCIO_CPU1_VRHOT_N"
				( objectStatus "@baseboard_fab2_lib.baseboard_fab2(sch_1):irq_pvccio_cpu1_vrhot_n" )
			)
			( signal "ISENSE_PVCCIO_CPU1_PH1_IMON"
				( objectStatus "@baseboard_fab2_lib.baseboard_fab2(sch_1):isense_pvccio_cpu1_ph1_imon" )
			)
			( signal "PU_VR_PVCCIO_CPU1_FAULT1"
				( objectStatus "@baseboard_fab2_lib.baseboard_fab2(sch_1):pu_vr_pvccio_cpu1_fault1" )
			)
			( signal "PWRGD_PVCCIO_CPU1_R"
				( objectStatus "@baseboard_fab2_lib.baseboard_fab2(sch_1):pwrgd_pvccio_cpu1_r" )
			)
			( signal "SVID_ALERT_PVCCIO_CPU1"
				( objectStatus "@baseboard_fab2_lib.baseboard_fab2(sch_1):svid_alert_pvccio_cpu1" )
			)
			( signal "SVID_CLK_PVCCIO_CPU1"
				( objectStatus "@baseboard_fab2_lib.baseboard_fab2(sch_1):svid_clk_pvccio_cpu1" )
			)
			( signal "SVID_VDIO_PVCCIO_CPU1"
				( objectStatus "@baseboard_fab2_lib.baseboard_fab2(sch_1):svid_vdio_pvccio_cpu1" )
			)
			( signal "VR_PVCCIO_CPU1_AIREF1"
				( objectStatus "@baseboard_fab2_lib.baseboard_fab2(sch_1):vr_pvccio_cpu1_airef1" )
			)
			( signal "VR_PVCCIO_CPU1_AVSP"
				( attribute "VOLTAGE" "1.05"
					( Units "uVoltage" "V" 1.000000)
					( Status sAliasFlattened )
					( Origin gFrontEnd )
				)
				( objectStatus "@baseboard_fab2_lib.baseboard_fab2(sch_1):vr_pvccio_cpu1_avsp" )
			)
			( signal "VR_PVCCIO_CPU1_EN"
				( attribute "VOLTAGE" "3.3"
					( Units "uVoltage" "V" 1.000000)
					( Status sAliasFlattened )
					( Origin gFrontEnd )
				)
				( objectStatus "@baseboard_fab2_lib.baseboard_fab2(sch_1):vr_pvccio_cpu1_en" )
			)
			( signal "VR_PVCCIO_CPU1_PWM1"
				( attribute "VOLTAGE" "3.6"
					( Units "uVoltage" "V" 1.000000)
					( Status sAliasFlattened )
					( Origin gFrontEnd )
				)
				( objectStatus "@baseboard_fab2_lib.baseboard_fab2(sch_1):vr_pvccio_cpu1_pwm1" )
			)
			( signal "VR_PVCCIO_CPU1_VD12"
				( objectStatus "@baseboard_fab2_lib.baseboard_fab2(sch_1):vr_pvccio_cpu1_vd12" )
			)
			( signal "VR_PVCCIO_CPU1_VDD"
				( attribute "VOLTAGE" "3.3"
					( Units "uVoltage" "V" 1.000000)
					( Status sAliasFlattened )
					( Origin gFrontEnd )
				)
				( objectStatus "@baseboard_fab2_lib.baseboard_fab2(sch_1):vr_pvccio_cpu1_vdd" )
			)
			( signal "VR_PVCCIO_CPU1_VINSEN"
				( objectStatus "@baseboard_fab2_lib.baseboard_fab2(sch_1):vr_pvccio_cpu1_vinsen" )
			)
			( signal "VR_PVCCIO_CPU1_XADDR1"
				( attribute "VOLTAGE" "3.3"
					( Units "uVoltage" "V" 1.000000)
					( Status sAliasFlattened )
					( Origin gFrontEnd )
				)
				( objectStatus "@baseboard_fab2_lib.baseboard_fab2(sch_1):vr_pvccio_cpu1_xaddr1" )
			)
			( signal "VR_PVCCIO_CPU1_XADDR2"
				( attribute "VOLTAGE" "3.3"
					( Units "uVoltage" "V" 1.000000)
					( Status sAliasFlattened )
					( Origin gFrontEnd )
				)
				( objectStatus "@baseboard_fab2_lib.baseboard_fab2(sch_1):vr_pvccio_cpu1_xaddr2" )
			)
			( signal "VSENSE_PVCCIO_CPU1_AVSN"
				( objectStatus "@baseboard_fab2_lib.baseboard_fab2(sch_1):vsense_pvccio_cpu1_avsn" )
			)
			( signal "VSENSE_PVCCIO_CPU1_AVSP"
				( objectStatus "@baseboard_fab2_lib.baseboard_fab2(sch_1):vsense_pvccio_cpu1_avsp" )
			)
			( signal "TP_PVCCIO_CPU1_GL_0"
				( objectStatus "@baseboard_fab2_lib.baseboard_fab2(sch_1):tp_pvccio_cpu1_gl_0" )
			)
			( signal "TP_PVCCIO_CPU1_GL_1"
				( objectStatus "@baseboard_fab2_lib.baseboard_fab2(sch_1):tp_pvccio_cpu1_gl_1" )
			)
			( signal "VR_PVCCIO_CPU1_OCSET"
				( objectStatus "@baseboard_fab2_lib.baseboard_fab2(sch_1):vr_pvccio_cpu1_ocset" )
			)
			( signal "VR_PVCCIO_CPU1_PH1_BOOT"
				( objectStatus "@baseboard_fab2_lib.baseboard_fab2(sch_1):vr_pvccio_cpu1_ph1_boot" )
			)
			( signal "VR_PVCCIO_CPU1_PH1_PHASE"
				( objectStatus "@baseboard_fab2_lib.baseboard_fab2(sch_1):vr_pvccio_cpu1_ph1_phase" )
			)
			( signal "VR_PVCCIO_CPU1_PH1_SW"
				( objectStatus "@baseboard_fab2_lib.baseboard_fab2(sch_1):vr_pvccio_cpu1_ph1_sw" )
			)
			( signal "VR_PVCCIO_CPU1_PH1_VCIN"
				( objectStatus "@baseboard_fab2_lib.baseboard_fab2(sch_1):vr_pvccio_cpu1_ph1_vcin" )
			)
			( signal "A_TSENSE_PVDDQ_ABC"
				( objectStatus "@baseboard_fab2_lib.baseboard_fab2(sch_1):a_tsense_pvddq_abc" )
			)
			( signal "IRQ_PVDDQ_ABC_VRHOT_LVT3_R_N"
				( objectStatus "@baseboard_fab2_lib.baseboard_fab2(sch_1):irq_pvddq_abc_vrhot_lvt3_r_n" )
			)
			( signal "ISENSE_PVDDQ_ABC_PH1_IMON"
				( objectStatus "@baseboard_fab2_lib.baseboard_fab2(sch_1):isense_pvddq_abc_ph1_imon" )
			)
			( signal "ISENSE_PVDDQ_ABC_PH2_IMON"
				( objectStatus "@baseboard_fab2_lib.baseboard_fab2(sch_1):isense_pvddq_abc_ph2_imon" )
			)
			( signal "PU_VR_PVDDQ_ABC_FAULT1"
				( objectStatus "@baseboard_fab2_lib.baseboard_fab2(sch_1):pu_vr_pvddq_abc_fault1" )
			)
			( signal "PWRGD_PVDDQ_ABC"
				( objectStatus "@baseboard_fab2_lib.baseboard_fab2(sch_1):pwrgd_pvddq_abc" )
			)
			( signal "PWRGD_PVDDQ_ABC_R"
				( objectStatus "@baseboard_fab2_lib.baseboard_fab2(sch_1):pwrgd_pvddq_abc_r" )
			)
			( signal "SVID_ALERT_PVDDQ_ABC"
				( objectStatus "@baseboard_fab2_lib.baseboard_fab2(sch_1):svid_alert_pvddq_abc" )
			)
			( signal "SVID_CLK_PVDDQ_ABC"
				( objectStatus "@baseboard_fab2_lib.baseboard_fab2(sch_1):svid_clk_pvddq_abc" )
			)
			( signal "SVID_VDIO_PVDDQ_ABC"
				( objectStatus "@baseboard_fab2_lib.baseboard_fab2(sch_1):svid_vdio_pvddq_abc" )
			)
			( signal "TP_PVDDQ_ABC_MP1"
				( objectStatus "@baseboard_fab2_lib.baseboard_fab2(sch_1):tp_pvddq_abc_mp1" )
			)
			( signal "TP_PVDDQ_ABC_MP2"
				( objectStatus "@baseboard_fab2_lib.baseboard_fab2(sch_1):tp_pvddq_abc_mp2" )
			)
			( signal "VR_FET_SW_P12V_STBY_PVDDQ_ABC"
				( objectStatus "@baseboard_fab2_lib.baseboard_fab2(sch_1):vr_fet_sw_p12v_stby_pvddq_abc" )
			)
			( signal "VR_PVDDQ_ABC_AIREF1"
				( objectStatus "@baseboard_fab2_lib.baseboard_fab2(sch_1):vr_pvddq_abc_airef1" )
			)
			( signal "VR_PVDDQ_ABC_AIREF2"
				( objectStatus "@baseboard_fab2_lib.baseboard_fab2(sch_1):vr_pvddq_abc_airef2" )
			)
			( signal "VR_PVDDQ_ABC_AVSP"
				( objectStatus "@baseboard_fab2_lib.baseboard_fab2(sch_1):vr_pvddq_abc_avsp" )
			)
			( signal "VR_PVDDQ_ABC_PWM1"
				( objectStatus "@baseboard_fab2_lib.baseboard_fab2(sch_1):vr_pvddq_abc_pwm1" )
			)
			( signal "VR_PVDDQ_ABC_PWM2"
				( objectStatus "@baseboard_fab2_lib.baseboard_fab2(sch_1):vr_pvddq_abc_pwm2" )
			)
			( signal "VR_PVDDQ_ABC_VD12"
				( objectStatus "@baseboard_fab2_lib.baseboard_fab2(sch_1):vr_pvddq_abc_vd12" )
			)
			( signal "VR_PVDDQ_ABC_VDD"
				( objectStatus "@baseboard_fab2_lib.baseboard_fab2(sch_1):vr_pvddq_abc_vdd" )
			)
			( signal "VR_PVDDQ_ABC_VINSEN"
				( objectStatus "@baseboard_fab2_lib.baseboard_fab2(sch_1):vr_pvddq_abc_vinsen" )
			)
			( signal "VR_PVDDQ_ABC_VREN"
				( objectStatus "@baseboard_fab2_lib.baseboard_fab2(sch_1):vr_pvddq_abc_vren" )
			)
			( signal "VR_PVDDQ_ABC_XADDR1"
				( objectStatus "@baseboard_fab2_lib.baseboard_fab2(sch_1):vr_pvddq_abc_xaddr1" )
			)
			( signal "VR_PVDDQ_ABC_XADDR2"
				( objectStatus "@baseboard_fab2_lib.baseboard_fab2(sch_1):vr_pvddq_abc_xaddr2" )
			)
			( signal "VSENSE_PVDDQ_ABC_N"
				( objectStatus "@baseboard_fab2_lib.baseboard_fab2(sch_1):vsense_pvddq_abc_n" )
			)
			( signal "VSENSE_PVDDQ_ABC_P"
				( objectStatus "@baseboard_fab2_lib.baseboard_fab2(sch_1):vsense_pvddq_abc_p" )
			)
			( signal "TP_PVDDQ_ABC_PH1_GL_0"
				( objectStatus "@baseboard_fab2_lib.baseboard_fab2(sch_1):tp_pvddq_abc_ph1_gl_0" )
			)
			( signal "TP_PVDDQ_ABC_PH1_GL_1"
				( objectStatus "@baseboard_fab2_lib.baseboard_fab2(sch_1):tp_pvddq_abc_ph1_gl_1" )
			)
			( signal "TP_PVDDQ_ABC_PH2_GL_0"
				( objectStatus "@baseboard_fab2_lib.baseboard_fab2(sch_1):tp_pvddq_abc_ph2_gl_0" )
			)
			( signal "TP_PVDDQ_ABC_PH2_GL_1"
				( objectStatus "@baseboard_fab2_lib.baseboard_fab2(sch_1):tp_pvddq_abc_ph2_gl_1" )
			)
			( signal "VR_PVDDQ_ABC_PH1_BOOT"
				( objectStatus "@baseboard_fab2_lib.baseboard_fab2(sch_1):vr_pvddq_abc_ph1_boot" )
			)
			( signal "VR_PVDDQ_ABC_PH1_OCSET"
				( attribute "VOLTAGE" "3.6"
					( Units "uVoltage" "V" 1.000000)
					( Status sAliasFlattened )
					( Origin gFrontEnd )
				)
				( objectStatus "@baseboard_fab2_lib.baseboard_fab2(sch_1):vr_pvddq_abc_ph1_ocset" )
			)
			( signal "VR_PVDDQ_ABC_PH1_PHASE"
				( objectStatus "@baseboard_fab2_lib.baseboard_fab2(sch_1):vr_pvddq_abc_ph1_phase" )
			)
			( signal "VR_PVDDQ_ABC_PH1_SW"
				( objectStatus "@baseboard_fab2_lib.baseboard_fab2(sch_1):vr_pvddq_abc_ph1_sw" )
			)
			( signal "VR_PVDDQ_ABC_PH1_VCIN"
				( objectStatus "@baseboard_fab2_lib.baseboard_fab2(sch_1):vr_pvddq_abc_ph1_vcin" )
			)
			( signal "VR_PVDDQ_ABC_PH2_BOOT"
				( objectStatus "@baseboard_fab2_lib.baseboard_fab2(sch_1):vr_pvddq_abc_ph2_boot" )
			)
			( signal "VR_PVDDQ_ABC_PH2_OCSET"
				( attribute "VOLTAGE" "3.6"
					( Units "uVoltage" "V" 1.000000)
					( Status sAliasFlattened )
					( Origin gFrontEnd )
				)
				( objectStatus "@baseboard_fab2_lib.baseboard_fab2(sch_1):vr_pvddq_abc_ph2_ocset" )
			)
			( signal "VR_PVDDQ_ABC_PH2_PHASE"
				( objectStatus "@baseboard_fab2_lib.baseboard_fab2(sch_1):vr_pvddq_abc_ph2_phase" )
			)
			( signal "VR_PVDDQ_ABC_PH2_SW"
				( objectStatus "@baseboard_fab2_lib.baseboard_fab2(sch_1):vr_pvddq_abc_ph2_sw" )
			)
			( signal "VR_PVDDQ_ABC_PH2_VCIN"
				( objectStatus "@baseboard_fab2_lib.baseboard_fab2(sch_1):vr_pvddq_abc_ph2_vcin" )
			)
			( signal "A_TSENSE_PVDDQ_DEF"
				( objectStatus "@baseboard_fab2_lib.baseboard_fab2(sch_1):a_tsense_pvddq_def" )
			)
			( signal "IRQ_PVDDQ_DEF_VRHOT_LVT3_R_N"
				( objectStatus "@baseboard_fab2_lib.baseboard_fab2(sch_1):irq_pvddq_def_vrhot_lvt3_r_n" )
			)
			( signal "ISENSE_PVDDQ_DEF_PH1_IMON"
				( objectStatus "@baseboard_fab2_lib.baseboard_fab2(sch_1):isense_pvddq_def_ph1_imon" )
			)
			( signal "ISENSE_PVDDQ_DEF_PH2_IMON"
				( objectStatus "@baseboard_fab2_lib.baseboard_fab2(sch_1):isense_pvddq_def_ph2_imon" )
			)
			( signal "PU_VR_PVDDQ_DEF_FAULT1"
				( objectStatus "@baseboard_fab2_lib.baseboard_fab2(sch_1):pu_vr_pvddq_def_fault1" )
			)
			( signal "PWRGD_PVDDQ_DEF"
				( objectStatus "@baseboard_fab2_lib.baseboard_fab2(sch_1):pwrgd_pvddq_def" )
			)
			( signal "PWRGD_PVDDQ_DEF_R"
				( objectStatus "@baseboard_fab2_lib.baseboard_fab2(sch_1):pwrgd_pvddq_def_r" )
			)
			( signal "SVID_ALERT_PVDDQ_DEF"
				( objectStatus "@baseboard_fab2_lib.baseboard_fab2(sch_1):svid_alert_pvddq_def" )
			)
			( signal "SVID_CLK_PVDDQ_DEF"
				( objectStatus "@baseboard_fab2_lib.baseboard_fab2(sch_1):svid_clk_pvddq_def" )
			)
			( signal "SVID_VDIO_PVDDQ_DEF"
				( objectStatus "@baseboard_fab2_lib.baseboard_fab2(sch_1):svid_vdio_pvddq_def" )
			)
			( signal "TP_PVDDQ_DEF_MP1"
				( objectStatus "@baseboard_fab2_lib.baseboard_fab2(sch_1):tp_pvddq_def_mp1" )
			)
			( signal "TP_PVDDQ_DEF_MP2"
				( objectStatus "@baseboard_fab2_lib.baseboard_fab2(sch_1):tp_pvddq_def_mp2" )
			)
			( signal "VR_FET_SW_P12V_STBY_PVDDQ_DEF"
				( objectStatus "@baseboard_fab2_lib.baseboard_fab2(sch_1):vr_fet_sw_p12v_stby_pvddq_def" )
			)
			( signal "VR_PVDDQ_DEF_AIREF1"
				( objectStatus "@baseboard_fab2_lib.baseboard_fab2(sch_1):vr_pvddq_def_airef1" )
			)
			( signal "VR_PVDDQ_DEF_AIREF2"
				( objectStatus "@baseboard_fab2_lib.baseboard_fab2(sch_1):vr_pvddq_def_airef2" )
			)
			( signal "VR_PVDDQ_DEF_AVSP"
				( objectStatus "@baseboard_fab2_lib.baseboard_fab2(sch_1):vr_pvddq_def_avsp" )
			)
			( signal "VR_PVDDQ_DEF_PWM1"
				( objectStatus "@baseboard_fab2_lib.baseboard_fab2(sch_1):vr_pvddq_def_pwm1" )
			)
			( signal "VR_PVDDQ_DEF_PWM2"
				( objectStatus "@baseboard_fab2_lib.baseboard_fab2(sch_1):vr_pvddq_def_pwm2" )
			)
			( signal "VR_PVDDQ_DEF_VD12"
				( objectStatus "@baseboard_fab2_lib.baseboard_fab2(sch_1):vr_pvddq_def_vd12" )
			)
			( signal "VR_PVDDQ_DEF_VDD"
				( objectStatus "@baseboard_fab2_lib.baseboard_fab2(sch_1):vr_pvddq_def_vdd" )
			)
			( signal "VR_PVDDQ_DEF_VINSEN"
				( objectStatus "@baseboard_fab2_lib.baseboard_fab2(sch_1):vr_pvddq_def_vinsen" )
			)
			( signal "VR_PVDDQ_DEF_VREN"
				( objectStatus "@baseboard_fab2_lib.baseboard_fab2(sch_1):vr_pvddq_def_vren" )
			)
			( signal "VR_PVDDQ_DEF_XADDR1"
				( objectStatus "@baseboard_fab2_lib.baseboard_fab2(sch_1):vr_pvddq_def_xaddr1" )
			)
			( signal "VR_PVDDQ_DEF_XADDR2"
				( objectStatus "@baseboard_fab2_lib.baseboard_fab2(sch_1):vr_pvddq_def_xaddr2" )
			)
			( signal "VSENSE_PVDDQ_DEF_N"
				( objectStatus "@baseboard_fab2_lib.baseboard_fab2(sch_1):vsense_pvddq_def_n" )
			)
			( signal "VSENSE_PVDDQ_DEF_P"
				( objectStatus "@baseboard_fab2_lib.baseboard_fab2(sch_1):vsense_pvddq_def_p" )
			)
			( signal "TP_PVDDQ_DEF_PH1_GL_0"
				( objectStatus "@baseboard_fab2_lib.baseboard_fab2(sch_1):tp_pvddq_def_ph1_gl_0" )
			)
			( signal "TP_PVDDQ_DEF_PH1_GL_1"
				( objectStatus "@baseboard_fab2_lib.baseboard_fab2(sch_1):tp_pvddq_def_ph1_gl_1" )
			)
			( signal "TP_PVDDQ_DEF_PH2_GL_0"
				( objectStatus "@baseboard_fab2_lib.baseboard_fab2(sch_1):tp_pvddq_def_ph2_gl_0" )
			)
			( signal "TP_PVDDQ_DEF_PH2_GL_1"
				( objectStatus "@baseboard_fab2_lib.baseboard_fab2(sch_1):tp_pvddq_def_ph2_gl_1" )
			)
			( signal "VR_PVDDQ_DEF_PH1_BOOT"
				( objectStatus "@baseboard_fab2_lib.baseboard_fab2(sch_1):vr_pvddq_def_ph1_boot" )
			)
			( signal "VR_PVDDQ_DEF_PH1_OCSET"
				( attribute "VOLTAGE" "3.6"
					( Units "uVoltage" "V" 1.000000)
					( Status sAliasFlattened )
					( Origin gFrontEnd )
				)
				( objectStatus "@baseboard_fab2_lib.baseboard_fab2(sch_1):vr_pvddq_def_ph1_ocset" )
			)
			( signal "VR_PVDDQ_DEF_PH1_PHASE"
				( objectStatus "@baseboard_fab2_lib.baseboard_fab2(sch_1):vr_pvddq_def_ph1_phase" )
			)
			( signal "VR_PVDDQ_DEF_PH1_SW"
				( objectStatus "@baseboard_fab2_lib.baseboard_fab2(sch_1):vr_pvddq_def_ph1_sw" )
			)
			( signal "VR_PVDDQ_DEF_PH1_VCIN"
				( objectStatus "@baseboard_fab2_lib.baseboard_fab2(sch_1):vr_pvddq_def_ph1_vcin" )
			)
			( signal "VR_PVDDQ_DEF_PH2_BOOT"
				( objectStatus "@baseboard_fab2_lib.baseboard_fab2(sch_1):vr_pvddq_def_ph2_boot" )
			)
			( signal "VR_PVDDQ_DEF_PH2_OCSET"
				( attribute "VOLTAGE" "3.6"
					( Units "uVoltage" "V" 1.000000)
					( Status sAliasFlattened )
					( Origin gFrontEnd )
				)
				( objectStatus "@baseboard_fab2_lib.baseboard_fab2(sch_1):vr_pvddq_def_ph2_ocset" )
			)
			( signal "VR_PVDDQ_DEF_PH2_PHASE"
				( objectStatus "@baseboard_fab2_lib.baseboard_fab2(sch_1):vr_pvddq_def_ph2_phase" )
			)
			( signal "VR_PVDDQ_DEF_PH2_SW"
				( objectStatus "@baseboard_fab2_lib.baseboard_fab2(sch_1):vr_pvddq_def_ph2_sw" )
			)
			( signal "VR_PVDDQ_DEF_PH2_VCIN"
				( objectStatus "@baseboard_fab2_lib.baseboard_fab2(sch_1):vr_pvddq_def_ph2_vcin" )
			)
			( signal "FM_PVTT_ABC_EN_R"
				( objectStatus "@baseboard_fab2_lib.baseboard_fab2(sch_1):fm_pvtt_abc_en_r" )
			)
			( signal "PWRGD_PVTT_ABC_CPU0_R"
				( objectStatus "@baseboard_fab2_lib.baseboard_fab2(sch_1):pwrgd_pvtt_abc_cpu0_r" )
			)
			( signal "VR_PVTT_ABC_BIAS"
				( objectStatus "@baseboard_fab2_lib.baseboard_fab2(sch_1):vr_pvtt_abc_bias" )
			)
			( signal "VR_PVTT_ABC_SNS"
				( objectStatus "@baseboard_fab2_lib.baseboard_fab2(sch_1):vr_pvtt_abc_sns" )
			)
			( signal "VR_PVTT_ABC_VREF"
				( objectStatus "@baseboard_fab2_lib.baseboard_fab2(sch_1):vr_pvtt_abc_vref" )
			)
			( signal "VSENSE_PVDDQ_ABC_VTT"
				( objectStatus "@baseboard_fab2_lib.baseboard_fab2(sch_1):vsense_pvddq_abc_vtt" )
			)
			( signal "FM_PVTT_DEF_EN_R"
				( objectStatus "@baseboard_fab2_lib.baseboard_fab2(sch_1):fm_pvtt_def_en_r" )
			)
			( signal "PWRGD_PVTT_DEF_CPU0_R"
				( objectStatus "@baseboard_fab2_lib.baseboard_fab2(sch_1):pwrgd_pvtt_def_cpu0_r" )
			)
			( signal "VR_PVTT_DEF_BIAS"
				( objectStatus "@baseboard_fab2_lib.baseboard_fab2(sch_1):vr_pvtt_def_bias" )
			)
			( signal "VR_PVTT_DEF_SNS"
				( objectStatus "@baseboard_fab2_lib.baseboard_fab2(sch_1):vr_pvtt_def_sns" )
			)
			( signal "VR_PVTT_DEF_VREF"
				( objectStatus "@baseboard_fab2_lib.baseboard_fab2(sch_1):vr_pvtt_def_vref" )
			)
			( signal "VSENSE_PVDDQ_DEF_VTT"
				( objectStatus "@baseboard_fab2_lib.baseboard_fab2(sch_1):vsense_pvddq_def_vtt" )
			)
			( signal "A_TSENSE_PVDDQ_GHJ"
				( objectStatus "@baseboard_fab2_lib.baseboard_fab2(sch_1):a_tsense_pvddq_ghj" )
			)
			( signal "IRQ_PVDDQ_GHJ_VRHOT_LVT3_R_N"
				( objectStatus "@baseboard_fab2_lib.baseboard_fab2(sch_1):irq_pvddq_ghj_vrhot_lvt3_r_n" )
			)
			( signal "ISENSE_PVDDQ_GHJ_PH1_IMON"
				( objectStatus "@baseboard_fab2_lib.baseboard_fab2(sch_1):isense_pvddq_ghj_ph1_imon" )
			)
			( signal "ISENSE_PVDDQ_GHJ_PH2_IMON"
				( objectStatus "@baseboard_fab2_lib.baseboard_fab2(sch_1):isense_pvddq_ghj_ph2_imon" )
			)
			( signal "PU_VR_PVDDQ_GHJ_FAULT1"
				( objectStatus "@baseboard_fab2_lib.baseboard_fab2(sch_1):pu_vr_pvddq_ghj_fault1" )
			)
			( signal "PWRGD_PVDDQ_GHJ"
				( objectStatus "@baseboard_fab2_lib.baseboard_fab2(sch_1):pwrgd_pvddq_ghj" )
			)
			( signal "PWRGD_PVDDQ_GHJ_R"
				( objectStatus "@baseboard_fab2_lib.baseboard_fab2(sch_1):pwrgd_pvddq_ghj_r" )
			)
			( signal "SVID_ALERT_PVDDQ_GHJ"
				( objectStatus "@baseboard_fab2_lib.baseboard_fab2(sch_1):svid_alert_pvddq_ghj" )
			)
			( signal "SVID_CLK_PVDDQ_GHJ"
				( objectStatus "@baseboard_fab2_lib.baseboard_fab2(sch_1):svid_clk_pvddq_ghj" )
			)
			( signal "SVID_VDIO_PVDDQ_GHJ"
				( objectStatus "@baseboard_fab2_lib.baseboard_fab2(sch_1):svid_vdio_pvddq_ghj" )
			)
			( signal "TP_PVDDQ_GHJ_MP1"
				( objectStatus "@baseboard_fab2_lib.baseboard_fab2(sch_1):tp_pvddq_ghj_mp1" )
			)
			( signal "TP_PVDDQ_GHJ_MP2"
				( objectStatus "@baseboard_fab2_lib.baseboard_fab2(sch_1):tp_pvddq_ghj_mp2" )
			)
			( signal "VR_FET_SW_P12V_STBY_PVDDQ_GHJ"
				( objectStatus "@baseboard_fab2_lib.baseboard_fab2(sch_1):vr_fet_sw_p12v_stby_pvddq_ghj" )
			)
			( signal "VR_PVDDQ_GHJ_AIREF1"
				( objectStatus "@baseboard_fab2_lib.baseboard_fab2(sch_1):vr_pvddq_ghj_airef1" )
			)
			( signal "VR_PVDDQ_GHJ_AIREF2"
				( objectStatus "@baseboard_fab2_lib.baseboard_fab2(sch_1):vr_pvddq_ghj_airef2" )
			)
			( signal "VR_PVDDQ_GHJ_AVSP"
				( objectStatus "@baseboard_fab2_lib.baseboard_fab2(sch_1):vr_pvddq_ghj_avsp" )
			)
			( signal "VR_PVDDQ_GHJ_PWM1"
				( objectStatus "@baseboard_fab2_lib.baseboard_fab2(sch_1):vr_pvddq_ghj_pwm1" )
			)
			( signal "VR_PVDDQ_GHJ_PWM2"
				( objectStatus "@baseboard_fab2_lib.baseboard_fab2(sch_1):vr_pvddq_ghj_pwm2" )
			)
			( signal "VR_PVDDQ_GHJ_VD12"
				( objectStatus "@baseboard_fab2_lib.baseboard_fab2(sch_1):vr_pvddq_ghj_vd12" )
			)
			( signal "VR_PVDDQ_GHJ_VDD"
				( objectStatus "@baseboard_fab2_lib.baseboard_fab2(sch_1):vr_pvddq_ghj_vdd" )
			)
			( signal "VR_PVDDQ_GHJ_VINSEN"
				( objectStatus "@baseboard_fab2_lib.baseboard_fab2(sch_1):vr_pvddq_ghj_vinsen" )
			)
			( signal "VR_PVDDQ_GHJ_VREN"
				( objectStatus "@baseboard_fab2_lib.baseboard_fab2(sch_1):vr_pvddq_ghj_vren" )
			)
			( signal "VR_PVDDQ_GHJ_XADDR1"
				( objectStatus "@baseboard_fab2_lib.baseboard_fab2(sch_1):vr_pvddq_ghj_xaddr1" )
			)
			( signal "VR_PVDDQ_GHJ_XADDR2"
				( objectStatus "@baseboard_fab2_lib.baseboard_fab2(sch_1):vr_pvddq_ghj_xaddr2" )
			)
			( signal "VSENSE_PVDDQ_GHJ_N"
				( objectStatus "@baseboard_fab2_lib.baseboard_fab2(sch_1):vsense_pvddq_ghj_n" )
			)
			( signal "VSENSE_PVDDQ_GHJ_P"
				( objectStatus "@baseboard_fab2_lib.baseboard_fab2(sch_1):vsense_pvddq_ghj_p" )
			)
			( signal "TP_PVDDQ_GHJ_PH1_GL_0"
				( objectStatus "@baseboard_fab2_lib.baseboard_fab2(sch_1):tp_pvddq_ghj_ph1_gl_0" )
			)
			( signal "TP_PVDDQ_GHJ_PH1_GL_1"
				( objectStatus "@baseboard_fab2_lib.baseboard_fab2(sch_1):tp_pvddq_ghj_ph1_gl_1" )
			)
			( signal "TP_PVDDQ_GHJ_PH2_GL_0"
				( objectStatus "@baseboard_fab2_lib.baseboard_fab2(sch_1):tp_pvddq_ghj_ph2_gl_0" )
			)
			( signal "TP_PVDDQ_GHJ_PH2_GL_1"
				( objectStatus "@baseboard_fab2_lib.baseboard_fab2(sch_1):tp_pvddq_ghj_ph2_gl_1" )
			)
			( signal "VR_PVDDQ_GHJ_PH1_BOOT"
				( objectStatus "@baseboard_fab2_lib.baseboard_fab2(sch_1):vr_pvddq_ghj_ph1_boot" )
			)
			( signal "VR_PVDDQ_GHJ_PH1_OCSET"
				( attribute "VOLTAGE" "3.6"
					( Units "uVoltage" "V" 1.000000)
					( Status sAliasFlattened )
					( Origin gFrontEnd )
				)
				( objectStatus "@baseboard_fab2_lib.baseboard_fab2(sch_1):vr_pvddq_ghj_ph1_ocset" )
			)
			( signal "VR_PVDDQ_GHJ_PH1_PHASE"
				( objectStatus "@baseboard_fab2_lib.baseboard_fab2(sch_1):vr_pvddq_ghj_ph1_phase" )
			)
			( signal "VR_PVDDQ_GHJ_PH1_SW"
				( objectStatus "@baseboard_fab2_lib.baseboard_fab2(sch_1):vr_pvddq_ghj_ph1_sw" )
			)
			( signal "VR_PVDDQ_GHJ_PH1_VCIN"
				( objectStatus "@baseboard_fab2_lib.baseboard_fab2(sch_1):vr_pvddq_ghj_ph1_vcin" )
			)
			( signal "VR_PVDDQ_GHJ_PH2_BOOT"
				( objectStatus "@baseboard_fab2_lib.baseboard_fab2(sch_1):vr_pvddq_ghj_ph2_boot" )
			)
			( signal "VR_PVDDQ_GHJ_PH2_OCSET"
				( attribute "VOLTAGE" "3.6"
					( Units "uVoltage" "V" 1.000000)
					( Status sAliasFlattened )
					( Origin gFrontEnd )
				)
				( objectStatus "@baseboard_fab2_lib.baseboard_fab2(sch_1):vr_pvddq_ghj_ph2_ocset" )
			)
			( signal "VR_PVDDQ_GHJ_PH2_PHASE"
				( objectStatus "@baseboard_fab2_lib.baseboard_fab2(sch_1):vr_pvddq_ghj_ph2_phase" )
			)
			( signal "VR_PVDDQ_GHJ_PH2_SW"
				( objectStatus "@baseboard_fab2_lib.baseboard_fab2(sch_1):vr_pvddq_ghj_ph2_sw" )
			)
			( signal "VR_PVDDQ_GHJ_PH2_VCIN"
				( objectStatus "@baseboard_fab2_lib.baseboard_fab2(sch_1):vr_pvddq_ghj_ph2_vcin" )
			)
			( signal "A_TSENSE_PVDDQ_KLM"
				( objectStatus "@baseboard_fab2_lib.baseboard_fab2(sch_1):a_tsense_pvddq_klm" )
			)
			( signal "IRQ_PVDDQ_KLM_VRHOT_LVT3_R_N"
				( objectStatus "@baseboard_fab2_lib.baseboard_fab2(sch_1):irq_pvddq_klm_vrhot_lvt3_r_n" )
			)
			( signal "ISENSE_PVDDQ_KLM_PH1_IMON"
				( objectStatus "@baseboard_fab2_lib.baseboard_fab2(sch_1):isense_pvddq_klm_ph1_imon" )
			)
			( signal "ISENSE_PVDDQ_KLM_PH2_IMON"
				( objectStatus "@baseboard_fab2_lib.baseboard_fab2(sch_1):isense_pvddq_klm_ph2_imon" )
			)
			( signal "NC_PVDDQ_KLM_GP0"
				( objectStatus "@baseboard_fab2_lib.baseboard_fab2(sch_1):nc_pvddq_klm_gp0" )
			)
			( signal "NC_PVDDQ_KLM_GP1"
				( objectStatus "@baseboard_fab2_lib.baseboard_fab2(sch_1):nc_pvddq_klm_gp1" )
			)
			( signal "PU_VR_PVDDQ_KLM_FAULT1"
				( objectStatus "@baseboard_fab2_lib.baseboard_fab2(sch_1):pu_vr_pvddq_klm_fault1" )
			)
			( signal "PWRGD_PVDDQ_KLM"
				( objectStatus "@baseboard_fab2_lib.baseboard_fab2(sch_1):pwrgd_pvddq_klm" )
			)
			( signal "PWRGD_PVDDQ_KLM_R"
				( objectStatus "@baseboard_fab2_lib.baseboard_fab2(sch_1):pwrgd_pvddq_klm_r" )
			)
			( signal "SVID_ALERT_PVDDQ_KLM"
				( objectStatus "@baseboard_fab2_lib.baseboard_fab2(sch_1):svid_alert_pvddq_klm" )
			)
			( signal "SVID_CLK_PVDDQ_KLM"
				( objectStatus "@baseboard_fab2_lib.baseboard_fab2(sch_1):svid_clk_pvddq_klm" )
			)
			( signal "SVID_VDIO_PVDDQ_KLM"
				( objectStatus "@baseboard_fab2_lib.baseboard_fab2(sch_1):svid_vdio_pvddq_klm" )
			)
			( signal "VR_FET_SW_P12V_STBY_PVDDQ_KLM"
				( objectStatus "@baseboard_fab2_lib.baseboard_fab2(sch_1):vr_fet_sw_p12v_stby_pvddq_klm" )
			)
			( signal "VR_PVDDQ_KLM_AIREF1"
				( objectStatus "@baseboard_fab2_lib.baseboard_fab2(sch_1):vr_pvddq_klm_airef1" )
			)
			( signal "VR_PVDDQ_KLM_AIREF2"
				( objectStatus "@baseboard_fab2_lib.baseboard_fab2(sch_1):vr_pvddq_klm_airef2" )
			)
			( signal "VR_PVDDQ_KLM_AVSP"
				( objectStatus "@baseboard_fab2_lib.baseboard_fab2(sch_1):vr_pvddq_klm_avsp" )
			)
			( signal "VR_PVDDQ_KLM_PWM1"
				( objectStatus "@baseboard_fab2_lib.baseboard_fab2(sch_1):vr_pvddq_klm_pwm1" )
			)
			( signal "VR_PVDDQ_KLM_PWM2"
				( objectStatus "@baseboard_fab2_lib.baseboard_fab2(sch_1):vr_pvddq_klm_pwm2" )
			)
			( signal "VR_PVDDQ_KLM_VD12"
				( objectStatus "@baseboard_fab2_lib.baseboard_fab2(sch_1):vr_pvddq_klm_vd12" )
			)
			( signal "VR_PVDDQ_KLM_VDD"
				( objectStatus "@baseboard_fab2_lib.baseboard_fab2(sch_1):vr_pvddq_klm_vdd" )
			)
			( signal "VR_PVDDQ_KLM_VINSEN"
				( objectStatus "@baseboard_fab2_lib.baseboard_fab2(sch_1):vr_pvddq_klm_vinsen" )
			)
			( signal "VR_PVDDQ_KLM_VREN"
				( objectStatus "@baseboard_fab2_lib.baseboard_fab2(sch_1):vr_pvddq_klm_vren" )
			)
			( signal "VR_PVDDQ_KLM_XADDR1"
				( objectStatus "@baseboard_fab2_lib.baseboard_fab2(sch_1):vr_pvddq_klm_xaddr1" )
			)
			( signal "VR_PVDDQ_KLM_XADDR2"
				( objectStatus "@baseboard_fab2_lib.baseboard_fab2(sch_1):vr_pvddq_klm_xaddr2" )
			)
			( signal "VSENSE_PVDDQ_KLM_N"
				( objectStatus "@baseboard_fab2_lib.baseboard_fab2(sch_1):vsense_pvddq_klm_n" )
			)
			( signal "VSENSE_PVDDQ_KLM_P"
				( objectStatus "@baseboard_fab2_lib.baseboard_fab2(sch_1):vsense_pvddq_klm_p" )
			)
			( signal "TP_PVDDQ_KLM_PH1_GL_0"
				( objectStatus "@baseboard_fab2_lib.baseboard_fab2(sch_1):tp_pvddq_klm_ph1_gl_0" )
			)
			( signal "TP_PVDDQ_KLM_PH1_GL_1"
				( objectStatus "@baseboard_fab2_lib.baseboard_fab2(sch_1):tp_pvddq_klm_ph1_gl_1" )
			)
			( signal "TP_PVDDQ_KLM_PH2_GL_0"
				( objectStatus "@baseboard_fab2_lib.baseboard_fab2(sch_1):tp_pvddq_klm_ph2_gl_0" )
			)
			( signal "TP_PVDDQ_KLM_PH2_GL_1"
				( objectStatus "@baseboard_fab2_lib.baseboard_fab2(sch_1):tp_pvddq_klm_ph2_gl_1" )
			)
			( signal "VR_PVDDQ_KLM_PH1_BOOT"
				( objectStatus "@baseboard_fab2_lib.baseboard_fab2(sch_1):vr_pvddq_klm_ph1_boot" )
			)
			( signal "VR_PVDDQ_KLM_PH1_OCSET"
				( attribute "VOLTAGE" "3.6"
					( Units "uVoltage" "V" 1.000000)
					( Status sAliasFlattened )
					( Origin gFrontEnd )
				)
				( objectStatus "@baseboard_fab2_lib.baseboard_fab2(sch_1):vr_pvddq_klm_ph1_ocset" )
			)
			( signal "VR_PVDDQ_KLM_PH1_PHASE"
				( objectStatus "@baseboard_fab2_lib.baseboard_fab2(sch_1):vr_pvddq_klm_ph1_phase" )
			)
			( signal "VR_PVDDQ_KLM_PH1_SW"
				( objectStatus "@baseboard_fab2_lib.baseboard_fab2(sch_1):vr_pvddq_klm_ph1_sw" )
			)
			( signal "VR_PVDDQ_KLM_PH1_VCIN"
				( objectStatus "@baseboard_fab2_lib.baseboard_fab2(sch_1):vr_pvddq_klm_ph1_vcin" )
			)
			( signal "VR_PVDDQ_KLM_PH2_BOOT"
				( objectStatus "@baseboard_fab2_lib.baseboard_fab2(sch_1):vr_pvddq_klm_ph2_boot" )
			)
			( signal "VR_PVDDQ_KLM_PH2_OCSET"
				( attribute "VOLTAGE" "3.6"
					( Units "uVoltage" "V" 1.000000)
					( Status sAliasFlattened )
					( Origin gFrontEnd )
				)
				( objectStatus "@baseboard_fab2_lib.baseboard_fab2(sch_1):vr_pvddq_klm_ph2_ocset" )
			)
			( signal "VR_PVDDQ_KLM_PH2_PHASE"
				( objectStatus "@baseboard_fab2_lib.baseboard_fab2(sch_1):vr_pvddq_klm_ph2_phase" )
			)
			( signal "VR_PVDDQ_KLM_PH2_SW"
				( objectStatus "@baseboard_fab2_lib.baseboard_fab2(sch_1):vr_pvddq_klm_ph2_sw" )
			)
			( signal "VR_PVDDQ_KLM_PH2_VCIN"
				( objectStatus "@baseboard_fab2_lib.baseboard_fab2(sch_1):vr_pvddq_klm_ph2_vcin" )
			)
			( signal "FM_PVTT_GHJ_EN_R"
				( objectStatus "@baseboard_fab2_lib.baseboard_fab2(sch_1):fm_pvtt_ghj_en_r" )
			)
			( signal "PWRGD_PVTT_GHJ_CPU1_R"
				( objectStatus "@baseboard_fab2_lib.baseboard_fab2(sch_1):pwrgd_pvtt_ghj_cpu1_r" )
			)
			( signal "VR_PVTT_GHJ_BIAS"
				( objectStatus "@baseboard_fab2_lib.baseboard_fab2(sch_1):vr_pvtt_ghj_bias" )
			)
			( signal "VR_PVTT_GHJ_SNS"
				( objectStatus "@baseboard_fab2_lib.baseboard_fab2(sch_1):vr_pvtt_ghj_sns" )
			)
			( signal "VR_PVTT_GHJ_VREF"
				( objectStatus "@baseboard_fab2_lib.baseboard_fab2(sch_1):vr_pvtt_ghj_vref" )
			)
			( signal "VSENSE_PVDDQ_GHJ_VTT"
				( objectStatus "@baseboard_fab2_lib.baseboard_fab2(sch_1):vsense_pvddq_ghj_vtt" )
			)
			( signal "FM_PVTT_KLM_EN_R"
				( objectStatus "@baseboard_fab2_lib.baseboard_fab2(sch_1):fm_pvtt_klm_en_r" )
			)
			( signal "PWRGD_PVTT_KLM_CPU1_R"
				( objectStatus "@baseboard_fab2_lib.baseboard_fab2(sch_1):pwrgd_pvtt_klm_cpu1_r" )
			)
			( signal "VR_PVTT_KLM_BIAS"
				( objectStatus "@baseboard_fab2_lib.baseboard_fab2(sch_1):vr_pvtt_klm_bias" )
			)
			( signal "VR_PVTT_KLM_SNS"
				( objectStatus "@baseboard_fab2_lib.baseboard_fab2(sch_1):vr_pvtt_klm_sns" )
			)
			( signal "VR_PVTT_KLM_VREF"
				( objectStatus "@baseboard_fab2_lib.baseboard_fab2(sch_1):vr_pvtt_klm_vref" )
			)
			( signal "VSENSE_PVDDQ_KLM_VTT"
				( objectStatus "@baseboard_fab2_lib.baseboard_fab2(sch_1):vsense_pvddq_klm_vtt" )
			)
			( signal "AGND_PVPP_ABC"
				( attribute "VOLTAGE" "0.0V"
					( Units "uVoltage" "V" 1.000000)
					( Status sAliasFlattened )
					( Origin gFrontEnd )
				)
				( objectStatus "@baseboard_fab2_lib.baseboard_fab2(sch_1):agnd_pvpp_abc" )
			)
			( signal "FM_PVPP_PVDDQ_CPU0_EN_ABC"
				( objectStatus "@baseboard_fab2_lib.baseboard_fab2(sch_1):fm_pvpp_pvddq_cpu0_en_abc" )
			)
			( signal "PWRGD_PVPP_ABC_R"
				( objectStatus "@baseboard_fab2_lib.baseboard_fab2(sch_1):pwrgd_pvpp_abc_r" )
			)
			( signal "VR_COMP_PVPP_ABC"
				( objectStatus "@baseboard_fab2_lib.baseboard_fab2(sch_1):vr_comp_pvpp_abc" )
			)
			( signal "VR_COMP_PVPP_ABC_3"
				( objectStatus "@baseboard_fab2_lib.baseboard_fab2(sch_1):vr_comp_pvpp_abc_3" )
			)
			( signal "VR_COMP_RC_PVPP_ABC"
				( objectStatus "@baseboard_fab2_lib.baseboard_fab2(sch_1):vr_comp_rc_pvpp_abc" )
			)
			( signal "VR_FB_PVPP_ABC"
				( objectStatus "@baseboard_fab2_lib.baseboard_fab2(sch_1):vr_fb_pvpp_abc" )
			)
			( signal "VR_FET_SW_P12V_STBY_PVPP_ABC"
				( objectStatus "@baseboard_fab2_lib.baseboard_fab2(sch_1):vr_fet_sw_p12v_stby_pvpp_abc" )
			)
			( signal "VR_PVPP_ABC_BOOT"
				( objectStatus "@baseboard_fab2_lib.baseboard_fab2(sch_1):vr_pvpp_abc_boot" )
			)
			( signal "VR_PVPP_ABC_BOOT_R"
				( objectStatus "@baseboard_fab2_lib.baseboard_fab2(sch_1):vr_pvpp_abc_boot_r" )
			)
			( signal "VR_PVPP_ABC_ISET"
				( objectStatus "@baseboard_fab2_lib.baseboard_fab2(sch_1):vr_pvpp_abc_iset" )
			)
			( signal "VR_PVPP_ABC_PHASE"
				( objectStatus "@baseboard_fab2_lib.baseboard_fab2(sch_1):vr_pvpp_abc_phase" )
			)
			( signal "VR_PVPP_ABC_SNUB"
				( objectStatus "@baseboard_fab2_lib.baseboard_fab2(sch_1):vr_pvpp_abc_snub" )
			)
			( signal "VR_PVPP_ABC_SS"
				( objectStatus "@baseboard_fab2_lib.baseboard_fab2(sch_1):vr_pvpp_abc_ss" )
			)
			( signal "VR_VB_PVPP_ABC"
				( objectStatus "@baseboard_fab2_lib.baseboard_fab2(sch_1):vr_vb_pvpp_abc" )
			)
			( signal "VSENSE_PVPP_ABC"
				( objectStatus "@baseboard_fab2_lib.baseboard_fab2(sch_1):vsense_pvpp_abc" )
			)
			( signal "AGND_PVPP_DEF"
				( attribute "VOLTAGE" "0.0V"
					( Units "uVoltage" "V" 1.000000)
					( Status sAliasFlattened )
					( Origin gFrontEnd )
				)
				( objectStatus "@baseboard_fab2_lib.baseboard_fab2(sch_1):agnd_pvpp_def" )
			)
			( signal "FM_PVPP_PVDDQ_CPU0_EN_DEF"
				( objectStatus "@baseboard_fab2_lib.baseboard_fab2(sch_1):fm_pvpp_pvddq_cpu0_en_def" )
			)
			( signal "PWRGD_PVPP_DEF_R"
				( objectStatus "@baseboard_fab2_lib.baseboard_fab2(sch_1):pwrgd_pvpp_def_r" )
			)
			( signal "VR_COMP_PVPP_DEF"
				( objectStatus "@baseboard_fab2_lib.baseboard_fab2(sch_1):vr_comp_pvpp_def" )
			)
			( signal "VR_COMP_PVPP_DEF_3"
				( objectStatus "@baseboard_fab2_lib.baseboard_fab2(sch_1):vr_comp_pvpp_def_3" )
			)
			( signal "VR_COMP_RC_PVPP_DEF"
				( objectStatus "@baseboard_fab2_lib.baseboard_fab2(sch_1):vr_comp_rc_pvpp_def" )
			)
			( signal "VR_FB_PVPP_DEF"
				( objectStatus "@baseboard_fab2_lib.baseboard_fab2(sch_1):vr_fb_pvpp_def" )
			)
			( signal "VR_FET_SW_P12V_STBY_PVPP_DEF"
				( objectStatus "@baseboard_fab2_lib.baseboard_fab2(sch_1):vr_fet_sw_p12v_stby_pvpp_def" )
			)
			( signal "VR_PVPP_DEF_BOOT"
				( objectStatus "@baseboard_fab2_lib.baseboard_fab2(sch_1):vr_pvpp_def_boot" )
			)
			( signal "VR_PVPP_DEF_BOOT_R"
				( objectStatus "@baseboard_fab2_lib.baseboard_fab2(sch_1):vr_pvpp_def_boot_r" )
			)
			( signal "VR_PVPP_DEF_ISET"
				( objectStatus "@baseboard_fab2_lib.baseboard_fab2(sch_1):vr_pvpp_def_iset" )
			)
			( signal "VR_PVPP_DEF_PHASE"
				( objectStatus "@baseboard_fab2_lib.baseboard_fab2(sch_1):vr_pvpp_def_phase" )
			)
			( signal "VR_PVPP_DEF_SNUB"
				( objectStatus "@baseboard_fab2_lib.baseboard_fab2(sch_1):vr_pvpp_def_snub" )
			)
			( signal "VR_PVPP_DEF_SS"
				( objectStatus "@baseboard_fab2_lib.baseboard_fab2(sch_1):vr_pvpp_def_ss" )
			)
			( signal "VR_VB_PVPP_DEF"
				( objectStatus "@baseboard_fab2_lib.baseboard_fab2(sch_1):vr_vb_pvpp_def" )
			)
			( signal "VSENSE_PVPP_DEF"
				( objectStatus "@baseboard_fab2_lib.baseboard_fab2(sch_1):vsense_pvpp_def" )
			)
			( signal "AGND_PVPP_GHJ"
				( attribute "VOLTAGE" "0.0V"
					( Units "uVoltage" "V" 1.000000)
					( Status sAliasFlattened )
					( Origin gFrontEnd )
				)
				( objectStatus "@baseboard_fab2_lib.baseboard_fab2(sch_1):agnd_pvpp_ghj" )
			)
			( signal "FM_PVPP_PVDDQ_CPU1_EN_GHJ"
				( objectStatus "@baseboard_fab2_lib.baseboard_fab2(sch_1):fm_pvpp_pvddq_cpu1_en_ghj" )
			)
			( signal "PWRGD_PVPP_GHJ_R"
				( objectStatus "@baseboard_fab2_lib.baseboard_fab2(sch_1):pwrgd_pvpp_ghj_r" )
			)
			( signal "VR_COMP_PVPP_GHJ"
				( objectStatus "@baseboard_fab2_lib.baseboard_fab2(sch_1):vr_comp_pvpp_ghj" )
			)
			( signal "VR_COMP_PVPP_GHJ_3"
				( objectStatus "@baseboard_fab2_lib.baseboard_fab2(sch_1):vr_comp_pvpp_ghj_3" )
			)
			( signal "VR_COMP_RC_PVPP_GHJ"
				( objectStatus "@baseboard_fab2_lib.baseboard_fab2(sch_1):vr_comp_rc_pvpp_ghj" )
			)
			( signal "VR_FB_PVPP_GHJ"
				( objectStatus "@baseboard_fab2_lib.baseboard_fab2(sch_1):vr_fb_pvpp_ghj" )
			)
			( signal "VR_FET_SW_P12V_STBY_PVPP_GHJ"
				( objectStatus "@baseboard_fab2_lib.baseboard_fab2(sch_1):vr_fet_sw_p12v_stby_pvpp_ghj" )
			)
			( signal "VR_PVPP_GHJ_BOOT"
				( objectStatus "@baseboard_fab2_lib.baseboard_fab2(sch_1):vr_pvpp_ghj_boot" )
			)
			( signal "VR_PVPP_GHJ_BOOT_R"
				( objectStatus "@baseboard_fab2_lib.baseboard_fab2(sch_1):vr_pvpp_ghj_boot_r" )
			)
			( signal "VR_PVPP_GHJ_ISET"
				( objectStatus "@baseboard_fab2_lib.baseboard_fab2(sch_1):vr_pvpp_ghj_iset" )
			)
			( signal "VR_PVPP_GHJ_PHASE"
				( objectStatus "@baseboard_fab2_lib.baseboard_fab2(sch_1):vr_pvpp_ghj_phase" )
			)
			( signal "VR_PVPP_GHJ_SNUB"
				( objectStatus "@baseboard_fab2_lib.baseboard_fab2(sch_1):vr_pvpp_ghj_snub" )
			)
			( signal "VR_PVPP_GHJ_SS"
				( objectStatus "@baseboard_fab2_lib.baseboard_fab2(sch_1):vr_pvpp_ghj_ss" )
			)
			( signal "VR_VB_PVPP_GHJ"
				( objectStatus "@baseboard_fab2_lib.baseboard_fab2(sch_1):vr_vb_pvpp_ghj" )
			)
			( signal "VSENSE_PVPP_GHJ"
				( objectStatus "@baseboard_fab2_lib.baseboard_fab2(sch_1):vsense_pvpp_ghj" )
			)
			( signal "AGND_PVPP_KLM"
				( attribute "VOLTAGE" "0.0V"
					( Units "uVoltage" "V" 1.000000)
					( Status sAliasFlattened )
					( Origin gFrontEnd )
				)
				( objectStatus "@baseboard_fab2_lib.baseboard_fab2(sch_1):agnd_pvpp_klm" )
			)
			( signal "FM_PVPP_PVDDQ_CPU1_EN_KLM"
				( objectStatus "@baseboard_fab2_lib.baseboard_fab2(sch_1):fm_pvpp_pvddq_cpu1_en_klm" )
			)
			( signal "PWRGD_PVPP_KLM_R"
				( objectStatus "@baseboard_fab2_lib.baseboard_fab2(sch_1):pwrgd_pvpp_klm_r" )
			)
			( signal "VR_COMP_PVPP_KLM"
				( objectStatus "@baseboard_fab2_lib.baseboard_fab2(sch_1):vr_comp_pvpp_klm" )
			)
			( signal "VR_COMP_PVPP_KLM_3"
				( objectStatus "@baseboard_fab2_lib.baseboard_fab2(sch_1):vr_comp_pvpp_klm_3" )
			)
			( signal "VR_COMP_RC_PVPP_KLM"
				( objectStatus "@baseboard_fab2_lib.baseboard_fab2(sch_1):vr_comp_rc_pvpp_klm" )
			)
			( signal "VR_FB_PVPP_KLM"
				( objectStatus "@baseboard_fab2_lib.baseboard_fab2(sch_1):vr_fb_pvpp_klm" )
			)
			( signal "VR_FET_SW_P12V_STBY_PVPP_KLM"
				( objectStatus "@baseboard_fab2_lib.baseboard_fab2(sch_1):vr_fet_sw_p12v_stby_pvpp_klm" )
			)
			( signal "VR_PVPP_KLM_BOOT"
				( objectStatus "@baseboard_fab2_lib.baseboard_fab2(sch_1):vr_pvpp_klm_boot" )
			)
			( signal "VR_PVPP_KLM_BOOT_R"
				( objectStatus "@baseboard_fab2_lib.baseboard_fab2(sch_1):vr_pvpp_klm_boot_r" )
			)
			( signal "VR_PVPP_KLM_ISET"
				( objectStatus "@baseboard_fab2_lib.baseboard_fab2(sch_1):vr_pvpp_klm_iset" )
			)
			( signal "VR_PVPP_KLM_PHASE"
				( objectStatus "@baseboard_fab2_lib.baseboard_fab2(sch_1):vr_pvpp_klm_phase" )
			)
			( signal "VR_PVPP_KLM_SNUB"
				( objectStatus "@baseboard_fab2_lib.baseboard_fab2(sch_1):vr_pvpp_klm_snub" )
			)
			( signal "VR_PVPP_KLM_SS"
				( objectStatus "@baseboard_fab2_lib.baseboard_fab2(sch_1):vr_pvpp_klm_ss" )
			)
			( signal "VR_VB_PVPP_KLM"
				( objectStatus "@baseboard_fab2_lib.baseboard_fab2(sch_1):vr_vb_pvpp_klm" )
			)
			( signal "VSENSE_PVPP_KLM"
				( objectStatus "@baseboard_fab2_lib.baseboard_fab2(sch_1):vsense_pvpp_klm" )
			)
			( signal "A_TSENSE_P1V05_PCH_STBY_TMON"
				( objectStatus "@baseboard_fab2_lib.baseboard_fab2(sch_1):a_tsense_p1v05_pch_stby_tmon" )
			)
			( signal "A_TSENSE_PVNN_PCH_TMON"
				( objectStatus "@baseboard_fab2_lib.baseboard_fab2(sch_1):a_tsense_pvnn_pch_tmon" )
			)
			( signal "IRQ_PVNN_PCH_VRHOT_N"
				( objectStatus "@baseboard_fab2_lib.baseboard_fab2(sch_1):irq_pvnn_pch_vrhot_n" )
			)
			( signal "ISENSE_P1V05_PCH_STBY_PH1_IMON"
				( objectStatus "@baseboard_fab2_lib.baseboard_fab2(sch_1):isense_p1v05_pch_stby_ph1_imon" )
			)
			( signal "ISENSE_PVNN_PCH_PH1_IMON"
				( objectStatus "@baseboard_fab2_lib.baseboard_fab2(sch_1):isense_pvnn_pch_ph1_imon" )
			)
			( signal "PU_VR_PVNN_PCH_FAULT1"
				( objectStatus "@baseboard_fab2_lib.baseboard_fab2(sch_1):pu_vr_pvnn_pch_fault1" )
			)
			( signal "PWRGD_P1V8_PCH_STBY"
				( objectStatus "@baseboard_fab2_lib.baseboard_fab2(sch_1):pwrgd_p1v8_pch_stby" )
			)
			( signal "PWRGD_PVNN_PCH_R"
				( objectStatus "@baseboard_fab2_lib.baseboard_fab2(sch_1):pwrgd_pvnn_pch_r" )
			)
			( signal "PU_PVNN_PCH_VDIO"
				( objectStatus "@baseboard_fab2_lib.baseboard_fab2(sch_1):pu_pvnn_pch_vdio" )
			)
			( signal "VR_P1V05_PCH_BIREF1"
				( objectStatus "@baseboard_fab2_lib.baseboard_fab2(sch_1):vr_p1v05_pch_biref1" )
			)
			( signal "VR_P1V05_PCH_STBY_AVSP"
				( objectStatus "@baseboard_fab2_lib.baseboard_fab2(sch_1):vr_p1v05_pch_stby_avsp" )
			)
			( signal "VR_P1V05_PCH_STBY_PWM1"
				( objectStatus "@baseboard_fab2_lib.baseboard_fab2(sch_1):vr_p1v05_pch_stby_pwm1" )
			)
			( signal "VR_PVNN_P1V05_PCH_VD12"
				( objectStatus "@baseboard_fab2_lib.baseboard_fab2(sch_1):vr_pvnn_p1v05_pch_vd12" )
			)
			( signal "VR_PVNN_PCH_AIREF1"
				( objectStatus "@baseboard_fab2_lib.baseboard_fab2(sch_1):vr_pvnn_pch_airef1" )
			)
			( signal "VR_PVNN_PCH_AVSP"
				( objectStatus "@baseboard_fab2_lib.baseboard_fab2(sch_1):vr_pvnn_pch_avsp" )
			)
			( signal "VR_PVNN_PCH_PWM1"
				( objectStatus "@baseboard_fab2_lib.baseboard_fab2(sch_1):vr_pvnn_pch_pwm1" )
			)
			( signal "VR_PVNN_PCH_VDD"
				( objectStatus "@baseboard_fab2_lib.baseboard_fab2(sch_1):vr_pvnn_pch_vdd" )
			)
			( signal "VR_PVNN_PCH_VINSEN"
				( objectStatus "@baseboard_fab2_lib.baseboard_fab2(sch_1):vr_pvnn_pch_vinsen" )
			)
			( signal "VR_PVNN_PCH_VREN"
				( objectStatus "@baseboard_fab2_lib.baseboard_fab2(sch_1):vr_pvnn_pch_vren" )
			)
			( signal "VR_PVNN_PCH_XADDR1"
				( objectStatus "@baseboard_fab2_lib.baseboard_fab2(sch_1):vr_pvnn_pch_xaddr1" )
			)
			( signal "VR_PVNN_PCH_XADDR2"
				( objectStatus "@baseboard_fab2_lib.baseboard_fab2(sch_1):vr_pvnn_pch_xaddr2" )
			)
			( signal "VSENSE_P1V05_PCH_STBY_AVSN"
				( objectStatus "@baseboard_fab2_lib.baseboard_fab2(sch_1):vsense_p1v05_pch_stby_avsn" )
			)
			( signal "VSENSE_P1V05_PCH_STBY_AVSP"
				( objectStatus "@baseboard_fab2_lib.baseboard_fab2(sch_1):vsense_p1v05_pch_stby_avsp" )
			)
			( signal "VSENSE_PVNN_PCH_STBY_AVSN"
				( objectStatus "@baseboard_fab2_lib.baseboard_fab2(sch_1):vsense_pvnn_pch_stby_avsn" )
			)
			( signal "VSENSE_PVNN_PCH_STBY_AVSP"
				( objectStatus "@baseboard_fab2_lib.baseboard_fab2(sch_1):vsense_pvnn_pch_stby_avsp" )
			)
			( signal "NC_CLK_156M_CPU1_OSC"
				( objectStatus "@baseboard_fab2_lib.baseboard_fab2(sch_1):nc_clk_156m_cpu1_osc" )
			)
			( signal "NC_CLK_156M_CPU0_OSC"
				( objectStatus "@baseboard_fab2_lib.baseboard_fab2(sch_1):nc_clk_156m_cpu0_osc" )
			)
			( signal "TP_P1V05_PCH_GL_0"
				( objectStatus "@baseboard_fab2_lib.baseboard_fab2(sch_1):tp_p1v05_pch_gl_0" )
			)
			( signal "TP_P1V05_PCH_GL_1"
				( objectStatus "@baseboard_fab2_lib.baseboard_fab2(sch_1):tp_p1v05_pch_gl_1" )
			)
			( signal "TP_PVNN_PCH_GL_0"
				( objectStatus "@baseboard_fab2_lib.baseboard_fab2(sch_1):tp_pvnn_pch_gl_0" )
			)
			( signal "TP_PVNN_PCH_GL_1"
				( objectStatus "@baseboard_fab2_lib.baseboard_fab2(sch_1):tp_pvnn_pch_gl_1" )
			)
			( signal "VR_P1V05_PCH_STBY_OCSET"
				( objectStatus "@baseboard_fab2_lib.baseboard_fab2(sch_1):vr_p1v05_pch_stby_ocset" )
			)
			( signal "VR_P1V05_PCH_STBY_PH1_BOOT"
				( objectStatus "@baseboard_fab2_lib.baseboard_fab2(sch_1):vr_p1v05_pch_stby_ph1_boot" )
			)
			( signal "VR_P1V05_PCH_STBY_PH1_PHASE"
				( objectStatus "@baseboard_fab2_lib.baseboard_fab2(sch_1):vr_p1v05_pch_stby_ph1_phase" )
			)
			( signal "VR_P1V05_PCH_STBY_PH1_PHASE_SW"
				( objectStatus "@baseboard_fab2_lib.baseboard_fab2(sch_1):vr_p1v05_pch_stby_ph1_phase_sw" )
			)
			( signal "VR_P1V05_PCH_STBY_PH1_VCIN"
				( objectStatus "@baseboard_fab2_lib.baseboard_fab2(sch_1):vr_p1v05_pch_stby_ph1_vcin" )
			)
			( signal "VR_PVNN_PCH_PH1_BOOT"
				( objectStatus "@baseboard_fab2_lib.baseboard_fab2(sch_1):vr_pvnn_pch_ph1_boot" )
			)
			( signal "VR_PVNN_PCH_PH1_PHASE"
				( objectStatus "@baseboard_fab2_lib.baseboard_fab2(sch_1):vr_pvnn_pch_ph1_phase" )
			)
			( signal "VR_PVNN_PCH_PH1_PHASE_SW"
				( objectStatus "@baseboard_fab2_lib.baseboard_fab2(sch_1):vr_pvnn_pch_ph1_phase_sw" )
			)
			( signal "VR_PVNN_PCH_PH1_VCIN"
				( objectStatus "@baseboard_fab2_lib.baseboard_fab2(sch_1):vr_pvnn_pch_ph1_vcin" )
			)
			( signal "VR_PVNN_PCH_STBY_OCSET"
				( objectStatus "@baseboard_fab2_lib.baseboard_fab2(sch_1):vr_pvnn_pch_stby_ocset" )
			)
			( signal "PWRGD_P1V8_PCH_STBY_R"
				( objectStatus "@baseboard_fab2_lib.baseboard_fab2(sch_1):pwrgd_p1v8_pch_stby_r" )
			)
			( signal "VR_P1V8_PCH_STBY_FB"
				( objectStatus "@baseboard_fab2_lib.baseboard_fab2(sch_1):vr_p1v8_pch_stby_fb" )
			)
			( signal "PWRGD_P1V15_BMC_STBY_R"
				( objectStatus "@baseboard_fab2_lib.baseboard_fab2(sch_1):pwrgd_p1v15_bmc_stby_r" )
			)
			( signal "AGND_P3V3_STBY"
				( attribute "VOLTAGE" "0V"
					( Units "uVoltage" "V" 1.000000)
					( Status sAliasFlattened )
					( Origin gFrontEnd )
				)
				( objectStatus "@baseboard_fab2_lib.baseboard_fab2(sch_1):agnd_p3v3_stby" )
			)
			( signal "PWRGD_P3V3_STBY_R"
				( objectStatus "@baseboard_fab2_lib.baseboard_fab2(sch_1):pwrgd_p3v3_stby_r" )
			)
			( signal "PWRGD_P5V_STBY"
				( objectStatus "@baseboard_fab2_lib.baseboard_fab2(sch_1):pwrgd_p5v_stby" )
			)
			( signal "VR_FET_SW_P12V_STBY_P3V3_STBY"
				( objectStatus "@baseboard_fab2_lib.baseboard_fab2(sch_1):vr_fet_sw_p12v_stby_p3v3_stby" )
			)
			( signal "VR_P3V3_STBY_BOOT"
				( objectStatus "@baseboard_fab2_lib.baseboard_fab2(sch_1):vr_p3v3_stby_boot" )
			)
			( signal "VR_P3V3_STBY_BOOT_R"
				( objectStatus "@baseboard_fab2_lib.baseboard_fab2(sch_1):vr_p3v3_stby_boot_r" )
			)
			( signal "VR_P3V3_STBY_EN"
				( objectStatus "@baseboard_fab2_lib.baseboard_fab2(sch_1):vr_p3v3_stby_en" )
			)
			( signal "VR_P3V3_STBY_LGATE"
				( objectStatus "@baseboard_fab2_lib.baseboard_fab2(sch_1):vr_p3v3_stby_lgate" )
			)
			( signal "VR_P3V3_STBY_OCSELECT"
				( objectStatus "@baseboard_fab2_lib.baseboard_fab2(sch_1):vr_p3v3_stby_ocselect" )
			)
			( signal "VR_P3V3_STBY_PHASE"
				( objectStatus "@baseboard_fab2_lib.baseboard_fab2(sch_1):vr_p3v3_stby_phase" )
			)
			( signal "VR_P3V3_STBY_SNUB"
				( objectStatus "@baseboard_fab2_lib.baseboard_fab2(sch_1):vr_p3v3_stby_snub" )
			)
			( signal "VR_P3V3_STBY_UGATE"
				( objectStatus "@baseboard_fab2_lib.baseboard_fab2(sch_1):vr_p3v3_stby_ugate" )
			)
			( signal "VSENSE_P3V3_STBY"
				( objectStatus "@baseboard_fab2_lib.baseboard_fab2(sch_1):vsense_p3v3_stby" )
			)
			( signal "VSENSE_RGND_P3V3_STBY"
				( objectStatus "@baseboard_fab2_lib.baseboard_fab2(sch_1):vsense_rgnd_p3v3_stby" )
			)
			( signal "VSENSE_VOUT_P3V3_STBY"
				( objectStatus "@baseboard_fab2_lib.baseboard_fab2(sch_1):vsense_vout_p3v3_stby" )
			)
			( signal "AGND_P5V_STBY"
				( attribute "VOLTAGE" "0"
					( Units "uVoltage" "V" 1.000000)
					( Status sAliasFlattened )
					( Origin gFrontEnd )
				)
				( objectStatus "@baseboard_fab2_lib.baseboard_fab2(sch_1):agnd_p5v_stby" )
			)
			( signal "PWRGD_P5V_STBY_R"
				( objectStatus "@baseboard_fab2_lib.baseboard_fab2(sch_1):pwrgd_p5v_stby_r" )
			)
			( signal "VR_FET_SW_P5V_STBY_PVIN"
				( objectStatus "@baseboard_fab2_lib.baseboard_fab2(sch_1):vr_fet_sw_p5v_stby_pvin" )
			)
			( signal "VR_P5V_STBY_BOOT"
				( objectStatus "@baseboard_fab2_lib.baseboard_fab2(sch_1):vr_p5v_stby_boot" )
			)
			( signal "VR_P5V_STBY_COMP"
				( objectStatus "@baseboard_fab2_lib.baseboard_fab2(sch_1):vr_p5v_stby_comp" )
			)
			( signal "VR_P5V_STBY_EN"
				( objectStatus "@baseboard_fab2_lib.baseboard_fab2(sch_1):vr_p5v_stby_en" )
			)
			( signal "VR_P5V_STBY_PHASE"
				( objectStatus "@baseboard_fab2_lib.baseboard_fab2(sch_1):vr_p5v_stby_phase" )
			)
			( signal "VR_P5V_STBY_RC_COMP"
				( objectStatus "@baseboard_fab2_lib.baseboard_fab2(sch_1):vr_p5v_stby_rc_comp" )
			)
			( signal "VR_P5V_STBY_RT"
				( objectStatus "@baseboard_fab2_lib.baseboard_fab2(sch_1):vr_p5v_stby_rt" )
			)
			( signal "VR_P5V_STBY_SS"
				( objectStatus "@baseboard_fab2_lib.baseboard_fab2(sch_1):vr_p5v_stby_ss" )
			)
			( signal "VR_P5V_STBY_VIN"
				( objectStatus "@baseboard_fab2_lib.baseboard_fab2(sch_1):vr_p5v_stby_vin" )
			)
			( signal "VR_P5V_STBY_VSENSE"
				( objectStatus "@baseboard_fab2_lib.baseboard_fab2(sch_1):vr_p5v_stby_vsense" )
			)
			( signal "VR_P5V_STBY_VSENSE_R"
				( objectStatus "@baseboard_fab2_lib.baseboard_fab2(sch_1):vr_p5v_stby_vsense_r" )
			)
			( signal "VR_PVCCIN_CPU0_PH1_BOOT_R"
				( objectStatus "@baseboard_fab2_lib.baseboard_fab2(sch_1):vr_pvccin_cpu0_ph1_boot_r" )
			)
			( signal "VR_PVCCIN_CPU0_PH2_BOOT_R"
				( objectStatus "@baseboard_fab2_lib.baseboard_fab2(sch_1):vr_pvccin_cpu0_ph2_boot_r" )
			)
			( signal "VR_PVCCIN_CPU1_PHASE3_RC"
				( objectStatus "@baseboard_fab2_lib.baseboard_fab2(sch_1):vr_pvccin_cpu1_phase3_rc" )
			)
			( signal "VR_PVDDQ_KLM_PH1_BOOT_R"
				( objectStatus "@baseboard_fab2_lib.baseboard_fab2(sch_1):vr_pvddq_klm_ph1_boot_r" )
			)
			( signal "VR_PVDDQ_KLM_PH2_BOOT_R"
				( objectStatus "@baseboard_fab2_lib.baseboard_fab2(sch_1):vr_pvddq_klm_ph2_boot_r" )
			)
			( signal "VR_PVCCIN_CPU1_PH5_BOOT_R"
				( objectStatus "@baseboard_fab2_lib.baseboard_fab2(sch_1):vr_pvccin_cpu1_ph5_boot_r" )
			)
			( signal "VR_PVCCIN_CPU1_PH3_BOOT_R"
				( objectStatus "@baseboard_fab2_lib.baseboard_fab2(sch_1):vr_pvccin_cpu1_ph3_boot_r" )
			)
			( signal "VR_PVCCIN_CPU1_PH4_BOOT_R"
				( objectStatus "@baseboard_fab2_lib.baseboard_fab2(sch_1):vr_pvccin_cpu1_ph4_boot_r" )
			)
			( signal "VR_PVCCIN_CPU1_PH1_BOOT_R"
				( objectStatus "@baseboard_fab2_lib.baseboard_fab2(sch_1):vr_pvccin_cpu1_ph1_boot_r" )
			)
			( signal "VR_PVDDQ_GHJ_PH1_BOOT_R"
				( objectStatus "@baseboard_fab2_lib.baseboard_fab2(sch_1):vr_pvddq_ghj_ph1_boot_r" )
			)
			( signal "VR_PVDDQ_GHJ_PH2_BOOT_R"
				( objectStatus "@baseboard_fab2_lib.baseboard_fab2(sch_1):vr_pvddq_ghj_ph2_boot_r" )
			)
			( signal "VR_PVDDQ_GHJ_PH1_SW_RC"
				( objectStatus "@baseboard_fab2_lib.baseboard_fab2(sch_1):vr_pvddq_ghj_ph1_sw_rc" )
			)
			( signal "VR_PVCCIN_CPU0_PH3_BOOT_R"
				( objectStatus "@baseboard_fab2_lib.baseboard_fab2(sch_1):vr_pvccin_cpu0_ph3_boot_r" )
			)
			( signal "VR_PVDDQ_DEF_PH1_BOOT_R"
				( objectStatus "@baseboard_fab2_lib.baseboard_fab2(sch_1):vr_pvddq_def_ph1_boot_r" )
			)
			( signal "VR_PVDDQ_DEF_PH2_BOOT_R"
				( objectStatus "@baseboard_fab2_lib.baseboard_fab2(sch_1):vr_pvddq_def_ph2_boot_r" )
			)
			( signal "VR_PVDDQ_ABC_PH1_BOOT_R"
				( objectStatus "@baseboard_fab2_lib.baseboard_fab2(sch_1):vr_pvddq_abc_ph1_boot_r" )
			)
			( signal "VR_PVDDQ_ABC_PH2_BOOT_R"
				( objectStatus "@baseboard_fab2_lib.baseboard_fab2(sch_1):vr_pvddq_abc_ph2_boot_r" )
			)
			( signal "VR_PVSA_CPU1_BOOT_R"
				( objectStatus "@baseboard_fab2_lib.baseboard_fab2(sch_1):vr_pvsa_cpu1_boot_r" )
			)
			( signal "VR_PVSA_CPU0_BOOT_R"
				( objectStatus "@baseboard_fab2_lib.baseboard_fab2(sch_1):vr_pvsa_cpu0_boot_r" )
			)
			( signal "VR_PVCCIO_CPU1_PH1_BOOT_R"
				( objectStatus "@baseboard_fab2_lib.baseboard_fab2(sch_1):vr_pvccio_cpu1_ph1_boot_r" )
			)
			( signal "VR_P1V05_PCH_STBY_PH1_BOOT_R"
				( objectStatus "@baseboard_fab2_lib.baseboard_fab2(sch_1):vr_p1v05_pch_stby_ph1_boot_r" )
			)
			( signal "VR_PVNN_PCH_PH1_BOOT_R"
				( objectStatus "@baseboard_fab2_lib.baseboard_fab2(sch_1):vr_pvnn_pch_ph1_boot_r" )
			)
			( signal "VR_PVCCIO_CPU0_PH1_BOOT_R"
				( objectStatus "@baseboard_fab2_lib.baseboard_fab2(sch_1):vr_pvccio_cpu0_ph1_boot_r" )
			)
			( signal "VR_PVCCIN_CPU1_PH2_BOOT_R"
				( objectStatus "@baseboard_fab2_lib.baseboard_fab2(sch_1):vr_pvccin_cpu1_ph2_boot_r" )
			)
			( signal "VR_PVCCIN_CPU0_PH4_BOOT_R"
				( objectStatus "@baseboard_fab2_lib.baseboard_fab2(sch_1):vr_pvccin_cpu0_ph4_boot_r" )
			)
			( signal "P3E_CPU0_PE1_PCH_CON_RXN<8>"
				( objectStatus "@baseboard_fab2_lib.baseboard_fab2(sch_1):p3e_cpu0_pe1_pch_con_rxn(8)" )
			)
			( signal "P3E_CPU0_PE1_PCH_CON_RXN<9>"
				( objectStatus "@baseboard_fab2_lib.baseboard_fab2(sch_1):p3e_cpu0_pe1_pch_con_rxn(9)" )
			)
			( signal "P3E_CPU0_PE1_PCH_CON_RXN<10>"
				( objectStatus "@baseboard_fab2_lib.baseboard_fab2(sch_1):p3e_cpu0_pe1_pch_con_rxn(10)" )
			)
			( signal "P3E_CPU0_PE1_PCH_CON_RXN<11>"
				( objectStatus "@baseboard_fab2_lib.baseboard_fab2(sch_1):p3e_cpu0_pe1_pch_con_rxn(11)" )
			)
			( signal "P3E_CPU0_PE1_PCH_CON_RXN<12>"
				( objectStatus "@baseboard_fab2_lib.baseboard_fab2(sch_1):p3e_cpu0_pe1_pch_con_rxn(12)" )
			)
			( signal "P3E_CPU0_PE1_PCH_CON_RXN<13>"
				( objectStatus "@baseboard_fab2_lib.baseboard_fab2(sch_1):p3e_cpu0_pe1_pch_con_rxn(13)" )
			)
			( signal "P3E_CPU0_PE1_PCH_CON_RXN<14>"
				( objectStatus "@baseboard_fab2_lib.baseboard_fab2(sch_1):p3e_cpu0_pe1_pch_con_rxn(14)" )
			)
			( signal "P3E_CPU0_PE1_PCH_CON_RXN<15>"
				( objectStatus "@baseboard_fab2_lib.baseboard_fab2(sch_1):p3e_cpu0_pe1_pch_con_rxn(15)" )
			)
			( signal "P3E_CPU0_PE1_PCH_CON_RXP<8>"
				( objectStatus "@baseboard_fab2_lib.baseboard_fab2(sch_1):p3e_cpu0_pe1_pch_con_rxp(8)" )
			)
			( signal "P3E_CPU0_PE1_PCH_CON_RXP<9>"
				( objectStatus "@baseboard_fab2_lib.baseboard_fab2(sch_1):p3e_cpu0_pe1_pch_con_rxp(9)" )
			)
			( signal "P3E_CPU0_PE1_PCH_CON_RXP<10>"
				( objectStatus "@baseboard_fab2_lib.baseboard_fab2(sch_1):p3e_cpu0_pe1_pch_con_rxp(10)" )
			)
			( signal "P3E_CPU0_PE1_PCH_CON_RXP<11>"
				( objectStatus "@baseboard_fab2_lib.baseboard_fab2(sch_1):p3e_cpu0_pe1_pch_con_rxp(11)" )
			)
			( signal "P3E_CPU0_PE1_PCH_CON_RXP<12>"
				( objectStatus "@baseboard_fab2_lib.baseboard_fab2(sch_1):p3e_cpu0_pe1_pch_con_rxp(12)" )
			)
			( signal "P3E_CPU0_PE1_PCH_CON_RXP<13>"
				( objectStatus "@baseboard_fab2_lib.baseboard_fab2(sch_1):p3e_cpu0_pe1_pch_con_rxp(13)" )
			)
			( signal "P3E_CPU0_PE1_PCH_CON_RXP<14>"
				( objectStatus "@baseboard_fab2_lib.baseboard_fab2(sch_1):p3e_cpu0_pe1_pch_con_rxp(14)" )
			)
			( signal "P3E_CPU0_PE1_PCH_CON_RXP<15>"
				( objectStatus "@baseboard_fab2_lib.baseboard_fab2(sch_1):p3e_cpu0_pe1_pch_con_rxp(15)" )
			)
			( signal "P3E_CPU0_PE1_PCH_CON_TXN<8>"
				( objectStatus "@baseboard_fab2_lib.baseboard_fab2(sch_1):p3e_cpu0_pe1_pch_con_txn(8)" )
			)
			( signal "P3E_CPU0_PE1_PCH_CON_TXN<9>"
				( objectStatus "@baseboard_fab2_lib.baseboard_fab2(sch_1):p3e_cpu0_pe1_pch_con_txn(9)" )
			)
			( signal "P3E_CPU0_PE1_PCH_CON_TXN<10>"
				( objectStatus "@baseboard_fab2_lib.baseboard_fab2(sch_1):p3e_cpu0_pe1_pch_con_txn(10)" )
			)
			( signal "P3E_CPU0_PE1_PCH_CON_TXN<11>"
				( objectStatus "@baseboard_fab2_lib.baseboard_fab2(sch_1):p3e_cpu0_pe1_pch_con_txn(11)" )
			)
			( signal "P3E_CPU0_PE1_PCH_CON_TXN<12>"
				( objectStatus "@baseboard_fab2_lib.baseboard_fab2(sch_1):p3e_cpu0_pe1_pch_con_txn(12)" )
			)
			( signal "P3E_CPU0_PE1_PCH_CON_TXN<13>"
				( objectStatus "@baseboard_fab2_lib.baseboard_fab2(sch_1):p3e_cpu0_pe1_pch_con_txn(13)" )
			)
			( signal "P3E_CPU0_PE1_PCH_CON_TXN<14>"
				( objectStatus "@baseboard_fab2_lib.baseboard_fab2(sch_1):p3e_cpu0_pe1_pch_con_txn(14)" )
			)
			( signal "P3E_CPU0_PE1_PCH_CON_TXN<15>"
				( objectStatus "@baseboard_fab2_lib.baseboard_fab2(sch_1):p3e_cpu0_pe1_pch_con_txn(15)" )
			)
			( signal "P3E_CPU0_PE1_PCH_CON_TXP<8>"
				( objectStatus "@baseboard_fab2_lib.baseboard_fab2(sch_1):p3e_cpu0_pe1_pch_con_txp(8)" )
			)
			( signal "P3E_CPU0_PE1_PCH_CON_TXP<9>"
				( objectStatus "@baseboard_fab2_lib.baseboard_fab2(sch_1):p3e_cpu0_pe1_pch_con_txp(9)" )
			)
			( signal "P3E_CPU0_PE1_PCH_CON_TXP<10>"
				( objectStatus "@baseboard_fab2_lib.baseboard_fab2(sch_1):p3e_cpu0_pe1_pch_con_txp(10)" )
			)
			( signal "P3E_CPU0_PE1_PCH_CON_TXP<11>"
				( objectStatus "@baseboard_fab2_lib.baseboard_fab2(sch_1):p3e_cpu0_pe1_pch_con_txp(11)" )
			)
			( signal "P3E_CPU0_PE1_PCH_CON_TXP<12>"
				( objectStatus "@baseboard_fab2_lib.baseboard_fab2(sch_1):p3e_cpu0_pe1_pch_con_txp(12)" )
			)
			( signal "P3E_CPU0_PE1_PCH_CON_TXP<13>"
				( objectStatus "@baseboard_fab2_lib.baseboard_fab2(sch_1):p3e_cpu0_pe1_pch_con_txp(13)" )
			)
			( signal "P3E_CPU0_PE1_PCH_CON_TXP<14>"
				( objectStatus "@baseboard_fab2_lib.baseboard_fab2(sch_1):p3e_cpu0_pe1_pch_con_txp(14)" )
			)
			( signal "P3E_CPU0_PE1_PCH_CON_TXP<15>"
				( objectStatus "@baseboard_fab2_lib.baseboard_fab2(sch_1):p3e_cpu0_pe1_pch_con_txp(15)" )
			)
			( signal "UV_HIGH_SET_N"
				( objectStatus "@baseboard_fab2_lib.baseboard_fab2(sch_1):uv_high_set_n" )
			)
			( signal "BMC_STRAP_BIT5"
				( objectStatus "@baseboard_fab2_lib.baseboard_fab2(sch_1):bmc_strap_bit5" )
			)
			( signal "PCA9555_A0"
				( objectStatus "@baseboard_fab2_lib.baseboard_fab2(sch_1):pca9555_a0" )
			)
			( signal "PCA9555_INT_N"
				( objectStatus "@baseboard_fab2_lib.baseboard_fab2(sch_1):pca9555_int_n" )
			)
			( signal "FM_TPM_PRES_RST"
				( objectStatus "@baseboard_fab2_lib.baseboard_fab2(sch_1):fm_tpm_pres_rst" )
			)
			( signal "FM_TPM_PRES_RST_N"
				( objectStatus "@baseboard_fab2_lib.baseboard_fab2(sch_1):fm_tpm_pres_rst_n" )
			)
			( signal "VREF_2V2"
				( objectStatus "@baseboard_fab2_lib.baseboard_fab2(sch_1):vref_2v2" )
			)
			( signal "BMC_M_A0"
				( objectStatus "@baseboard_fab2_lib.baseboard_fab2(sch_1):bmc_m_a0" )
			)
			( signal "BMC_M_A1"
				( objectStatus "@baseboard_fab2_lib.baseboard_fab2(sch_1):bmc_m_a1" )
			)
			( signal "BMC_M_A10"
				( objectStatus "@baseboard_fab2_lib.baseboard_fab2(sch_1):bmc_m_a10" )
			)
			( signal "BMC_M_A11"
				( objectStatus "@baseboard_fab2_lib.baseboard_fab2(sch_1):bmc_m_a11" )
			)
			( signal "BMC_M_A12"
				( objectStatus "@baseboard_fab2_lib.baseboard_fab2(sch_1):bmc_m_a12" )
			)
			( signal "BMC_M_A13"
				( objectStatus "@baseboard_fab2_lib.baseboard_fab2(sch_1):bmc_m_a13" )
			)
			( signal "BMC_M_A2"
				( objectStatus "@baseboard_fab2_lib.baseboard_fab2(sch_1):bmc_m_a2" )
			)
			( signal "BMC_M_A3"
				( objectStatus "@baseboard_fab2_lib.baseboard_fab2(sch_1):bmc_m_a3" )
			)
			( signal "BMC_M_A4"
				( objectStatus "@baseboard_fab2_lib.baseboard_fab2(sch_1):bmc_m_a4" )
			)
			( signal "BMC_M_A5"
				( objectStatus "@baseboard_fab2_lib.baseboard_fab2(sch_1):bmc_m_a5" )
			)
			( signal "BMC_M_A6"
				( objectStatus "@baseboard_fab2_lib.baseboard_fab2(sch_1):bmc_m_a6" )
			)
			( signal "BMC_M_A7"
				( objectStatus "@baseboard_fab2_lib.baseboard_fab2(sch_1):bmc_m_a7" )
			)
			( signal "BMC_M_A8"
				( objectStatus "@baseboard_fab2_lib.baseboard_fab2(sch_1):bmc_m_a8" )
			)
			( signal "BMC_M_A9"
				( objectStatus "@baseboard_fab2_lib.baseboard_fab2(sch_1):bmc_m_a9" )
			)
			( signal "BMC_M_BA0"
				( objectStatus "@baseboard_fab2_lib.baseboard_fab2(sch_1):bmc_m_ba0" )
			)
			( signal "BMC_M_BA1"
				( objectStatus "@baseboard_fab2_lib.baseboard_fab2(sch_1):bmc_m_ba1" )
			)
			( signal "BMC_M_BG0"
				( objectStatus "@baseboard_fab2_lib.baseboard_fab2(sch_1):bmc_m_bg0" )
			)
			( signal "BMC_M_CAS_N"
				( objectStatus "@baseboard_fab2_lib.baseboard_fab2(sch_1):bmc_m_cas_n" )
			)
			( signal "BMC_M_CKE"
				( objectStatus "@baseboard_fab2_lib.baseboard_fab2(sch_1):bmc_m_cke" )
			)
			( signal "BMC_M_CLK_DN"
				( objectStatus "@baseboard_fab2_lib.baseboard_fab2(sch_1):bmc_m_clk_dn" )
			)
			( signal "BMC_M_CLK_DP"
				( objectStatus "@baseboard_fab2_lib.baseboard_fab2(sch_1):bmc_m_clk_dp" )
			)
			( signal "BMC_M_CS_N"
				( objectStatus "@baseboard_fab2_lib.baseboard_fab2(sch_1):bmc_m_cs_n" )
			)
			( signal "BMC_M_DM0"
				( objectStatus "@baseboard_fab2_lib.baseboard_fab2(sch_1):bmc_m_dm0" )
			)
			( signal "BMC_M_DM1"
				( objectStatus "@baseboard_fab2_lib.baseboard_fab2(sch_1):bmc_m_dm1" )
			)
			( signal "BMC_M_DQ0"
				( objectStatus "@baseboard_fab2_lib.baseboard_fab2(sch_1):bmc_m_dq0" )
			)
			( signal "BMC_M_DQ1"
				( objectStatus "@baseboard_fab2_lib.baseboard_fab2(sch_1):bmc_m_dq1" )
			)
			( signal "BMC_M_DQ10"
				( objectStatus "@baseboard_fab2_lib.baseboard_fab2(sch_1):bmc_m_dq10" )
			)
			( signal "BMC_M_DQ11"
				( objectStatus "@baseboard_fab2_lib.baseboard_fab2(sch_1):bmc_m_dq11" )
			)
			( signal "BMC_M_DQ12"
				( objectStatus "@baseboard_fab2_lib.baseboard_fab2(sch_1):bmc_m_dq12" )
			)
			( signal "BMC_M_DQ13"
				( objectStatus "@baseboard_fab2_lib.baseboard_fab2(sch_1):bmc_m_dq13" )
			)
			( signal "BMC_M_DQ14"
				( objectStatus "@baseboard_fab2_lib.baseboard_fab2(sch_1):bmc_m_dq14" )
			)
			( signal "BMC_M_DQ15"
				( objectStatus "@baseboard_fab2_lib.baseboard_fab2(sch_1):bmc_m_dq15" )
			)
			( signal "BMC_M_DQ2"
				( objectStatus "@baseboard_fab2_lib.baseboard_fab2(sch_1):bmc_m_dq2" )
			)
			( signal "BMC_M_DQ3"
				( objectStatus "@baseboard_fab2_lib.baseboard_fab2(sch_1):bmc_m_dq3" )
			)
			( signal "BMC_M_DQ4"
				( objectStatus "@baseboard_fab2_lib.baseboard_fab2(sch_1):bmc_m_dq4" )
			)
			( signal "BMC_M_DQ5"
				( objectStatus "@baseboard_fab2_lib.baseboard_fab2(sch_1):bmc_m_dq5" )
			)
			( signal "BMC_M_DQ6"
				( objectStatus "@baseboard_fab2_lib.baseboard_fab2(sch_1):bmc_m_dq6" )
			)
			( signal "BMC_M_DQ7"
				( objectStatus "@baseboard_fab2_lib.baseboard_fab2(sch_1):bmc_m_dq7" )
			)
			( signal "BMC_M_DQ8"
				( objectStatus "@baseboard_fab2_lib.baseboard_fab2(sch_1):bmc_m_dq8" )
			)
			( signal "BMC_M_DQ9"
				( objectStatus "@baseboard_fab2_lib.baseboard_fab2(sch_1):bmc_m_dq9" )
			)
			( signal "BMC_M_DQS0_DN"
				( objectStatus "@baseboard_fab2_lib.baseboard_fab2(sch_1):bmc_m_dqs0_dn" )
			)
			( signal "BMC_M_DQS0_DP"
				( objectStatus "@baseboard_fab2_lib.baseboard_fab2(sch_1):bmc_m_dqs0_dp" )
			)
			( signal "BMC_M_DQS1_DP"
				( objectStatus "@baseboard_fab2_lib.baseboard_fab2(sch_1):bmc_m_dqs1_dp" )
			)
			( signal "A_DACRSET"
				( objectStatus "@baseboard_fab2_lib.baseboard_fab2(sch_1):a_dacrset" )
			)
			( signal "IRQ_LPC_SERIRQ_R"
				( objectStatus "@baseboard_fab2_lib.baseboard_fab2(sch_1):irq_lpc_serirq_r" )
			)
			( signal "LPC_LAD0_IO0_R"
				( objectStatus "@baseboard_fab2_lib.baseboard_fab2(sch_1):lpc_lad0_io0_r" )
			)
			( signal "LPC_LAD1_IO1_R"
				( objectStatus "@baseboard_fab2_lib.baseboard_fab2(sch_1):lpc_lad1_io1_r" )
			)
			( signal "LPC_LAD3_IO3_R"
				( objectStatus "@baseboard_fab2_lib.baseboard_fab2(sch_1):lpc_lad3_io3_r" )
			)
			( signal "RST_BMC_LVC3_N"
				( objectStatus "@baseboard_fab2_lib.baseboard_fab2(sch_1):rst_bmc_lvc3_n" )
			)
			( signal "SGPIO_BMC_CLK_R"
				( objectStatus "@baseboard_fab2_lib.baseboard_fab2(sch_1):sgpio_bmc_clk_r" )
			)
			( signal "SGPIO_BMC_LD_R_N"
				( objectStatus "@baseboard_fab2_lib.baseboard_fab2(sch_1):sgpio_bmc_ld_r_n" )
			)
			( signal "BMC_VGA_HSYNC"
				( objectStatus "@baseboard_fab2_lib.baseboard_fab2(sch_1):bmc_vga_hsync" )
			)
			( signal "PU_24M_OSC_OE"
				( objectStatus "@baseboard_fab2_lib.baseboard_fab2(sch_1):pu_24m_osc_oe" )
			)
			( signal "A_USB2BVRES"
				( objectStatus "@baseboard_fab2_lib.baseboard_fab2(sch_1):a_usb2bvres" )
			)
			( signal "VCCBAT_TW12"
				( objectStatus "@baseboard_fab2_lib.baseboard_fab2(sch_1):vccbat_tw12" )
			)
			( signal "A_USB2AVRES"
				( objectStatus "@baseboard_fab2_lib.baseboard_fab2(sch_1):a_usb2avres" )
			)
			( signal "GPIOS7"
				( objectStatus "@baseboard_fab2_lib.baseboard_fab2(sch_1):gpios7" )
			)
			( signal "BMC_SELF_HW_RST"
				( objectStatus "@baseboard_fab2_lib.baseboard_fab2(sch_1):bmc_self_hw_rst" )
			)
			( signal "PWRGD_P2V5_BMC_STBY"
				( objectStatus "@baseboard_fab2_lib.baseboard_fab2(sch_1):pwrgd_p2v5_bmc_stby" )
			)
			( signal "VR_PVCCIN_CPU0_PHASE1_RC"
				( objectStatus "@baseboard_fab2_lib.baseboard_fab2(sch_1):vr_pvccin_cpu0_phase1_rc" )
			)
			( signal "FM_TPM_PRES_RST_N_R"
				( objectStatus "@baseboard_fab2_lib.baseboard_fab2(sch_1):fm_tpm_pres_rst_n_r" )
			)
			( signal "USB2_P02_DN"
				( objectStatus "@baseboard_fab2_lib.baseboard_fab2(sch_1):usb2_p02_dn" )
			)
			( signal "USB2_P02_DP"
				( objectStatus "@baseboard_fab2_lib.baseboard_fab2(sch_1):usb2_p02_dp" )
			)
			( signal "JTAG_RISER_TMS"
				( objectStatus "@baseboard_fab2_lib.baseboard_fab2(sch_1):jtag_riser_tms" )
			)
			( signal "JTAG_RISER_TCK"
				( objectStatus "@baseboard_fab2_lib.baseboard_fab2(sch_1):jtag_riser_tck" )
			)
			( signal "SMB_DEBUG_STBY_LVC3_SCL_R"
				( objectStatus "@baseboard_fab2_lib.baseboard_fab2(sch_1):smb_debug_stby_lvc3_scl_r" )
			)
			( signal "SMB_DEBUG_STBY_LVC3_SCL"
				( objectStatus "@baseboard_fab2_lib.baseboard_fab2(sch_1):smb_debug_stby_lvc3_scl" )
			)
			( signal "HSC_SMBUS_SWITCH_EN"
				( objectStatus "@baseboard_fab2_lib.baseboard_fab2(sch_1):hsc_smbus_switch_en" )
			)
			( signal "SMB_HOST_STBY_LVC3_SCL_R3"
				( objectStatus "@baseboard_fab2_lib.baseboard_fab2(sch_1):smb_host_stby_lvc3_scl_r3" )
			)
			( signal "SMB_HOST_STBY_LVC3_SDA_R3"
				( objectStatus "@baseboard_fab2_lib.baseboard_fab2(sch_1):smb_host_stby_lvc3_sda_r3" )
			)
			( signal "PD_ID_EEPROM_WP"
				( objectStatus "@baseboard_fab2_lib.baseboard_fab2(sch_1):pd_id_eeprom_wp" )
			)
			( signal "TP_BMC_M_A15"
				( objectStatus "@baseboard_fab2_lib.baseboard_fab2(sch_1):tp_bmc_m_a15" )
			)
			( signal "RST_PCIE_M2_DEV_AND"
				( objectStatus "@baseboard_fab2_lib.baseboard_fab2(sch_1):rst_pcie_m2_dev_and" )
			)
			( signal "VR_PVCCIN_CPU0_PHASE2_RC"
				( objectStatus "@baseboard_fab2_lib.baseboard_fab2(sch_1):vr_pvccin_cpu0_phase2_rc" )
			)
			( signal "VR_P2V5_BMC_STBY_FB"
				( objectStatus "@baseboard_fab2_lib.baseboard_fab2(sch_1):vr_p2v5_bmc_stby_fb" )
			)
			( signal "VR_PVDDQ_KLM_PH2_RC"
				( objectStatus "@baseboard_fab2_lib.baseboard_fab2(sch_1):vr_pvddq_klm_ph2_rc" )
			)
			( signal "VR_PVCCIN_CPU1_PHASE5_RC"
				( objectStatus "@baseboard_fab2_lib.baseboard_fab2(sch_1):vr_pvccin_cpu1_phase5_rc" )
			)
			( signal "VR_PVCCIN_CPU1_PHASE4_RC"
				( objectStatus "@baseboard_fab2_lib.baseboard_fab2(sch_1):vr_pvccin_cpu1_phase4_rc" )
			)
			( signal "VR_PVCCIN_CPU1_PHASE1_RC"
				( objectStatus "@baseboard_fab2_lib.baseboard_fab2(sch_1):vr_pvccin_cpu1_phase1_rc" )
			)
			( signal "VR_PVCCIN_CPU1_PHASE2_RC"
				( objectStatus "@baseboard_fab2_lib.baseboard_fab2(sch_1):vr_pvccin_cpu1_phase2_rc" )
			)
			( signal "VR_PVDDQ_GHJ_PH2_SW_RC"
				( objectStatus "@baseboard_fab2_lib.baseboard_fab2(sch_1):vr_pvddq_ghj_ph2_sw_rc" )
			)
			( signal "VR_PVCCIN_CPU0_PHASE5_RC"
				( objectStatus "@baseboard_fab2_lib.baseboard_fab2(sch_1):vr_pvccin_cpu0_phase5_rc" )
			)
			( signal "VR_PVCCIN_CPU0_PHASE3_RC"
				( objectStatus "@baseboard_fab2_lib.baseboard_fab2(sch_1):vr_pvccin_cpu0_phase3_rc" )
			)
			( signal "VR_PVCCIN_CPU0_PHASE4_RC"
				( objectStatus "@baseboard_fab2_lib.baseboard_fab2(sch_1):vr_pvccin_cpu0_phase4_rc" )
			)
			( signal "VR_PVDDQ_DEF_PH2_SW_RC"
				( objectStatus "@baseboard_fab2_lib.baseboard_fab2(sch_1):vr_pvddq_def_ph2_sw_rc" )
			)
			( signal "VR_PVDDQ_ABC_PH1_SW_RC"
				( objectStatus "@baseboard_fab2_lib.baseboard_fab2(sch_1):vr_pvddq_abc_ph1_sw_rc" )
			)
			( signal "VR_PVDDQ_ABC_PH2_SW_RC"
				( objectStatus "@baseboard_fab2_lib.baseboard_fab2(sch_1):vr_pvddq_abc_ph2_sw_rc" )
			)
			( signal "VR_PVCCIO_CPU1_PH1_SW_RC"
				( objectStatus "@baseboard_fab2_lib.baseboard_fab2(sch_1):vr_pvccio_cpu1_ph1_sw_rc" )
			)
			( signal "VR_PVCCIN_CPU0_PH5_BOOT_R"
				( objectStatus "@baseboard_fab2_lib.baseboard_fab2(sch_1):vr_pvccin_cpu0_ph5_boot_r" )
			)
			( signal "VR_PVNN_PCH_PH1_PHASE_SW_RC"
				( objectStatus "@baseboard_fab2_lib.baseboard_fab2(sch_1):vr_pvnn_pch_ph1_phase_sw_rc" )
			)
			( signal "VR_PVCCIO_CPU0_PH1_SW_RC"
				( objectStatus "@baseboard_fab2_lib.baseboard_fab2(sch_1):vr_pvccio_cpu0_ph1_sw_rc" )
			)
			( signal "SPI_TPM_BMC_DI_R"
				( objectStatus "@baseboard_fab2_lib.baseboard_fab2(sch_1):spi_tpm_bmc_di_r" )
			)
			( signal "RST_BMC_DDR3_R_N"
				( objectStatus "@baseboard_fab2_lib.baseboard_fab2(sch_1):rst_bmc_ddr3_r_n" )
			)
			( signal "SMB_CPU0_PE_HP_GTL_R_SCL"
				( objectStatus "@baseboard_fab2_lib.baseboard_fab2(sch_1):smb_cpu0_pe_hp_gtl_r_scl" )
			)
			( signal "SMB_CPU0_PE_HP_GTL_R_SDA"
				( objectStatus "@baseboard_fab2_lib.baseboard_fab2(sch_1):smb_cpu0_pe_hp_gtl_r_sda" )
			)
			( signal "SMB_CPU0_PE_HP_GTL_SCL"
				( objectStatus "@baseboard_fab2_lib.baseboard_fab2(sch_1):smb_cpu0_pe_hp_gtl_scl" )
			)
			( signal "SMB_CPU0_PE_HP_GTL_SDA"
				( objectStatus "@baseboard_fab2_lib.baseboard_fab2(sch_1):smb_cpu0_pe_hp_gtl_sda" )
			)
			( signal "TP_SMB_PEHPCPU0_EN"
				( objectStatus "@baseboard_fab2_lib.baseboard_fab2(sch_1):tp_smb_pehpcpu0_en" )
			)
			( signal "SMB_PEHPCPU0_STBY_LVC3_R_SCL"
				( objectStatus "@baseboard_fab2_lib.baseboard_fab2(sch_1):smb_pehpcpu0_stby_lvc3_r_scl" )
			)
			( signal "SMB_PEHPCPU0_STBY_LVC3_R_SDA"
				( objectStatus "@baseboard_fab2_lib.baseboard_fab2(sch_1):smb_pehpcpu0_stby_lvc3_r_sda" )
			)
			( signal "SMB_PEHPCPU0_STBY_LVC3_SCL"
				( objectStatus "@baseboard_fab2_lib.baseboard_fab2(sch_1):smb_pehpcpu0_stby_lvc3_scl" )
			)
			( signal "SMB_PEHPCPU0_STBY_LVC3_SDA"
				( objectStatus "@baseboard_fab2_lib.baseboard_fab2(sch_1):smb_pehpcpu0_stby_lvc3_sda" )
			)
			( signal "FM_OCP_MEZZB_PRES_1V05_PCH_N"
				( objectStatus "@baseboard_fab2_lib.baseboard_fab2(sch_1):fm_ocp_mezzb_pres_1v05_pch_n" )
			)
			( signal "FM_OCP_MEZZC_PRES_1V05_PCH_N"
				( objectStatus "@baseboard_fab2_lib.baseboard_fab2(sch_1):fm_ocp_mezzc_pres_1v05_pch_n" )
			)
			( signal "BMC_STRAP_BIT3"
				( objectStatus "@baseboard_fab2_lib.baseboard_fab2(sch_1):bmc_strap_bit3" )
			)
			( signal "SMB_DEBUG_STBY_LVC3_SDA"
				( objectStatus "@baseboard_fab2_lib.baseboard_fab2(sch_1):smb_debug_stby_lvc3_sda" )
			)
			( signal "SMB_DEBUG_STBY_LVC3_SDA_R"
				( objectStatus "@baseboard_fab2_lib.baseboard_fab2(sch_1):smb_debug_stby_lvc3_sda_r" )
			)
			( signal "BMC_STRAP_BIT27"
				( objectStatus "@baseboard_fab2_lib.baseboard_fab2(sch_1):bmc_strap_bit27" )
			)
			( signal "BMC_STRAP_BIT17"
				( objectStatus "@baseboard_fab2_lib.baseboard_fab2(sch_1):bmc_strap_bit17" )
			)
			( signal "BMC_STRAP_BIT18"
				( objectStatus "@baseboard_fab2_lib.baseboard_fab2(sch_1):bmc_strap_bit18" )
			)
			( signal "BMC_STRAP_BIT20"
				( objectStatus "@baseboard_fab2_lib.baseboard_fab2(sch_1):bmc_strap_bit20" )
			)
			( signal "RST_PCIE_M2_DEV_IC_N"
				( objectStatus "@baseboard_fab2_lib.baseboard_fab2(sch_1):rst_pcie_m2_dev_ic_n" )
			)
			( signal "FM_TPM_PRES_N"
				( objectStatus "@baseboard_fab2_lib.baseboard_fab2(sch_1):fm_tpm_pres_n" )
			)
			( signal "PWRGD_P1V2_BMC_STBY"
				( objectStatus "@baseboard_fab2_lib.baseboard_fab2(sch_1):pwrgd_p1v2_bmc_stby" )
			)
			( signal "PWRGD_P1V2_BMC_STBY_R"
				( objectStatus "@baseboard_fab2_lib.baseboard_fab2(sch_1):pwrgd_p1v2_bmc_stby_r" )
			)
			( signal "TPM_SPI_BMC_WP_N"
				( objectStatus "@baseboard_fab2_lib.baseboard_fab2(sch_1):tpm_spi_bmc_wp_n" )
			)
			( signal "VR_P1V05_PCH_STBY_PH1_SW_RC"
				( objectStatus "@baseboard_fab2_lib.baseboard_fab2(sch_1):vr_p1v05_pch_stby_ph1_sw_rc" )
			)
			( signal "FM_OCP_MEZZC_PRES_LVT3_BMC"
				( objectStatus "@baseboard_fab2_lib.baseboard_fab2(sch_1):fm_ocp_mezzc_pres_lvt3_bmc" )
			)
			( signal "VR_P1V15_BMC_STBY_FB"
				( objectStatus "@baseboard_fab2_lib.baseboard_fab2(sch_1):vr_p1v15_bmc_stby_fb" )
			)
			( signal "VR_P1V2_BMC_STBY_FB"
				( objectStatus "@baseboard_fab2_lib.baseboard_fab2(sch_1):vr_p1v2_bmc_stby_fb" )
			)
			( signal "FM_OCP_MEZZB_PRES_LVT3_BMC"
				( objectStatus "@baseboard_fab2_lib.baseboard_fab2(sch_1):fm_ocp_mezzb_pres_lvt3_bmc" )
			)
			( signal "P5V_TPS2061"
				( objectStatus "@baseboard_fab2_lib.baseboard_fab2(sch_1):p5v_tps2061" )
			)
			( signal "FM_USB_P0_EN_R_N"
				( objectStatus "@baseboard_fab2_lib.baseboard_fab2(sch_1):fm_usb_p0_en_r_n" )
			)
			( signal "FM_MEZZB_PRSNT1_N"
				( objectStatus "@baseboard_fab2_lib.baseboard_fab2(sch_1):fm_mezzb_prsnt1_n" )
			)
			( signal "PUMP_PWM_OUT"
				( objectStatus "@baseboard_fab2_lib.baseboard_fab2(sch_1):pump_pwm_out" )
			)
			( signal "P12V_PUMP"
				( objectStatus "@baseboard_fab2_lib.baseboard_fab2(sch_1):p12v_pump" )
			)
			( signal "P1V8_M2"
				( objectStatus "@baseboard_fab2_lib.baseboard_fab2(sch_1):p1v8_m2" )
			)
			( signal "SMB_PEHPCPU0_STBY_LVC3_R2_SCL"
				( objectStatus "@baseboard_fab2_lib.baseboard_fab2(sch_1):smb_pehpcpu0_stby_lvc3_r2_scl" )
			)
			( signal "SMB_PEHPCPU0_STBY_LVC3_R2_SDA"
				( objectStatus "@baseboard_fab2_lib.baseboard_fab2(sch_1):smb_pehpcpu0_stby_lvc3_r2_sda" )
			)
			( signal "PUMP_TACH_D"
				( objectStatus "@baseboard_fab2_lib.baseboard_fab2(sch_1):pump_tach_d" )
			)
			( signal "PUMP_TACH_R"
				( objectStatus "@baseboard_fab2_lib.baseboard_fab2(sch_1):pump_tach_r" )
			)
			( signal "USB2_P02_DN_R"
				( objectStatus "@baseboard_fab2_lib.baseboard_fab2(sch_1):usb2_p02_dn_r" )
			)
			( signal "USB2_P02_DP_R"
				( objectStatus "@baseboard_fab2_lib.baseboard_fab2(sch_1):usb2_p02_dp_r" )
			)
			( signal "USB2_PCH_BMC_P5_DN_R"
				( objectStatus "@baseboard_fab2_lib.baseboard_fab2(sch_1):usb2_pch_bmc_p5_dn_r" )
			)
			( signal "USB2_PCH_BMC_P5_DP_R"
				( objectStatus "@baseboard_fab2_lib.baseboard_fab2(sch_1):usb2_pch_bmc_p5_dp_r" )
			)
			( signal "USB_PCH_BMC_P4_DN_R"
				( objectStatus "@baseboard_fab2_lib.baseboard_fab2(sch_1):usb_pch_bmc_p4_dn_r" )
			)
			( signal "USB_PCH_BMC_P4_DP_R"
				( objectStatus "@baseboard_fab2_lib.baseboard_fab2(sch_1):usb_pch_bmc_p4_dp_r" )
			)
			( signal "I2C_BMC_VGA_DDC_SCL"
				( objectStatus "@baseboard_fab2_lib.baseboard_fab2(sch_1):i2c_bmc_vga_ddc_scl" )
			)
			( signal "I2C_BMC_VGA_DDC_SDA"
				( objectStatus "@baseboard_fab2_lib.baseboard_fab2(sch_1):i2c_bmc_vga_ddc_sda" )
			)
			( signal "I2C_BMC_VGA_DDC_SCL_G"
				( objectStatus "@baseboard_fab2_lib.baseboard_fab2(sch_1):i2c_bmc_vga_ddc_scl_g" )
			)
			( signal "I2C_BMC_VGA_DDC_SDA_G"
				( objectStatus "@baseboard_fab2_lib.baseboard_fab2(sch_1):i2c_bmc_vga_ddc_sda_g" )
			)
			( signal "P5V_VGA_D"
				( objectStatus "@baseboard_fab2_lib.baseboard_fab2(sch_1):p5v_vga_d" )
			)
			( signal "Q25W1_GATE"
				( objectStatus "@baseboard_fab2_lib.baseboard_fab2(sch_1):q25w1_gate" )
			)
			( signal "Q25W2_GATE"
				( objectStatus "@baseboard_fab2_lib.baseboard_fab2(sch_1):q25w2_gate" )
			)
			( signal "V_IBMC_5V_DDC_SCL_J"
				( objectStatus "@baseboard_fab2_lib.baseboard_fab2(sch_1):v_ibmc_5v_ddc_scl_j" )
			)
			( signal "V_IBMC_5V_DDC_SDA_J"
				( objectStatus "@baseboard_fab2_lib.baseboard_fab2(sch_1):v_ibmc_5v_ddc_sda_j" )
			)
			( signal "VGA_REAR_HSYNC_S"
				( objectStatus "@baseboard_fab2_lib.baseboard_fab2(sch_1):vga_rear_hsync_s" )
			)
			( signal "VGA_REAR_VSYNC_S"
				( objectStatus "@baseboard_fab2_lib.baseboard_fab2(sch_1):vga_rear_vsync_s" )
			)
			( signal "V_IO_HSYNC_J"
				( objectStatus "@baseboard_fab2_lib.baseboard_fab2(sch_1):v_io_hsync_j" )
			)
			( signal "V_IO_VSYNC_J"
				( objectStatus "@baseboard_fab2_lib.baseboard_fab2(sch_1):v_io_vsync_j" )
			)
			( signal "P5V_VGA"
				( objectStatus "@baseboard_fab2_lib.baseboard_fab2(sch_1):p5v_vga" )
			)
			( signal "CLK_48M_USB_BMC_R"
				( objectStatus "@baseboard_fab2_lib.baseboard_fab2(sch_1):clk_48m_usb_bmc_r" )
			)
			( signal "RST_PLTRST_BUF_N_R"
				( objectStatus "@baseboard_fab2_lib.baseboard_fab2(sch_1):rst_pltrst_buf_n_r" )
			)
			( signal "PD_CPU0_EAR_N"
				( objectStatus "@baseboard_fab2_lib.baseboard_fab2(sch_1):pd_cpu0_ear_n" )
			)
			( signal "PD_CPU1_EAR_N"
				( objectStatus "@baseboard_fab2_lib.baseboard_fab2(sch_1):pd_cpu1_ear_n" )
			)
			( signal "FM_SLPS3_R_N"
				( objectStatus "@baseboard_fab2_lib.baseboard_fab2(sch_1):fm_slps3_r_n" )
			)
			( signal "USB3_P01_FB_RXN"
				( objectStatus "@baseboard_fab2_lib.baseboard_fab2(sch_1):usb3_p01_fb_rxn" )
			)
			( signal "USB3_P01_FB_RXP"
				( objectStatus "@baseboard_fab2_lib.baseboard_fab2(sch_1):usb3_p01_fb_rxp" )
			)
			( signal "USB3_P01_FB_TXN"
				( objectStatus "@baseboard_fab2_lib.baseboard_fab2(sch_1):usb3_p01_fb_txn" )
			)
			( signal "USB3_P01_FB_TXP"
				( objectStatus "@baseboard_fab2_lib.baseboard_fab2(sch_1):usb3_p01_fb_txp" )
			)
			( signal "USB3_P01_C_TXN"
				( objectStatus "@baseboard_fab2_lib.baseboard_fab2(sch_1):usb3_p01_c_txn" )
			)
			( signal "USB3_P01_C_TXP"
				( objectStatus "@baseboard_fab2_lib.baseboard_fab2(sch_1):usb3_p01_c_txp" )
			)
			( signal "USB3_P01_RXN"
				( objectStatus "@baseboard_fab2_lib.baseboard_fab2(sch_1):usb3_p01_rxn" )
			)
			( signal "USB3_P01_RXP"
				( objectStatus "@baseboard_fab2_lib.baseboard_fab2(sch_1):usb3_p01_rxp" )
			)
			( signal "USB3_P01_TXN"
				( objectStatus "@baseboard_fab2_lib.baseboard_fab2(sch_1):usb3_p01_txn" )
			)
			( signal "USB3_P01_TXP"
				( objectStatus "@baseboard_fab2_lib.baseboard_fab2(sch_1):usb3_p01_txp" )
			)
			( signal "TEMP_SENSOR_B"
				( objectStatus "@baseboard_fab2_lib.baseboard_fab2(sch_1):temp_sensor_b" )
			)
			( signal "TEMP_SENSOR_E"
				( objectStatus "@baseboard_fab2_lib.baseboard_fab2(sch_1):temp_sensor_e" )
			)
			( signal "PWRGD_PVDDQ_KLM_N"
				( objectStatus "@baseboard_fab2_lib.baseboard_fab2(sch_1):pwrgd_pvddq_klm_n" )
			)
			( signal "PWRGD_PVDDQ_ABC_N"
				( objectStatus "@baseboard_fab2_lib.baseboard_fab2(sch_1):pwrgd_pvddq_abc_n" )
			)
			( signal "PWRGD_PVDDQ_GHJ_N"
				( objectStatus "@baseboard_fab2_lib.baseboard_fab2(sch_1):pwrgd_pvddq_ghj_n" )
			)
			( signal "P12V_NVDIMM_ABC_D"
				( objectStatus "@baseboard_fab2_lib.baseboard_fab2(sch_1):p12v_nvdimm_abc_d" )
			)
			( signal "FM_GLOBAL_RST_WARN_N_R"
				( objectStatus "@baseboard_fab2_lib.baseboard_fab2(sch_1):fm_global_rst_warn_n_r" )
			)
			( signal "PU_CPLD1_PT20D_PROGRAMN"
				( objectStatus "@baseboard_fab2_lib.baseboard_fab2(sch_1):pu_cpld1_pt20d_programn" )
			)
			( signal "SMB_HOST_STBY_LVC3_SDA_R4"
				( objectStatus "@baseboard_fab2_lib.baseboard_fab2(sch_1):smb_host_stby_lvc3_sda_r4" )
			)
			( signal "XTAL_CK_MNG_OUT_R"
				( objectStatus "@baseboard_fab2_lib.baseboard_fab2(sch_1):xtal_ck_mng_out_r" )
			)
			( signal "SMB_HOST_STBY_LVC3_SCL_R4"
				( objectStatus "@baseboard_fab2_lib.baseboard_fab2(sch_1):smb_host_stby_lvc3_scl_r4" )
			)
			( signal "PU_33P_33M_SMBADR"
				( objectStatus "@baseboard_fab2_lib.baseboard_fab2(sch_1):pu_33p_33m_smbadr" )
			)
			( signal "FM_CPU1_CD_PRES_N"
				( objectStatus "@baseboard_fab2_lib.baseboard_fab2(sch_1):fm_cpu1_cd_pres_n" )
			)
			( signal "PU_PVNN_PCH_VCLK"
				( objectStatus "@baseboard_fab2_lib.baseboard_fab2(sch_1):pu_pvnn_pch_vclk" )
			)
			( signal "FM_PWR_BTN_R2_N"
				( objectStatus "@baseboard_fab2_lib.baseboard_fab2(sch_1):fm_pwr_btn_r2_n" )
			)
			( signal "FM_PCH_PWRBTN_R1_N"
				( objectStatus "@baseboard_fab2_lib.baseboard_fab2(sch_1):fm_pch_pwrbtn_r1_n" )
			)
			( signal "FM_PWR_BTN_R1_N"
				( objectStatus "@baseboard_fab2_lib.baseboard_fab2(sch_1):fm_pwr_btn_r1_n" )
			)
			( signal "RST_SYSTEM_BTN_R_N"
				( objectStatus "@baseboard_fab2_lib.baseboard_fab2(sch_1):rst_system_btn_r_n" )
			)
			( signal "RST_BMC_SYSRST_BTN_OUT_B_R1_N"
				( objectStatus "@baseboard_fab2_lib.baseboard_fab2(sch_1):rst_bmc_sysrst_btn_out_b_r1_n" )
			)
			( signal "PU_JTAG_BMC_RTCK"
				( objectStatus "@baseboard_fab2_lib.baseboard_fab2(sch_1):pu_jtag_bmc_rtck" )
			)
			( signal "TP_RGMII2TXD2_GPIOU2"
				( objectStatus "@baseboard_fab2_lib.baseboard_fab2(sch_1):tp_rgmii2txd2_gpiou2" )
			)
			( signal "TP_RGMII2TXD3_GPIOU3"
				( objectStatus "@baseboard_fab2_lib.baseboard_fab2(sch_1):tp_rgmii2txd3_gpiou3" )
			)
			( signal "RST_BMC_EXTRST_N"
				( objectStatus "@baseboard_fab2_lib.baseboard_fab2(sch_1):rst_bmc_extrst_n" )
			)
			( signal "TP_SLOTX24_RSVD63"
				( objectStatus "@baseboard_fab2_lib.baseboard_fab2(sch_1):tp_slotx24_rsvd63" )
			)
			( signal "FM_PRSNT_2_1_N"
				( objectStatus "@baseboard_fab2_lib.baseboard_fab2(sch_1):fm_prsnt_2_1_n" )
			)
			( signal "TP_SLOTX24_RSVD66"
				( objectStatus "@baseboard_fab2_lib.baseboard_fab2(sch_1):tp_slotx24_rsvd66" )
			)
			( signal "PU_SPI_BMC_BT_CS0_N"
				( objectStatus "@baseboard_fab2_lib.baseboard_fab2(sch_1):pu_spi_bmc_bt_cs0_n" )
			)
			( signal "PD_UV_HIGH_SET"
				( objectStatus "@baseboard_fab2_lib.baseboard_fab2(sch_1):pd_uv_high_set" )
			)
			( signal "PU_UV_HIGH_SET"
				( objectStatus "@baseboard_fab2_lib.baseboard_fab2(sch_1):pu_uv_high_set" )
			)
			( signal "SMB_HOST_STBY_LVC3_SDA_R5"
				( objectStatus "@baseboard_fab2_lib.baseboard_fab2(sch_1):smb_host_stby_lvc3_sda_r5" )
			)
			( signal "SMB_HOST_STBY_LVC3_SCL_R5"
				( objectStatus "@baseboard_fab2_lib.baseboard_fab2(sch_1):smb_host_stby_lvc3_scl_r5" )
			)
			( signal "SMB_SLOTX24_PCH_STBY_LVC3_SCL"
				( objectStatus "@baseboard_fab2_lib.baseboard_fab2(sch_1):smb_slotx24_pch_stby_lvc3_scl" )
			)
			( signal "SMB_SLOTX24_PCH_STBY_LVC3_SDA"
				( objectStatus "@baseboard_fab2_lib.baseboard_fab2(sch_1):smb_slotx24_pch_stby_lvc3_sda" )
			)
			( signal "TP_BMC_GPIOA2"
				( objectStatus "@baseboard_fab2_lib.baseboard_fab2(sch_1):tp_bmc_gpioa2" )
			)
			( signal "PU_PVNN_PCH_PINALRT_N"
				( objectStatus "@baseboard_fab2_lib.baseboard_fab2(sch_1):pu_pvnn_pch_pinalrt_n" )
			)
			( signal "P3V3_DB1200_R1"
				( objectStatus "@baseboard_fab2_lib.baseboard_fab2(sch_1):p3v3_db1200_r1" )
			)
			( signal "FM_DB1200_PWRGD_R"
				( objectStatus "@baseboard_fab2_lib.baseboard_fab2(sch_1):fm_db1200_pwrgd_r" )
			)
			( signal "KR_P1_OCP_RX_C_DN"
				( objectStatus "@baseboard_fab2_lib.baseboard_fab2(sch_1):kr_p1_ocp_rx_c_dn" )
			)
			( signal "KR_P1_OCP_RX_C_DP"
				( objectStatus "@baseboard_fab2_lib.baseboard_fab2(sch_1):kr_p1_ocp_rx_c_dp" )
			)
			( signal "KR_P1_OCP_RX_DN"
				( objectStatus "@baseboard_fab2_lib.baseboard_fab2(sch_1):kr_p1_ocp_rx_dn" )
			)
			( signal "KR_P1_OCP_RX_DP"
				( objectStatus "@baseboard_fab2_lib.baseboard_fab2(sch_1):kr_p1_ocp_rx_dp" )
			)
			( signal "KR_P1_OCP_TX_DN"
				( objectStatus "@baseboard_fab2_lib.baseboard_fab2(sch_1):kr_p1_ocp_tx_dn" )
			)
			( signal "KR_P1_OCP_TX_DP"
				( objectStatus "@baseboard_fab2_lib.baseboard_fab2(sch_1):kr_p1_ocp_tx_dp" )
			)
			( signal "JTAG_MCP_TCK_R1"
				( objectStatus "@baseboard_fab2_lib.baseboard_fab2(sch_1):jtag_mcp_tck_r1" )
			)
			( signal "P5V_STBY_USBC"
				( objectStatus "@baseboard_fab2_lib.baseboard_fab2(sch_1):p5v_stby_usbc" )
			)
			( signal "FM_ADR_COMPLETE_CPU1_N"
				( objectStatus "@baseboard_fab2_lib.baseboard_fab2(sch_1):fm_adr_complete_cpu1_n" )
			)
			( signal "IRQ_DIMM_SAVE_CPU1_R_N"
				( objectStatus "@baseboard_fab2_lib.baseboard_fab2(sch_1):irq_dimm_save_cpu1_r_n" )
			)
			( signal "IRQ_DIMM_SAVE_LVT3_CPU1"
				( objectStatus "@baseboard_fab2_lib.baseboard_fab2(sch_1):irq_dimm_save_lvt3_cpu1" )
			)
			( signal "FM_ADR_COMPLETE_CPU0_R"
				( objectStatus "@baseboard_fab2_lib.baseboard_fab2(sch_1):fm_adr_complete_cpu0_r" )
			)
			( signal "FM_ADR_COMPLETE_CPU1_R"
				( objectStatus "@baseboard_fab2_lib.baseboard_fab2(sch_1):fm_adr_complete_cpu1_r" )
			)
			( signal "SMB_DEBUG_STBY_LVC3_SCL_R1"
				( objectStatus "@baseboard_fab2_lib.baseboard_fab2(sch_1):smb_debug_stby_lvc3_scl_r1" )
			)
			( signal "SMB_DEBUG_STBY_LVC3_SDA_R1"
				( objectStatus "@baseboard_fab2_lib.baseboard_fab2(sch_1):smb_debug_stby_lvc3_sda_r1" )
			)
			( signal "DEBUG_CARD2_PRSNT"
				( objectStatus "@baseboard_fab2_lib.baseboard_fab2(sch_1):debug_card2_prsnt" )
			)
			( signal "SPA_MID_DBG2_TX"
				( objectStatus "@baseboard_fab2_lib.baseboard_fab2(sch_1):spa_mid_dbg2_tx" )
			)
			( signal "SPA_MID_DBG2_RX_BUF"
				( objectStatus "@baseboard_fab2_lib.baseboard_fab2(sch_1):spa_mid_dbg2_rx_buf" )
			)
			( signal "SPA_MID_DBG2_TX_R"
				( objectStatus "@baseboard_fab2_lib.baseboard_fab2(sch_1):spa_mid_dbg2_tx_r" )
			)
			( signal "SPA_MID_DBG1_TX"
				( objectStatus "@baseboard_fab2_lib.baseboard_fab2(sch_1):spa_mid_dbg1_tx" )
			)
			( signal "SPA_MID_DBG1_TX_R"
				( objectStatus "@baseboard_fab2_lib.baseboard_fab2(sch_1):spa_mid_dbg1_tx_r" )
			)
			( signal "FM_CPU_CATERR_MSMI_LVT3_N"
				( objectStatus "@baseboard_fab2_lib.baseboard_fab2(sch_1):fm_cpu_caterr_msmi_lvt3_n" )
			)
			( signal "SPA_MID_DBG1_TX_EN"
				( objectStatus "@baseboard_fab2_lib.baseboard_fab2(sch_1):spa_mid_dbg1_tx_en" )
			)
			( signal "SMB_DEBUG_STBY_LVC3_SCL_CONN"
				( objectStatus "@baseboard_fab2_lib.baseboard_fab2(sch_1):smb_debug_stby_lvc3_scl_conn" )
			)
			( signal "SMB_DEBUG_STBY_LVC3_SDA_CONN"
				( objectStatus "@baseboard_fab2_lib.baseboard_fab2(sch_1):smb_debug_stby_lvc3_sda_conn" )
			)
			( signal "BMC_M_CLK"
				( objectStatus "@baseboard_fab2_lib.baseboard_fab2(sch_1):bmc_m_clk" )
			)
			( signal "SMB_M2_ALT_R_N"
				( objectStatus "@baseboard_fab2_lib.baseboard_fab2(sch_1):smb_m2_alt_r_n" )
			)
			( signal "SMB_M2_ALT_N"
				( objectStatus "@baseboard_fab2_lib.baseboard_fab2(sch_1):smb_m2_alt_n" )
			)
			( signal "TP_PUMP"
				( objectStatus "@baseboard_fab2_lib.baseboard_fab2(sch_1):tp_pump" )
			)
			( signal "PUMP_TACH1"
				( objectStatus "@baseboard_fab2_lib.baseboard_fab2(sch_1):pump_tach1" )
			)
			( signal "PUMP_TACH1_D"
				( objectStatus "@baseboard_fab2_lib.baseboard_fab2(sch_1):pump_tach1_d" )
			)
			( signal "PUMP_TACH1_R"
				( objectStatus "@baseboard_fab2_lib.baseboard_fab2(sch_1):pump_tach1_r" )
			)
			( signal "SMB_M2_SCL"
				( objectStatus "@baseboard_fab2_lib.baseboard_fab2(sch_1):smb_m2_scl" )
			)
			( signal "SMB_M2_SCL_R"
				( objectStatus "@baseboard_fab2_lib.baseboard_fab2(sch_1):smb_m2_scl_r" )
			)
			( signal "SMB_M2_SDA"
				( objectStatus "@baseboard_fab2_lib.baseboard_fab2(sch_1):smb_m2_sda" )
			)
			( signal "SMB_M2_SDA_R"
				( objectStatus "@baseboard_fab2_lib.baseboard_fab2(sch_1):smb_m2_sda_r" )
			)
			( signal "VREF_LMV431_1V42"
				( objectStatus "@baseboard_fab2_lib.baseboard_fab2(sch_1):vref_lmv431_1v42" )
			)
			( signal "PU_ID_EEPROM_A0"
				( objectStatus "@baseboard_fab2_lib.baseboard_fab2(sch_1):pu_id_eeprom_a0" )
			)
			( signal "BMC_SELF_HW_D_RST"
				( objectStatus "@baseboard_fab2_lib.baseboard_fab2(sch_1):bmc_self_hw_d_rst" )
			)
			( signal "PCA9554_A0"
				( objectStatus "@baseboard_fab2_lib.baseboard_fab2(sch_1):pca9554_a0" )
			)
			( signal "FM_PMBUS_ALERT_BUF_EN_R_N"
				( objectStatus "@baseboard_fab2_lib.baseboard_fab2(sch_1):fm_pmbus_alert_buf_en_r_n" )
			)
			( signal "FM_PMBUS_ALERT_BUF_EN_R2_N"
				( objectStatus "@baseboard_fab2_lib.baseboard_fab2(sch_1):fm_pmbus_alert_buf_en_r2_n" )
			)
			( signal "FM_PMBUS_ALERT_BUF_EN_R3_N"
				( objectStatus "@baseboard_fab2_lib.baseboard_fab2(sch_1):fm_pmbus_alert_buf_en_r3_n" )
			)
			( signal "JTAG_BMC_TCK0"
				( objectStatus "@baseboard_fab2_lib.baseboard_fab2(sch_1):jtag_bmc_tck0" )
			)
			( signal "JTAG_BMC_TCK1"
				( objectStatus "@baseboard_fab2_lib.baseboard_fab2(sch_1):jtag_bmc_tck1" )
			)
			( signal "PD_GTL2014_3_VREF"
				( objectStatus "@baseboard_fab2_lib.baseboard_fab2(sch_1):pd_gtl2014_3_vref" )
			)
			( signal "PU_GTL2014_3_DIR"
				( objectStatus "@baseboard_fab2_lib.baseboard_fab2(sch_1):pu_gtl2014_3_dir" )
			)
			( signal "XDP_CPU_TCK0_R"
				( objectStatus "@baseboard_fab2_lib.baseboard_fab2(sch_1):xdp_cpu_tck0_r" )
			)
			( signal "XDP_PCH_TCK1_R"
				( objectStatus "@baseboard_fab2_lib.baseboard_fab2(sch_1):xdp_pch_tck1_r" )
			)
			( signal "XDP_TDI_R"
				( objectStatus "@baseboard_fab2_lib.baseboard_fab2(sch_1):xdp_tdi_r" )
			)
			( signal "XDP_TMS_R"
				( objectStatus "@baseboard_fab2_lib.baseboard_fab2(sch_1):xdp_tms_r" )
			)
			( signal "XDP_TRST_R_N"
				( objectStatus "@baseboard_fab2_lib.baseboard_fab2(sch_1):xdp_trst_r_n" )
			)
			( signal "CPU_XDP_PRESENT_N"
				( objectStatus "@baseboard_fab2_lib.baseboard_fab2(sch_1):cpu_xdp_present_n" )
			)
			( signal "P0V7_GTL2014_VREF_6"
				( attribute "VOLTAGE" "+0.7 V"
					( Units "uVoltage" "V" 1.000000)
					( Status sAliasFlattened )
					( Origin gFrontEnd )
				)
				( objectStatus "@baseboard_fab2_lib.baseboard_fab2(sch_1):p0v7_gtl2014_vref_6" )
			)
			( signal "PD_GTL2014_6_B0"
				( objectStatus "@baseboard_fab2_lib.baseboard_fab2(sch_1):pd_gtl2014_6_b0" )
			)
			( signal "PD_GTL2014_6_B2"
				( objectStatus "@baseboard_fab2_lib.baseboard_fab2(sch_1):pd_gtl2014_6_b2" )
			)
			( signal "PD_GTL2014_DIR_6"
				( objectStatus "@baseboard_fab2_lib.baseboard_fab2(sch_1):pd_gtl2014_dir_6" )
			)
			( signal "TP_GTL2014_6_A0"
				( objectStatus "@baseboard_fab2_lib.baseboard_fab2(sch_1):tp_gtl2014_6_a0" )
			)
			( signal "TP_GTL2014_6_A2"
				( objectStatus "@baseboard_fab2_lib.baseboard_fab2(sch_1):tp_gtl2014_6_a2" )
			)
			( signal "BMC_JTAG_SEL_N"
				( objectStatus "@baseboard_fab2_lib.baseboard_fab2(sch_1):bmc_jtag_sel_n" )
			)
			( signal "PCA9554_INT_N"
				( objectStatus "@baseboard_fab2_lib.baseboard_fab2(sch_1):pca9554_int_n" )
			)
			( signal "BMC_JTAG_SEL_N_MUX"
				( objectStatus "@baseboard_fab2_lib.baseboard_fab2(sch_1):bmc_jtag_sel_n_mux" )
			)
			( signal "JTAG_PLD_TCK_MUX"
				( objectStatus "@baseboard_fab2_lib.baseboard_fab2(sch_1):jtag_pld_tck_mux" )
			)
			( signal "JTAG_PLD_TDI_MUX"
				( objectStatus "@baseboard_fab2_lib.baseboard_fab2(sch_1):jtag_pld_tdi_mux" )
			)
			( signal "JTAG_PLD_TDO_MUX"
				( objectStatus "@baseboard_fab2_lib.baseboard_fab2(sch_1):jtag_pld_tdo_mux" )
			)
			( signal "JTAG_PLD_TMS_MUX"
				( objectStatus "@baseboard_fab2_lib.baseboard_fab2(sch_1):jtag_pld_tms_mux" )
			)
			( signal "RST_BMC_PLTRST_BUF_N"
				( objectStatus "@baseboard_fab2_lib.baseboard_fab2(sch_1):rst_bmc_pltrst_buf_n" )
			)
			( signal "JTAG_BMC_BUF_TDI"
				( objectStatus "@baseboard_fab2_lib.baseboard_fab2(sch_1):jtag_bmc_buf_tdi" )
			)
			( signal "JTAG_BMC_BUF_TDO"
				( objectStatus "@baseboard_fab2_lib.baseboard_fab2(sch_1):jtag_bmc_buf_tdo" )
			)
			( signal "JTAG_BMC_BUF_TMS"
				( objectStatus "@baseboard_fab2_lib.baseboard_fab2(sch_1):jtag_bmc_buf_tms" )
			)
			( signal "BMC_JTAG_SEL"
				( objectStatus "@baseboard_fab2_lib.baseboard_fab2(sch_1):bmc_jtag_sel" )
			)
			( signal "JTAG_BMC_TRST_BUF_N"
				( objectStatus "@baseboard_fab2_lib.baseboard_fab2(sch_1):jtag_bmc_trst_buf_n" )
			)
			( signal "BMC_JTAG_SEL_BUF"
				( objectStatus "@baseboard_fab2_lib.baseboard_fab2(sch_1):bmc_jtag_sel_buf" )
			)
			( signal "BMC_PREQ_BUF_N"
				( objectStatus "@baseboard_fab2_lib.baseboard_fab2(sch_1):bmc_preq_buf_n" )
			)
			( signal "BMC_PWR_DEBUG_BUF_N"
				( objectStatus "@baseboard_fab2_lib.baseboard_fab2(sch_1):bmc_pwr_debug_buf_n" )
			)
			( signal "SPA_5V_SIN_SW_D"
				( objectStatus "@baseboard_fab2_lib.baseboard_fab2(sch_1):spa_5v_sin_sw_d" )
			)
			( signal "PU_DEV_OFF_N"
				( objectStatus "@baseboard_fab2_lib.baseboard_fab2(sch_1):pu_dev_off_n" )
			)
			( signal "TP_PCH_GDP8_SUSCLK"
				( objectStatus "@baseboard_fab2_lib.baseboard_fab2(sch_1):tp_pch_gdp8_susclk" )
			)
			( signal "L1_85OHM_6INCH_DN"
				( objectStatus "@baseboard_fab2_lib.baseboard_fab2(sch_1):l1_85ohm_6inch_dn" )
			)
			( signal "L1_85OHM_6INCH_DP"
				( objectStatus "@baseboard_fab2_lib.baseboard_fab2(sch_1):l1_85ohm_6inch_dp" )
			)
			( signal "L1_85OHM_5INCH_DN"
				( objectStatus "@baseboard_fab2_lib.baseboard_fab2(sch_1):l1_85ohm_5inch_dn" )
			)
			( signal "L1_85OHM_5INCH_DP"
				( objectStatus "@baseboard_fab2_lib.baseboard_fab2(sch_1):l1_85ohm_5inch_dp" )
			)
			( signal "L3_85OHM_5INCH_DN"
				( objectStatus "@baseboard_fab2_lib.baseboard_fab2(sch_1):l3_85ohm_5inch_dn" )
			)
			( signal "L3_85OHM_5INCH_DP"
				( objectStatus "@baseboard_fab2_lib.baseboard_fab2(sch_1):l3_85ohm_5inch_dp" )
			)
			( signal "L5_85OHM_5INCH_DN"
				( objectStatus "@baseboard_fab2_lib.baseboard_fab2(sch_1):l5_85ohm_5inch_dn" )
			)
			( signal "L5_85OHM_5INCH_DP"
				( objectStatus "@baseboard_fab2_lib.baseboard_fab2(sch_1):l5_85ohm_5inch_dp" )
			)
			( signal "L10_85OHM_5INCH_DN"
				( objectStatus "@baseboard_fab2_lib.baseboard_fab2(sch_1):l10_85ohm_5inch_dn" )
			)
			( signal "L10_85OHM_5INCH_DP"
				( objectStatus "@baseboard_fab2_lib.baseboard_fab2(sch_1):l10_85ohm_5inch_dp" )
			)
			( signal "L12_85OHM_5INCH_DN"
				( objectStatus "@baseboard_fab2_lib.baseboard_fab2(sch_1):l12_85ohm_5inch_dn" )
			)
			( signal "L12_85OHM_5INCH_DP"
				( objectStatus "@baseboard_fab2_lib.baseboard_fab2(sch_1):l12_85ohm_5inch_dp" )
			)
			( signal "L14_85OHM_5INCH_DN"
				( objectStatus "@baseboard_fab2_lib.baseboard_fab2(sch_1):l14_85ohm_5inch_dn" )
			)
			( signal "L14_85OHM_5INCH_DP"
				( objectStatus "@baseboard_fab2_lib.baseboard_fab2(sch_1):l14_85ohm_5inch_dp" )
			)
			( signal "L10_85OHM_10INCH_DN"
				( objectStatus "@baseboard_fab2_lib.baseboard_fab2(sch_1):l10_85ohm_10inch_dn" )
			)
			( signal "L10_85OHM_10INCH_DP"
				( objectStatus "@baseboard_fab2_lib.baseboard_fab2(sch_1):l10_85ohm_10inch_dp" )
			)
			( signal "L12_85OHM_10INCH_DN"
				( objectStatus "@baseboard_fab2_lib.baseboard_fab2(sch_1):l12_85ohm_10inch_dn" )
			)
			( signal "L12_85OHM_10INCH_DP"
				( objectStatus "@baseboard_fab2_lib.baseboard_fab2(sch_1):l12_85ohm_10inch_dp" )
			)
			( signal "L14_85OHM_10INCH_DN"
				( objectStatus "@baseboard_fab2_lib.baseboard_fab2(sch_1):l14_85ohm_10inch_dn" )
			)
			( signal "L14_85OHM_10INCH_DP"
				( objectStatus "@baseboard_fab2_lib.baseboard_fab2(sch_1):l14_85ohm_10inch_dp" )
			)
			( signal "L1_85OHM_10INCH_DN"
				( objectStatus "@baseboard_fab2_lib.baseboard_fab2(sch_1):l1_85ohm_10inch_dn" )
			)
			( signal "L1_85OHM_10INCH_DP"
				( objectStatus "@baseboard_fab2_lib.baseboard_fab2(sch_1):l1_85ohm_10inch_dp" )
			)
			( signal "L3_85OHM_10INCH_DN"
				( objectStatus "@baseboard_fab2_lib.baseboard_fab2(sch_1):l3_85ohm_10inch_dn" )
			)
			( signal "L3_85OHM_10INCH_DP"
				( objectStatus "@baseboard_fab2_lib.baseboard_fab2(sch_1):l3_85ohm_10inch_dp" )
			)
			( signal "L5_85OHM_10INCH_DN"
				( objectStatus "@baseboard_fab2_lib.baseboard_fab2(sch_1):l5_85ohm_10inch_dn" )
			)
			( signal "L5_85OHM_10INCH_DP"
				( objectStatus "@baseboard_fab2_lib.baseboard_fab2(sch_1):l5_85ohm_10inch_dp" )
			)
			( signal "L10_73OHM_6INCH_DN"
				( objectStatus "@baseboard_fab2_lib.baseboard_fab2(sch_1):l10_73ohm_6inch_dn" )
			)
			( signal "L10_73OHM_6INCH_DP"
				( objectStatus "@baseboard_fab2_lib.baseboard_fab2(sch_1):l10_73ohm_6inch_dp" )
			)
			( signal "L10_85OHM_6INCH_DN"
				( objectStatus "@baseboard_fab2_lib.baseboard_fab2(sch_1):l10_85ohm_6inch_dn" )
			)
			( signal "L10_85OHM_6INCH_DP"
				( objectStatus "@baseboard_fab2_lib.baseboard_fab2(sch_1):l10_85ohm_6inch_dp" )
			)
			( signal "L12_73OHM_6INCH_DN"
				( objectStatus "@baseboard_fab2_lib.baseboard_fab2(sch_1):l12_73ohm_6inch_dn" )
			)
			( signal "L12_73OHM_6INCH_DP"
				( objectStatus "@baseboard_fab2_lib.baseboard_fab2(sch_1):l12_73ohm_6inch_dp" )
			)
			( signal "L12_85OHM_6INCH_DN"
				( objectStatus "@baseboard_fab2_lib.baseboard_fab2(sch_1):l12_85ohm_6inch_dn" )
			)
			( signal "L12_85OHM_6INCH_DP"
				( objectStatus "@baseboard_fab2_lib.baseboard_fab2(sch_1):l12_85ohm_6inch_dp" )
			)
			( signal "L14_73OHM_6INCH_DN"
				( objectStatus "@baseboard_fab2_lib.baseboard_fab2(sch_1):l14_73ohm_6inch_dn" )
			)
			( signal "L14_73OHM_6INCH_DP"
				( objectStatus "@baseboard_fab2_lib.baseboard_fab2(sch_1):l14_73ohm_6inch_dp" )
			)
			( signal "L14_85OHM_6INCH_DN"
				( objectStatus "@baseboard_fab2_lib.baseboard_fab2(sch_1):l14_85ohm_6inch_dn" )
			)
			( signal "L14_85OHM_6INCH_DP"
				( objectStatus "@baseboard_fab2_lib.baseboard_fab2(sch_1):l14_85ohm_6inch_dp" )
			)
			( signal "L1_73OHM_6INCH_DN"
				( objectStatus "@baseboard_fab2_lib.baseboard_fab2(sch_1):l1_73ohm_6inch_dn" )
			)
			( signal "L1_73OHM_6INCH_DP"
				( objectStatus "@baseboard_fab2_lib.baseboard_fab2(sch_1):l1_73ohm_6inch_dp" )
			)
			( signal "L3_73OHM_6INCH_DN"
				( objectStatus "@baseboard_fab2_lib.baseboard_fab2(sch_1):l3_73ohm_6inch_dn" )
			)
			( signal "L3_73OHM_6INCH_DP"
				( objectStatus "@baseboard_fab2_lib.baseboard_fab2(sch_1):l3_73ohm_6inch_dp" )
			)
			( signal "L3_85OHM_6INCH_DN"
				( objectStatus "@baseboard_fab2_lib.baseboard_fab2(sch_1):l3_85ohm_6inch_dn" )
			)
			( signal "L3_85OHM_6INCH_DP"
				( objectStatus "@baseboard_fab2_lib.baseboard_fab2(sch_1):l3_85ohm_6inch_dp" )
			)
			( signal "L5_73OHM_6INCH_DN"
				( objectStatus "@baseboard_fab2_lib.baseboard_fab2(sch_1):l5_73ohm_6inch_dn" )
			)
			( signal "L5_73OHM_6INCH_DP"
				( objectStatus "@baseboard_fab2_lib.baseboard_fab2(sch_1):l5_73ohm_6inch_dp" )
			)
			( signal "L5_85OHM_6INCH_DN"
				( objectStatus "@baseboard_fab2_lib.baseboard_fab2(sch_1):l5_85ohm_6inch_dn" )
			)
			( signal "L5_85OHM_6INCH_DP"
				( objectStatus "@baseboard_fab2_lib.baseboard_fab2(sch_1):l5_85ohm_6inch_dp" )
			)
			( signal "L12_95OHM_6INCH_DP"
				( objectStatus "@baseboard_fab2_lib.baseboard_fab2(sch_1):l12_95ohm_6inch_dp" )
			)
			( signal "L10_100OHM_6INCH_DN"
				( objectStatus "@baseboard_fab2_lib.baseboard_fab2(sch_1):l10_100ohm_6inch_dn" )
			)
			( signal "L10_100OHM_6INCH_DP"
				( objectStatus "@baseboard_fab2_lib.baseboard_fab2(sch_1):l10_100ohm_6inch_dp" )
			)
			( signal "L12_100OHM_6INCH_DN"
				( objectStatus "@baseboard_fab2_lib.baseboard_fab2(sch_1):l12_100ohm_6inch_dn" )
			)
			( signal "L12_100OHM_6INCH_DP"
				( objectStatus "@baseboard_fab2_lib.baseboard_fab2(sch_1):l12_100ohm_6inch_dp" )
			)
			( signal "L14_100OHM_6INCH_DN"
				( objectStatus "@baseboard_fab2_lib.baseboard_fab2(sch_1):l14_100ohm_6inch_dn" )
			)
			( signal "L14_100OHM_6INCH_DP"
				( objectStatus "@baseboard_fab2_lib.baseboard_fab2(sch_1):l14_100ohm_6inch_dp" )
			)
			( signal "L1_100OHM_6INCH_DN"
				( objectStatus "@baseboard_fab2_lib.baseboard_fab2(sch_1):l1_100ohm_6inch_dn" )
			)
			( signal "L1_100OHM_6INCH_DP"
				( objectStatus "@baseboard_fab2_lib.baseboard_fab2(sch_1):l1_100ohm_6inch_dp" )
			)
			( signal "L10_40OHM_6INCH"
				( objectStatus "@baseboard_fab2_lib.baseboard_fab2(sch_1):l10_40ohm_6inch" )
			)
			( signal "L10_50OHM_6INCH"
				( objectStatus "@baseboard_fab2_lib.baseboard_fab2(sch_1):l10_50ohm_6inch" )
			)
			( signal "L12_40OHM_6INCH"
				( objectStatus "@baseboard_fab2_lib.baseboard_fab2(sch_1):l12_40ohm_6inch" )
			)
			( signal "L12_50OHM_6INCH"
				( objectStatus "@baseboard_fab2_lib.baseboard_fab2(sch_1):l12_50ohm_6inch" )
			)
			( signal "L14_40OHM_6INCH"
				( objectStatus "@baseboard_fab2_lib.baseboard_fab2(sch_1):l14_40ohm_6inch" )
			)
			( signal "L14_50OHM_6INCH"
				( objectStatus "@baseboard_fab2_lib.baseboard_fab2(sch_1):l14_50ohm_6inch" )
			)
			( signal "L1_40OHM_6INCH"
				( objectStatus "@baseboard_fab2_lib.baseboard_fab2(sch_1):l1_40ohm_6inch" )
			)
			( signal "L1_50OHM_6INCH"
				( objectStatus "@baseboard_fab2_lib.baseboard_fab2(sch_1):l1_50ohm_6inch" )
			)
			( signal "L3_40OHM_6INCH"
				( objectStatus "@baseboard_fab2_lib.baseboard_fab2(sch_1):l3_40ohm_6inch" )
			)
			( signal "L3_50OHM_6INCH"
				( objectStatus "@baseboard_fab2_lib.baseboard_fab2(sch_1):l3_50ohm_6inch" )
			)
			( signal "L5_40OHM_6INCH"
				( objectStatus "@baseboard_fab2_lib.baseboard_fab2(sch_1):l5_40ohm_6inch" )
			)
			( signal "L5_50OHM_6INCH"
				( objectStatus "@baseboard_fab2_lib.baseboard_fab2(sch_1):l5_50ohm_6inch" )
			)
			( signal "L12_95OHM_6INCH_DN"
				( objectStatus "@baseboard_fab2_lib.baseboard_fab2(sch_1):l12_95ohm_6inch_dn" )
			)
			( signal "L1_95OHM_6INCH_DN"
				( objectStatus "@baseboard_fab2_lib.baseboard_fab2(sch_1):l1_95ohm_6inch_dn" )
			)
			( signal "FM_BATTERY_SENSE_EN_R_N"
				( objectStatus "@baseboard_fab2_lib.baseboard_fab2(sch_1):fm_battery_sense_en_r_n" )
			)
			( signal "L1_95OHM_6INCH_DP"
				( objectStatus "@baseboard_fab2_lib.baseboard_fab2(sch_1):l1_95ohm_6inch_dp" )
			)
			( signal "FM_CPU0_RC_ERROR_R_N"
				( objectStatus "@baseboard_fab2_lib.baseboard_fab2(sch_1):fm_cpu0_rc_error_r_n" )
			)
			( signal "FM_POST_CARD_PRES_BMC_R1_N"
				( objectStatus "@baseboard_fab2_lib.baseboard_fab2(sch_1):fm_post_card_pres_bmc_r1_n" )
			)
			( signal "FM_CPU0_RC_ERROR_R1_N"
				( objectStatus "@baseboard_fab2_lib.baseboard_fab2(sch_1):fm_cpu0_rc_error_r1_n" )
			)
			( signal "FM_CPU1_RC_ERROR_R1_N"
				( objectStatus "@baseboard_fab2_lib.baseboard_fab2(sch_1):fm_cpu1_rc_error_r1_n" )
			)
			( signal "FM_CPU1_RC_ERROR_R_N"
				( objectStatus "@baseboard_fab2_lib.baseboard_fab2(sch_1):fm_cpu1_rc_error_r_n" )
			)
			( signal "JTAG_BMC_BUF_TDO_R"
				( objectStatus "@baseboard_fab2_lib.baseboard_fab2(sch_1):jtag_bmc_buf_tdo_r" )
			)
			( signal "EXT_MDIO_I2C_SEL"
				( objectStatus "@baseboard_fab2_lib.baseboard_fab2(sch_1):ext_mdio_i2c_sel" )
			)
			( signal "FM_BMC_READY_R_N"
				( objectStatus "@baseboard_fab2_lib.baseboard_fab2(sch_1):fm_bmc_ready_r_n" )
			)
			( signal "FM_BMC_READY_R1_N"
				( objectStatus "@baseboard_fab2_lib.baseboard_fab2(sch_1):fm_bmc_ready_r1_n" )
			)
			( signal "FM_OCP_MEZZA_PRES_R"
				( objectStatus "@baseboard_fab2_lib.baseboard_fab2(sch_1):fm_ocp_mezza_pres_r" )
			)
			( signal "FM_THROTTLE_R2_N"
				( objectStatus "@baseboard_fab2_lib.baseboard_fab2(sch_1):fm_throttle_r2_n" )
			)
			( signal "IRQ_DIMM_SAVE_LVT3_R_N"
				( objectStatus "@baseboard_fab2_lib.baseboard_fab2(sch_1):irq_dimm_save_lvt3_r_n" )
			)
			( signal "IRQ_SML1_PMBUS_ALERT_R1_N"
				( objectStatus "@baseboard_fab2_lib.baseboard_fab2(sch_1):irq_sml1_pmbus_alert_r1_n" )
			)
			( signal "JTAG_BMC_TCK_BUF"
				( objectStatus "@baseboard_fab2_lib.baseboard_fab2(sch_1):jtag_bmc_tck_buf" )
			)
			( signal "JTAG_RISER_TRST"
				( objectStatus "@baseboard_fab2_lib.baseboard_fab2(sch_1):jtag_riser_trst" )
			)
			( signal "JTAG_RISER_TDI_R"
				( objectStatus "@baseboard_fab2_lib.baseboard_fab2(sch_1):jtag_riser_tdi_r" )
			)
			( signal "JTAG_RISER_TDO_R"
				( objectStatus "@baseboard_fab2_lib.baseboard_fab2(sch_1):jtag_riser_tdo_r" )
			)
			( signal "JTAG_PLD_TDO_MUX_R"
				( objectStatus "@baseboard_fab2_lib.baseboard_fab2(sch_1):jtag_pld_tdo_mux_r" )
			)
			( signal "JTAG_RISER_N"
				( objectStatus "@baseboard_fab2_lib.baseboard_fab2(sch_1):jtag_riser_n" )
			)
			( gate "R6N10"
				( objectStatus "@baseboard_fab2_lib.baseboard_fab2(sch_1):page21_i149" )
			)
			( gate "R6N12"
				( objectStatus "@baseboard_fab2_lib.baseboard_fab2(sch_1):page21_i150" )
			)
			( gate "R6N11"
				( objectStatus "@baseboard_fab2_lib.baseboard_fab2(sch_1):page21_i151" )
			)
			( gate "R6B3"
				( objectStatus "@baseboard_fab2_lib.baseboard_fab2(sch_1):page21_i152" )
			)
			( gate "R6B5"
				( objectStatus "@baseboard_fab2_lib.baseboard_fab2(sch_1):page21_i153" )
			)
			( gate "R6B4"
				( objectStatus "@baseboard_fab2_lib.baseboard_fab2(sch_1):page21_i154" )
			)
			( gate "R6B2"
				( objectStatus "@baseboard_fab2_lib.baseboard_fab2(sch_1):page21_i159" )
			)
			( gate "R6B1"
				( objectStatus "@baseboard_fab2_lib.baseboard_fab2(sch_1):page21_i161" )
			)
			( gate "R6N2"
				( objectStatus "@baseboard_fab2_lib.baseboard_fab2(sch_1):page21_i163" )
			)
			( gate "R6N1"
				( objectStatus "@baseboard_fab2_lib.baseboard_fab2(sch_1):page21_i164" )
			)
			( gate "R5D1"
				( objectStatus "@baseboard_fab2_lib.baseboard_fab2(sch_1):page21_i177" )
			)
			( gate "R5D2"
				( objectStatus "@baseboard_fab2_lib.baseboard_fab2(sch_1):page21_i178" )
			)
			( gate "R6D1"
				( objectStatus "@baseboard_fab2_lib.baseboard_fab2(sch_1):page21_i179" )
			)
			( gate "R4P8"
				( objectStatus "@baseboard_fab2_lib.baseboard_fab2(sch_1):page21_i180" )
			)
			( gate "R4P10"
				( objectStatus "@baseboard_fab2_lib.baseboard_fab2(sch_1):page21_i181" )
			)
			( gate "R4P11"
				( objectStatus "@baseboard_fab2_lib.baseboard_fab2(sch_1):page21_i182" )
			)
			( gate "R6D11"
				( objectStatus "@baseboard_fab2_lib.baseboard_fab2(sch_1):page21_i184" )
			)
			( gate "R4P3"
				( objectStatus "@baseboard_fab2_lib.baseboard_fab2(sch_1):page21_i186" )
			)
			( gate "R4P2"
				( objectStatus "@baseboard_fab2_lib.baseboard_fab2(sch_1):page21_i188" )
			)
			( gate "R4P4"
				( objectStatus "@baseboard_fab2_lib.baseboard_fab2(sch_1):page21_i189" )
			)
			( gate "R6D2"
				( objectStatus "@baseboard_fab2_lib.baseboard_fab2(sch_1):page21_i204" )
			)
			( gate "XRU1"
				( objectStatus "@baseboard_fab2_lib.baseboard_fab2(sch_1):page21_i216" )
			)
			( gate "XLU1"
				( objectStatus "@baseboard_fab2_lib.baseboard_fab2(sch_1):page21_i217" )
			)
			( gate "R4P19"
				( objectStatus "@baseboard_fab2_lib.baseboard_fab2(sch_1):page21_i219" )
			)
			( gate "R5N2"
				( objectStatus "@baseboard_fab2_lib.baseboard_fab2(sch_1):page21_i227" )
			)
			( gate "R5N1"
				( objectStatus "@baseboard_fab2_lib.baseboard_fab2(sch_1):page21_i238" )
			)
			( gate "R5N5"
				( objectStatus "@baseboard_fab2_lib.baseboard_fab2(sch_1):page21_i239" )
			)
			( gate "R5N3"
				( objectStatus "@baseboard_fab2_lib.baseboard_fab2(sch_1):page21_i240" )
			)
			( gate "R5N4"
				( objectStatus "@baseboard_fab2_lib.baseboard_fab2(sch_1):page21_i241" )
			)
			( gate "R4P18"
				( objectStatus "@baseboard_fab2_lib.baseboard_fab2(sch_1):page21_i244" )
			)
			( gate "R4R5"
				( objectStatus "@baseboard_fab2_lib.baseboard_fab2(sch_1):page21_i258" )
			)
			( gate "U5D1"
				( objectStatus "@baseboard_fab2_lib.baseboard_fab2(sch_1):page21_i259" )
			)
			( gate "R5R1"
				( objectStatus "@baseboard_fab2_lib.baseboard_fab2(sch_1):page22_i188" )
			)
			( gate "R5P4"
				( objectStatus "@baseboard_fab2_lib.baseboard_fab2(sch_1):page22_i190" )
			)
			( gate "U5D1"
				( objectStatus "@baseboard_fab2_lib.baseboard_fab2(sch_1):page22_i204" )
			)
			( gate "U5D1"
				( objectStatus "@baseboard_fab2_lib.baseboard_fab2(sch_1):page23_i172" )
			)
			( gate "U5D1"
				( objectStatus "@baseboard_fab2_lib.baseboard_fab2(sch_1):page24_i172" )
			)
			( gate "U5D1"
				( objectStatus "@baseboard_fab2_lib.baseboard_fab2(sch_1):page25_i172" )
			)
			( gate "U5D1"
				( objectStatus "@baseboard_fab2_lib.baseboard_fab2(sch_1):page26_i172" )
			)
			( gate "U5D1"
				( objectStatus "@baseboard_fab2_lib.baseboard_fab2(sch_1):page27_i172" )
			)
			( gate "U5D1"
				( objectStatus "@baseboard_fab2_lib.baseboard_fab2(sch_1):page28_i172" )
			)
			( gate "U5D1"
				( objectStatus "@baseboard_fab2_lib.baseboard_fab2(sch_1):page29_i61" )
			)
			( gate "U5D1"
				( objectStatus "@baseboard_fab2_lib.baseboard_fab2(sch_1):page30_i84" )
			)
			( gate "U5D1"
				( objectStatus "@baseboard_fab2_lib.baseboard_fab2(sch_1):page31_i106" )
			)
			( gate "U5D1"
				( objectStatus "@baseboard_fab2_lib.baseboard_fab2(sch_1):page32_i89" )
			)
			( gate "U5D1"
				( objectStatus "@baseboard_fab2_lib.baseboard_fab2(sch_1):page33_i86" )
			)
			( gate "U5D1"
				( objectStatus "@baseboard_fab2_lib.baseboard_fab2(sch_1):page34_i86" )
			)
			( gate "U5D1"
				( objectStatus "@baseboard_fab2_lib.baseboard_fab2(sch_1):page35_i3" )
			)
			( gate "U5D1"
				( objectStatus "@baseboard_fab2_lib.baseboard_fab2(sch_1):page36_i15" )
			)
			( gate "U5D1"
				( objectStatus "@baseboard_fab2_lib.baseboard_fab2(sch_1):page36_i16" )
			)
			( gate "R5D5"
				( objectStatus "@baseboard_fab2_lib.baseboard_fab2(sch_1):page37_i303" )
			)
			( gate "R5P1"
				( objectStatus "@baseboard_fab2_lib.baseboard_fab2(sch_1):page37_i309" )
			)
			( gate "U5D1"
				( objectStatus "@baseboard_fab2_lib.baseboard_fab2(sch_1):page37_i310" )
			)
			( gate "U5D1"
				( objectStatus "@baseboard_fab2_lib.baseboard_fab2(sch_1):page37_i311" )
			)
			( gate "R5D6"
				( objectStatus "@baseboard_fab2_lib.baseboard_fab2(sch_1):page37_i312" )
			)
			( gate "C6D1"
				( objectStatus "@baseboard_fab2_lib.baseboard_fab2(sch_1):page38_i19" )
			)
			( gate "U5D1"
				( objectStatus "@baseboard_fab2_lib.baseboard_fab2(sch_1):page38_i33" )
			)
			( gate "U5D1"
				( objectStatus "@baseboard_fab2_lib.baseboard_fab2(sch_1):page38_i34" )
			)
			( gate "U5D1"
				( objectStatus "@baseboard_fab2_lib.baseboard_fab2(sch_1):page39_i127" )
			)
			( gate "U5D1"
				( objectStatus "@baseboard_fab2_lib.baseboard_fab2(sch_1):page40_i20" )
			)
			( gate "U5D1"
				( objectStatus "@baseboard_fab2_lib.baseboard_fab2(sch_1):page40_i21" )
			)
			( gate "U5D1"
				( objectStatus "@baseboard_fab2_lib.baseboard_fab2(sch_1):page40_i22" )
			)
			( gate "U5D1"
				( objectStatus "@baseboard_fab2_lib.baseboard_fab2(sch_1):page40_i23" )
			)
			( gate "U5D1"
				( objectStatus "@baseboard_fab2_lib.baseboard_fab2(sch_1):page41_i283" )
			)
			( gate "U5D1"
				( objectStatus "@baseboard_fab2_lib.baseboard_fab2(sch_1):page41_i284" )
			)
			( gate "U5D1"
				( objectStatus "@baseboard_fab2_lib.baseboard_fab2(sch_1):page41_i285" )
			)
			( gate "U5D1"
				( objectStatus "@baseboard_fab2_lib.baseboard_fab2(sch_1):page41_i286" )
			)
			( gate "C4P1"
				( objectStatus "@baseboard_fab2_lib.baseboard_fab2(sch_1):page42_i10" )
			)
			( gate "C4P9"
				( objectStatus "@baseboard_fab2_lib.baseboard_fab2(sch_1):page42_i12" )
			)
			( gate "C4P10"
				( objectStatus "@baseboard_fab2_lib.baseboard_fab2(sch_1):page42_i17" )
			)
			( gate "C8P5"
				( objectStatus "@baseboard_fab2_lib.baseboard_fab2(sch_1):page76_i246" )
			)
			( gate "C5P9"
				( objectStatus "@baseboard_fab2_lib.baseboard_fab2(sch_1):page42_i215" )
			)
			( gate "C5P7"
				( objectStatus "@baseboard_fab2_lib.baseboard_fab2(sch_1):page42_i25" )
			)
			( gate "C5P23"
				( objectStatus "@baseboard_fab2_lib.baseboard_fab2(sch_1):page42_i28" )
			)
			( gate "C5P24"
				( objectStatus "@baseboard_fab2_lib.baseboard_fab2(sch_1):page42_i33" )
			)
			( gate "C5P25"
				( objectStatus "@baseboard_fab2_lib.baseboard_fab2(sch_1):page42_i37" )
			)
			( gate "C5P14"
				( objectStatus "@baseboard_fab2_lib.baseboard_fab2(sch_1):page42_i41" )
			)
			( gate "C5P27"
				( objectStatus "@baseboard_fab2_lib.baseboard_fab2(sch_1):page42_i44" )
			)
			( gate "C5P33"
				( objectStatus "@baseboard_fab2_lib.baseboard_fab2(sch_1):page42_i50" )
			)
			( gate "C5P35"
				( objectStatus "@baseboard_fab2_lib.baseboard_fab2(sch_1):page42_i51" )
			)
			( gate "C5P32"
				( objectStatus "@baseboard_fab2_lib.baseboard_fab2(sch_1):page42_i53" )
			)
			( gate "C5P34"
				( objectStatus "@baseboard_fab2_lib.baseboard_fab2(sch_1):page42_i54" )
			)
			( gate "C5P22"
				( objectStatus "@baseboard_fab2_lib.baseboard_fab2(sch_1):page42_i55" )
			)
			( gate "C5P26"
				( objectStatus "@baseboard_fab2_lib.baseboard_fab2(sch_1):page42_i56" )
			)
			( gate "C5P40"
				( objectStatus "@baseboard_fab2_lib.baseboard_fab2(sch_1):page42_i57" )
			)
			( gate "C8P32"
				( objectStatus "@baseboard_fab2_lib.baseboard_fab2(sch_1):page225_i317" )
			)
			( gate "C7P20"
				( objectStatus "@baseboard_fab2_lib.baseboard_fab2(sch_1):page225_i318" )
			)
			( gate "C8P33"
				( objectStatus "@baseboard_fab2_lib.baseboard_fab2(sch_1):page225_i316" )
			)
			( gate "C5P37"
				( objectStatus "@baseboard_fab2_lib.baseboard_fab2(sch_1):page42_i63" )
			)
			( gate "C5P36"
				( objectStatus "@baseboard_fab2_lib.baseboard_fab2(sch_1):page42_i65" )
			)
			( gate "C6D8"
				( objectStatus "@baseboard_fab2_lib.baseboard_fab2(sch_1):page42_i68" )
			)
			( gate "C5D38"
				( objectStatus "@baseboard_fab2_lib.baseboard_fab2(sch_1):page42_i69" )
			)
			( gate "C5D37"
				( objectStatus "@baseboard_fab2_lib.baseboard_fab2(sch_1):page42_i70" )
			)
			( gate "C6D7"
				( objectStatus "@baseboard_fab2_lib.baseboard_fab2(sch_1):page42_i72" )
			)
			( gate "C6D4"
				( objectStatus "@baseboard_fab2_lib.baseboard_fab2(sch_1):page42_i74" )
			)
			( gate "C6D5"
				( objectStatus "@baseboard_fab2_lib.baseboard_fab2(sch_1):page42_i75" )
			)
			( gate "C6D2"
				( objectStatus "@baseboard_fab2_lib.baseboard_fab2(sch_1):page42_i77" )
			)
			( gate "C6D3"
				( objectStatus "@baseboard_fab2_lib.baseboard_fab2(sch_1):page42_i80" )
			)
			( gate "C6D6"
				( objectStatus "@baseboard_fab2_lib.baseboard_fab2(sch_1):page42_i81" )
			)
			( gate "C5D51"
				( objectStatus "@baseboard_fab2_lib.baseboard_fab2(sch_1):page42_i83" )
			)
			( gate "C5D21"
				( objectStatus "@baseboard_fab2_lib.baseboard_fab2(sch_1):page42_i88" )
			)
			( gate "C5D50"
				( objectStatus "@baseboard_fab2_lib.baseboard_fab2(sch_1):page42_i89" )
			)
			( gate "C5D48"
				( objectStatus "@baseboard_fab2_lib.baseboard_fab2(sch_1):page42_i90" )
			)
			( gate "C5D13"
				( objectStatus "@baseboard_fab2_lib.baseboard_fab2(sch_1):page42_i91" )
			)
			( gate "C5D11"
				( objectStatus "@baseboard_fab2_lib.baseboard_fab2(sch_1):page42_i93" )
			)
			( gate "C5D12"
				( objectStatus "@baseboard_fab2_lib.baseboard_fab2(sch_1):page42_i94" )
			)
			( gate "C5D23"
				( objectStatus "@baseboard_fab2_lib.baseboard_fab2(sch_1):page42_i98" )
			)
			( gate "C5D28"
				( objectStatus "@baseboard_fab2_lib.baseboard_fab2(sch_1):page42_i100" )
			)
			( gate "C5D29"
				( objectStatus "@baseboard_fab2_lib.baseboard_fab2(sch_1):page42_i102" )
			)
			( gate "C5D32"
				( objectStatus "@baseboard_fab2_lib.baseboard_fab2(sch_1):page42_i103" )
			)
			( gate "C5D47"
				( objectStatus "@baseboard_fab2_lib.baseboard_fab2(sch_1):page42_i104" )
			)
			( gate "C5D31"
				( objectStatus "@baseboard_fab2_lib.baseboard_fab2(sch_1):page42_i106" )
			)
			( gate "C5D46"
				( objectStatus "@baseboard_fab2_lib.baseboard_fab2(sch_1):page42_i107" )
			)
			( gate "C5D10"
				( objectStatus "@baseboard_fab2_lib.baseboard_fab2(sch_1):page42_i108" )
			)
			( gate "C5D27"
				( objectStatus "@baseboard_fab2_lib.baseboard_fab2(sch_1):page42_i109" )
			)
			( gate "C5D30"
				( objectStatus "@baseboard_fab2_lib.baseboard_fab2(sch_1):page42_i111" )
			)
			( gate "C5D60"
				( objectStatus "@baseboard_fab2_lib.baseboard_fab2(sch_1):page217_i272" )
			)
			( gate "C5D59"
				( objectStatus "@baseboard_fab2_lib.baseboard_fab2(sch_1):page217_i271" )
			)
			( gate "C5D41"
				( objectStatus "@baseboard_fab2_lib.baseboard_fab2(sch_1):page42_i114" )
			)
			( gate "C5D40"
				( objectStatus "@baseboard_fab2_lib.baseboard_fab2(sch_1):page42_i115" )
			)
			( gate "C5D14"
				( objectStatus "@baseboard_fab2_lib.baseboard_fab2(sch_1):page42_i117" )
			)
			( gate "C5D17"
				( objectStatus "@baseboard_fab2_lib.baseboard_fab2(sch_1):page42_i118" )
			)
			( gate "C5D61"
				( objectStatus "@baseboard_fab2_lib.baseboard_fab2(sch_1):page217_i270" )
			)
			( gate "C5D16"
				( objectStatus "@baseboard_fab2_lib.baseboard_fab2(sch_1):page42_i123" )
			)
			( gate "C5D5"
				( objectStatus "@baseboard_fab2_lib.baseboard_fab2(sch_1):page42_i125" )
			)
			( gate "C5D1"
				( objectStatus "@baseboard_fab2_lib.baseboard_fab2(sch_1):page220_i252" )
			)
			( gate "C5D2"
				( objectStatus "@baseboard_fab2_lib.baseboard_fab2(sch_1):page220_i251" )
			)
			( gate "C5D19"
				( objectStatus "@baseboard_fab2_lib.baseboard_fab2(sch_1):page42_i128" )
			)
			( gate "C5D58"
				( objectStatus "@baseboard_fab2_lib.baseboard_fab2(sch_1):page217_i269" )
			)
			( gate "C5D3"
				( objectStatus "@baseboard_fab2_lib.baseboard_fab2(sch_1):page220_i250" )
			)
			( gate "C5D43"
				( objectStatus "@baseboard_fab2_lib.baseboard_fab2(sch_1):page42_i131" )
			)
			( gate "C5D15"
				( objectStatus "@baseboard_fab2_lib.baseboard_fab2(sch_1):page42_i132" )
			)
			( gate "C5D18"
				( objectStatus "@baseboard_fab2_lib.baseboard_fab2(sch_1):page42_i134" )
			)
			( gate "C5D42"
				( objectStatus "@baseboard_fab2_lib.baseboard_fab2(sch_1):page42_i135" )
			)
			( gate "C5D4"
				( objectStatus "@baseboard_fab2_lib.baseboard_fab2(sch_1):page220_i249" )
			)
			( gate "C5D24"
				( objectStatus "@baseboard_fab2_lib.baseboard_fab2(sch_1):page42_i138" )
			)
			( gate "C5D39"
				( objectStatus "@baseboard_fab2_lib.baseboard_fab2(sch_1):page42_i140" )
			)
			( gate "C5D44"
				( objectStatus "@baseboard_fab2_lib.baseboard_fab2(sch_1):page42_i142" )
			)
			( gate "C6D9"
				( objectStatus "@baseboard_fab2_lib.baseboard_fab2(sch_1):page42_i145" )
			)
			( gate "C6D10"
				( objectStatus "@baseboard_fab2_lib.baseboard_fab2(sch_1):page42_i147" )
			)
			( gate "C5D36"
				( objectStatus "@baseboard_fab2_lib.baseboard_fab2(sch_1):page42_i151" )
			)
			( gate "C5D49"
				( objectStatus "@baseboard_fab2_lib.baseboard_fab2(sch_1):page42_i152" )
			)
			( gate "C5D22"
				( objectStatus "@baseboard_fab2_lib.baseboard_fab2(sch_1):page42_i153" )
			)
			( gate "C5D26"
				( objectStatus "@baseboard_fab2_lib.baseboard_fab2(sch_1):page42_i154" )
			)
			( gate "C5D25"
				( objectStatus "@baseboard_fab2_lib.baseboard_fab2(sch_1):page42_i155" )
			)
			( gate "C5D45"
				( objectStatus "@baseboard_fab2_lib.baseboard_fab2(sch_1):page42_i156" )
			)
			( gate "C4P6"
				( objectStatus "@baseboard_fab2_lib.baseboard_fab2(sch_1):page42_i164" )
			)
			( gate "C5D20"
				( objectStatus "@baseboard_fab2_lib.baseboard_fab2(sch_1):page42_i173" )
			)
			( gate "C5D33"
				( objectStatus "@baseboard_fab2_lib.baseboard_fab2(sch_1):page42_i174" )
			)
			( gate "C5D34"
				( objectStatus "@baseboard_fab2_lib.baseboard_fab2(sch_1):page42_i175" )
			)
			( gate "C5D35"
				( objectStatus "@baseboard_fab2_lib.baseboard_fab2(sch_1):page42_i176" )
			)
			( gate "C4P8"
				( objectStatus "@baseboard_fab2_lib.baseboard_fab2(sch_1):page42_i178" )
			)
			( gate "C5D53"
				( objectStatus "@baseboard_fab2_lib.baseboard_fab2(sch_1):page42_i179" )
			)
			( gate "C5D52"
				( objectStatus "@baseboard_fab2_lib.baseboard_fab2(sch_1):page42_i180" )
			)
			( gate "C5P15"
				( objectStatus "@baseboard_fab2_lib.baseboard_fab2(sch_1):page42_i187" )
			)
			( gate "C5P16"
				( objectStatus "@baseboard_fab2_lib.baseboard_fab2(sch_1):page42_i188" )
			)
			( gate "C5P17"
				( objectStatus "@baseboard_fab2_lib.baseboard_fab2(sch_1):page42_i190" )
			)
			( gate "J4G1"
				( objectStatus "@baseboard_fab2_lib.baseboard_fab2(sch_1):page43_i1" )
			)
			( gate "J4G1"
				( objectStatus "@baseboard_fab2_lib.baseboard_fab2(sch_1):page43_i2" )
			)
			( gate "J4G1"
				( objectStatus "@baseboard_fab2_lib.baseboard_fab2(sch_1):page43_i259" )
			)
			( gate "J4G1"
				( objectStatus "@baseboard_fab2_lib.baseboard_fab2(sch_1):page43_i260" )
			)
			( gate "C4F10"
				( objectStatus "@baseboard_fab2_lib.baseboard_fab2(sch_1):page43_i272" )
			)
			( gate "C6T1"
				( objectStatus "@baseboard_fab2_lib.baseboard_fab2(sch_1):page44_i2" )
			)
			( gate "J6T1"
				( objectStatus "@baseboard_fab2_lib.baseboard_fab2(sch_1):page44_i13" )
			)
			( gate "J6T1"
				( objectStatus "@baseboard_fab2_lib.baseboard_fab2(sch_1):page44_i75" )
			)
			( gate "J6T1"
				( objectStatus "@baseboard_fab2_lib.baseboard_fab2(sch_1):page44_i120" )
			)
			( gate "J6T1"
				( objectStatus "@baseboard_fab2_lib.baseboard_fab2(sch_1):page44_i139" )
			)
			( gate "J4G2"
				( objectStatus "@baseboard_fab2_lib.baseboard_fab2(sch_1):page45_i43" )
			)
			( gate "J4G2"
				( objectStatus "@baseboard_fab2_lib.baseboard_fab2(sch_1):page45_i61" )
			)
			( gate "J4G2"
				( objectStatus "@baseboard_fab2_lib.baseboard_fab2(sch_1):page45_i111" )
			)
			( gate "J4G2"
				( objectStatus "@baseboard_fab2_lib.baseboard_fab2(sch_1):page45_i169" )
			)
			( gate "C4G3"
				( objectStatus "@baseboard_fab2_lib.baseboard_fab2(sch_1):page45_i179" )
			)
			( gate "C6U9"
				( objectStatus "@baseboard_fab2_lib.baseboard_fab2(sch_1):page46_i5" )
			)
			( gate "J6U1"
				( objectStatus "@baseboard_fab2_lib.baseboard_fab2(sch_1):page46_i14" )
			)
			( gate "J6U1"
				( objectStatus "@baseboard_fab2_lib.baseboard_fab2(sch_1):page46_i67" )
			)
			( gate "J6U1"
				( objectStatus "@baseboard_fab2_lib.baseboard_fab2(sch_1):page46_i112" )
			)
			( gate "J6U1"
				( objectStatus "@baseboard_fab2_lib.baseboard_fab2(sch_1):page46_i138" )
			)
			( gate "J4G3"
				( objectStatus "@baseboard_fab2_lib.baseboard_fab2(sch_1):page47_i43" )
			)
			( gate "J4G3"
				( objectStatus "@baseboard_fab2_lib.baseboard_fab2(sch_1):page47_i61" )
			)
			( gate "J4G3"
				( objectStatus "@baseboard_fab2_lib.baseboard_fab2(sch_1):page47_i111" )
			)
			( gate "J4G3"
				( objectStatus "@baseboard_fab2_lib.baseboard_fab2(sch_1):page47_i179" )
			)
			( gate "C4G19"
				( objectStatus "@baseboard_fab2_lib.baseboard_fab2(sch_1):page47_i188" )
			)
			( gate "J6U2"
				( objectStatus "@baseboard_fab2_lib.baseboard_fab2(sch_1):page48_i43" )
			)
			( gate "J6U2"
				( objectStatus "@baseboard_fab2_lib.baseboard_fab2(sch_1):page48_i61" )
			)
			( gate "J6U2"
				( objectStatus "@baseboard_fab2_lib.baseboard_fab2(sch_1):page48_i111" )
			)
			( gate "J6U2"
				( objectStatus "@baseboard_fab2_lib.baseboard_fab2(sch_1):page48_i171" )
			)
			( gate "C6U17"
				( objectStatus "@baseboard_fab2_lib.baseboard_fab2(sch_1):page48_i176" )
			)
			( gate "J4B1"
				( objectStatus "@baseboard_fab2_lib.baseboard_fab2(sch_1):page49_i43" )
			)
			( gate "J4B1"
				( objectStatus "@baseboard_fab2_lib.baseboard_fab2(sch_1):page49_i66" )
			)
			( gate "J4B1"
				( objectStatus "@baseboard_fab2_lib.baseboard_fab2(sch_1):page49_i111" )
			)
			( gate "J4B1"
				( objectStatus "@baseboard_fab2_lib.baseboard_fab2(sch_1):page49_i169" )
			)
			( gate "C4B12"
				( objectStatus "@baseboard_fab2_lib.baseboard_fab2(sch_1):page49_i179" )
			)
			( gate "J6M1"
				( objectStatus "@baseboard_fab2_lib.baseboard_fab2(sch_1):page50_i44" )
			)
			( gate "J6M1"
				( objectStatus "@baseboard_fab2_lib.baseboard_fab2(sch_1):page50_i46" )
			)
			( gate "J6M1"
				( objectStatus "@baseboard_fab2_lib.baseboard_fab2(sch_1):page50_i50" )
			)
			( gate "J6M1"
				( objectStatus "@baseboard_fab2_lib.baseboard_fab2(sch_1):page50_i158" )
			)
			( gate "C6M1"
				( objectStatus "@baseboard_fab2_lib.baseboard_fab2(sch_1):page50_i177" )
			)
			( gate "J4A2"
				( objectStatus "@baseboard_fab2_lib.baseboard_fab2(sch_1):page51_i43" )
			)
			( gate "J4A2"
				( objectStatus "@baseboard_fab2_lib.baseboard_fab2(sch_1):page51_i66" )
			)
			( gate "J4A2"
				( objectStatus "@baseboard_fab2_lib.baseboard_fab2(sch_1):page51_i111" )
			)
			( gate "J4A2"
				( objectStatus "@baseboard_fab2_lib.baseboard_fab2(sch_1):page51_i167" )
			)
			( gate "C6L6"
				( objectStatus "@baseboard_fab2_lib.baseboard_fab2(sch_1):page51_i175" )
			)
			( gate "C4A18"
				( objectStatus "@baseboard_fab2_lib.baseboard_fab2(sch_1):page52_i3" )
			)
			( gate "J6L2"
				( objectStatus "@baseboard_fab2_lib.baseboard_fab2(sch_1):page52_i12" )
			)
			( gate "J6L2"
				( objectStatus "@baseboard_fab2_lib.baseboard_fab2(sch_1):page52_i55" )
			)
			( gate "J6L2"
				( objectStatus "@baseboard_fab2_lib.baseboard_fab2(sch_1):page52_i100" )
			)
			( gate "J6L2"
				( objectStatus "@baseboard_fab2_lib.baseboard_fab2(sch_1):page52_i138" )
			)
			( gate "J4A1"
				( objectStatus "@baseboard_fab2_lib.baseboard_fab2(sch_1):page53_i43" )
			)
			( gate "J4A1"
				( objectStatus "@baseboard_fab2_lib.baseboard_fab2(sch_1):page53_i66" )
			)
			( gate "J4A1"
				( objectStatus "@baseboard_fab2_lib.baseboard_fab2(sch_1):page53_i111" )
			)
			( gate "J4A1"
				( objectStatus "@baseboard_fab2_lib.baseboard_fab2(sch_1):page53_i171" )
			)
			( gate "C6L1"
				( objectStatus "@baseboard_fab2_lib.baseboard_fab2(sch_1):page53_i178" )
			)
			( gate "J6L1"
				( objectStatus "@baseboard_fab2_lib.baseboard_fab2(sch_1):page54_i43" )
			)
			( gate "J6L1"
				( objectStatus "@baseboard_fab2_lib.baseboard_fab2(sch_1):page54_i66" )
			)
			( gate "J6L1"
				( objectStatus "@baseboard_fab2_lib.baseboard_fab2(sch_1):page54_i111" )
			)
			( gate "J6L1"
				( objectStatus "@baseboard_fab2_lib.baseboard_fab2(sch_1):page54_i170" )
			)
			( gate "C4A5"
				( objectStatus "@baseboard_fab2_lib.baseboard_fab2(sch_1):page54_i179" )
			)
			( gate "R9N1"
				( objectStatus "@baseboard_fab2_lib.baseboard_fab2(sch_1):page55_i4" )
			)
			( gate "R9N2"
				( objectStatus "@baseboard_fab2_lib.baseboard_fab2(sch_1):page55_i7" )
			)
			( gate "R3B2"
				( objectStatus "@baseboard_fab2_lib.baseboard_fab2(sch_1):page55_i19" )
			)
			( gate "R3B4"
				( objectStatus "@baseboard_fab2_lib.baseboard_fab2(sch_1):page55_i21" )
			)
			( gate "R1C2"
				( objectStatus "@baseboard_fab2_lib.baseboard_fab2(sch_1):page55_i24" )
			)
			( gate "R1C3"
				( objectStatus "@baseboard_fab2_lib.baseboard_fab2(sch_1):page55_i25" )
			)
			( gate "R1C1"
				( objectStatus "@baseboard_fab2_lib.baseboard_fab2(sch_1):page55_i26" )
			)
			( gate "R3B1"
				( objectStatus "@baseboard_fab2_lib.baseboard_fab2(sch_1):page55_i27" )
			)
			( gate "R3B5"
				( objectStatus "@baseboard_fab2_lib.baseboard_fab2(sch_1):page55_i28" )
			)
			( gate "R3B3"
				( objectStatus "@baseboard_fab2_lib.baseboard_fab2(sch_1):page55_i29" )
			)
			( gate "R7P19"
				( objectStatus "@baseboard_fab2_lib.baseboard_fab2(sch_1):page55_i115" )
			)
			( gate "R3D1"
				( objectStatus "@baseboard_fab2_lib.baseboard_fab2(sch_1):page55_i116" )
			)
			( gate "R3D2"
				( objectStatus "@baseboard_fab2_lib.baseboard_fab2(sch_1):page55_i117" )
			)
			( gate "R3D3"
				( objectStatus "@baseboard_fab2_lib.baseboard_fab2(sch_1):page55_i118" )
			)
			( gate "R7P16"
				( objectStatus "@baseboard_fab2_lib.baseboard_fab2(sch_1):page55_i119" )
			)
			( gate "R7P8"
				( objectStatus "@baseboard_fab2_lib.baseboard_fab2(sch_1):page55_i123" )
			)
			( gate "R7P10"
				( objectStatus "@baseboard_fab2_lib.baseboard_fab2(sch_1):page55_i124" )
			)
			( gate "R3D19"
				( objectStatus "@baseboard_fab2_lib.baseboard_fab2(sch_1):page55_i125" )
			)
			( gate "R7P11"
				( objectStatus "@baseboard_fab2_lib.baseboard_fab2(sch_1):page55_i126" )
			)
			( gate "R7P17"
				( objectStatus "@baseboard_fab2_lib.baseboard_fab2(sch_1):page55_i140" )
			)
			( gate "XRU2"
				( objectStatus "@baseboard_fab2_lib.baseboard_fab2(sch_1):page55_i152" )
			)
			( gate "XLU2"
				( objectStatus "@baseboard_fab2_lib.baseboard_fab2(sch_1):page55_i153" )
			)
			( gate "R3D4"
				( objectStatus "@baseboard_fab2_lib.baseboard_fab2(sch_1):page55_i155" )
			)
			( gate "R7P26"
				( objectStatus "@baseboard_fab2_lib.baseboard_fab2(sch_1):page55_i156" )
			)
			( gate "R8N1"
				( objectStatus "@baseboard_fab2_lib.baseboard_fab2(sch_1):page55_i157" )
			)
			( gate "R8N4"
				( objectStatus "@baseboard_fab2_lib.baseboard_fab2(sch_1):page55_i158" )
			)
			( gate "R8N3"
				( objectStatus "@baseboard_fab2_lib.baseboard_fab2(sch_1):page55_i159" )
			)
			( gate "R8N5"
				( objectStatus "@baseboard_fab2_lib.baseboard_fab2(sch_1):page55_i160" )
			)
			( gate "R8N2"
				( objectStatus "@baseboard_fab2_lib.baseboard_fab2(sch_1):page55_i161" )
			)
			( gate "R7P25"
				( objectStatus "@baseboard_fab2_lib.baseboard_fab2(sch_1):page55_i170" )
			)
			( gate "U2D1"
				( objectStatus "@baseboard_fab2_lib.baseboard_fab2(sch_1):page55_i172" )
			)
			( gate "R6P39"
				( objectStatus "@baseboard_fab2_lib.baseboard_fab2(sch_1):page55_i181" )
			)
			( gate "U2D1"
				( objectStatus "@baseboard_fab2_lib.baseboard_fab2(sch_1):page56_i169" )
			)
			( gate "R8P3"
				( objectStatus "@baseboard_fab2_lib.baseboard_fab2(sch_1):page56_i173" )
			)
			( gate "R8R1"
				( objectStatus "@baseboard_fab2_lib.baseboard_fab2(sch_1):page56_i174" )
			)
			( gate "U2D1"
				( objectStatus "@baseboard_fab2_lib.baseboard_fab2(sch_1):page57_i172" )
			)
			( gate "U2D1"
				( objectStatus "@baseboard_fab2_lib.baseboard_fab2(sch_1):page58_i172" )
			)
			( gate "U2D1"
				( objectStatus "@baseboard_fab2_lib.baseboard_fab2(sch_1):page59_i172" )
			)
			( gate "U2D1"
				( objectStatus "@baseboard_fab2_lib.baseboard_fab2(sch_1):page60_i172" )
			)
			( gate "U2D1"
				( objectStatus "@baseboard_fab2_lib.baseboard_fab2(sch_1):page61_i172" )
			)
			( gate "U2D1"
				( objectStatus "@baseboard_fab2_lib.baseboard_fab2(sch_1):page62_i172" )
			)
			( gate "U2D1"
				( objectStatus "@baseboard_fab2_lib.baseboard_fab2(sch_1):page63_i23" )
			)
			( gate "U2D1"
				( objectStatus "@baseboard_fab2_lib.baseboard_fab2(sch_1):page64_i68" )
			)
			( gate "U2D1"
				( objectStatus "@baseboard_fab2_lib.baseboard_fab2(sch_1):page65_i68" )
			)
			( gate "U2D1"
				( objectStatus "@baseboard_fab2_lib.baseboard_fab2(sch_1):page66_i84" )
			)
			( gate "U2D1"
				( objectStatus "@baseboard_fab2_lib.baseboard_fab2(sch_1):page67_i132" )
			)
			( gate "U2D1"
				( objectStatus "@baseboard_fab2_lib.baseboard_fab2(sch_1):page68_i125" )
			)
			( gate "U2D1"
				( objectStatus "@baseboard_fab2_lib.baseboard_fab2(sch_1):page69_i1" )
			)
			( gate "U2D1"
				( objectStatus "@baseboard_fab2_lib.baseboard_fab2(sch_1):page70_i9" )
			)
			( gate "U2D1"
				( objectStatus "@baseboard_fab2_lib.baseboard_fab2(sch_1):page70_i10" )
			)
			( gate "R3D27"
				( objectStatus "@baseboard_fab2_lib.baseboard_fab2(sch_1):page71_i43" )
			)
			( gate "RT8P1"
				( objectStatus "@baseboard_fab2_lib.baseboard_fab2(sch_1):page71_i49" )
			)
			( gate "U2D1"
				( objectStatus "@baseboard_fab2_lib.baseboard_fab2(sch_1):page71_i50" )
			)
			( gate "U2D1"
				( objectStatus "@baseboard_fab2_lib.baseboard_fab2(sch_1):page71_i51" )
			)
			( gate "R3D32"
				( objectStatus "@baseboard_fab2_lib.baseboard_fab2(sch_1):page71_i53" )
			)
			( gate "C3D3"
				( objectStatus "@baseboard_fab2_lib.baseboard_fab2(sch_1):page72_i25" )
			)
			( gate "U2D1"
				( objectStatus "@baseboard_fab2_lib.baseboard_fab2(sch_1):page72_i32" )
			)
			( gate "U2D1"
				( objectStatus "@baseboard_fab2_lib.baseboard_fab2(sch_1):page72_i33" )
			)
			( gate "U2D1"
				( objectStatus "@baseboard_fab2_lib.baseboard_fab2(sch_1):page73_i107" )
			)
			( gate "U2D1"
				( objectStatus "@baseboard_fab2_lib.baseboard_fab2(sch_1):page74_i20" )
			)
			( gate "U2D1"
				( objectStatus "@baseboard_fab2_lib.baseboard_fab2(sch_1):page74_i21" )
			)
			( gate "U2D1"
				( objectStatus "@baseboard_fab2_lib.baseboard_fab2(sch_1):page74_i22" )
			)
			( gate "U2D1"
				( objectStatus "@baseboard_fab2_lib.baseboard_fab2(sch_1):page74_i23" )
			)
			( gate "U2D1"
				( objectStatus "@baseboard_fab2_lib.baseboard_fab2(sch_1):page75_i17" )
			)
			( gate "U2D1"
				( objectStatus "@baseboard_fab2_lib.baseboard_fab2(sch_1):page75_i18" )
			)
			( gate "U2D1"
				( objectStatus "@baseboard_fab2_lib.baseboard_fab2(sch_1):page75_i19" )
			)
			( gate "U2D1"
				( objectStatus "@baseboard_fab2_lib.baseboard_fab2(sch_1):page75_i20" )
			)
			( gate "C3D21"
				( objectStatus "@baseboard_fab2_lib.baseboard_fab2(sch_1):page76_i1" )
			)
			( gate "C3D5"
				( objectStatus "@baseboard_fab2_lib.baseboard_fab2(sch_1):page76_i3" )
			)
			( gate "C3D12"
				( objectStatus "@baseboard_fab2_lib.baseboard_fab2(sch_1):page76_i4" )
			)
			( gate "C3D4"
				( objectStatus "@baseboard_fab2_lib.baseboard_fab2(sch_1):page76_i5" )
			)
			( gate "C3D11"
				( objectStatus "@baseboard_fab2_lib.baseboard_fab2(sch_1):page76_i7" )
			)
			( gate "C3D13"
				( objectStatus "@baseboard_fab2_lib.baseboard_fab2(sch_1):page76_i8" )
			)
			( gate "C2D40"
				( objectStatus "@baseboard_fab2_lib.baseboard_fab2(sch_1):page76_i10" )
			)
			( gate "C3D9"
				( objectStatus "@baseboard_fab2_lib.baseboard_fab2(sch_1):page76_i15" )
			)
			( gate "C3D8"
				( objectStatus "@baseboard_fab2_lib.baseboard_fab2(sch_1):page76_i18" )
			)
			( gate "C7P4"
				( objectStatus "@baseboard_fab2_lib.baseboard_fab2(sch_1):page76_i271" )
			)
			( gate "C8P15"
				( objectStatus "@baseboard_fab2_lib.baseboard_fab2(sch_1):page76_i270" )
			)
			( gate "C7P13"
				( objectStatus "@baseboard_fab2_lib.baseboard_fab2(sch_1):page76_i269" )
			)
			( gate "C7P17"
				( objectStatus "@baseboard_fab2_lib.baseboard_fab2(sch_1):page76_i29" )
			)
			( gate "C2D8"
				( objectStatus "@baseboard_fab2_lib.baseboard_fab2(sch_1):page76_i33" )
			)
			( gate "C2D10"
				( objectStatus "@baseboard_fab2_lib.baseboard_fab2(sch_1):page76_i37" )
			)
			( gate "C2D11"
				( objectStatus "@baseboard_fab2_lib.baseboard_fab2(sch_1):page76_i42" )
			)
			( gate "C2D9"
				( objectStatus "@baseboard_fab2_lib.baseboard_fab2(sch_1):page76_i43" )
			)
			( gate "C7P8"
				( objectStatus "@baseboard_fab2_lib.baseboard_fab2(sch_1):page76_i265" )
			)
			( gate "C7P15"
				( objectStatus "@baseboard_fab2_lib.baseboard_fab2(sch_1):page76_i263" )
			)
			( gate "C7P11"
				( objectStatus "@baseboard_fab2_lib.baseboard_fab2(sch_1):page76_i262" )
			)
			( gate "C8P25"
				( objectStatus "@baseboard_fab2_lib.baseboard_fab2(sch_1):page76_i251" )
			)
			( gate "C7P18"
				( objectStatus "@baseboard_fab2_lib.baseboard_fab2(sch_1):page76_i51" )
			)
			( gate "C7P3"
				( objectStatus "@baseboard_fab2_lib.baseboard_fab2(sch_1):page76_i52" )
			)
			( gate "C8P27"
				( objectStatus "@baseboard_fab2_lib.baseboard_fab2(sch_1):page76_i250" )
			)
			( gate "C8P21"
				( objectStatus "@baseboard_fab2_lib.baseboard_fab2(sch_1):page76_i249" )
			)
			( gate "C2D12"
				( objectStatus "@baseboard_fab2_lib.baseboard_fab2(sch_1):page76_i59" )
			)
			( gate "C2D22"
				( objectStatus "@baseboard_fab2_lib.baseboard_fab2(sch_1):page76_i61" )
			)
			( gate "C2D31"
				( objectStatus "@baseboard_fab2_lib.baseboard_fab2(sch_1):page76_i63" )
			)
			( gate "C2D21"
				( objectStatus "@baseboard_fab2_lib.baseboard_fab2(sch_1):page76_i65" )
			)
			( gate "C2D27"
				( objectStatus "@baseboard_fab2_lib.baseboard_fab2(sch_1):page76_i66" )
			)
			( gate "C3D2"
				( objectStatus "@baseboard_fab2_lib.baseboard_fab2(sch_1):page76_i69" )
			)
			( gate "C2D36"
				( objectStatus "@baseboard_fab2_lib.baseboard_fab2(sch_1):page76_i70" )
			)
			( gate "C2D13"
				( objectStatus "@baseboard_fab2_lib.baseboard_fab2(sch_1):page76_i73" )
			)
			( gate "C2D19"
				( objectStatus "@baseboard_fab2_lib.baseboard_fab2(sch_1):page76_i75" )
			)
			( gate "C2D14"
				( objectStatus "@baseboard_fab2_lib.baseboard_fab2(sch_1):page76_i76" )
			)
			( gate "C2D20"
				( objectStatus "@baseboard_fab2_lib.baseboard_fab2(sch_1):page76_i79" )
			)
			( gate "C2D24"
				( objectStatus "@baseboard_fab2_lib.baseboard_fab2(sch_1):page76_i80" )
			)
			( gate "C2D25"
				( objectStatus "@baseboard_fab2_lib.baseboard_fab2(sch_1):page76_i82" )
			)
			( gate "C2D30"
				( objectStatus "@baseboard_fab2_lib.baseboard_fab2(sch_1):page76_i83" )
			)
			( gate "C2D33"
				( objectStatus "@baseboard_fab2_lib.baseboard_fab2(sch_1):page76_i85" )
			)
			( gate "C8P20"
				( objectStatus "@baseboard_fab2_lib.baseboard_fab2(sch_1):page76_i89" )
			)
			( gate "C2D32"
				( objectStatus "@baseboard_fab2_lib.baseboard_fab2(sch_1):page76_i90" )
			)
			( gate "C8P18"
				( objectStatus "@baseboard_fab2_lib.baseboard_fab2(sch_1):page76_i92" )
			)
			( gate "C8P19"
				( objectStatus "@baseboard_fab2_lib.baseboard_fab2(sch_1):page76_i103" )
			)
			( gate "U7W1"
				( objectStatus "@baseboard_fab2_lib.baseboard_fab2(sch_1):page166_i34" )
			)
			( gate "C8P12"
				( objectStatus "@baseboard_fab2_lib.baseboard_fab2(sch_1):page76_i107" )
			)
			( gate "C2D26"
				( objectStatus "@baseboard_fab2_lib.baseboard_fab2(sch_1):page76_i108" )
			)
			( gate "C2D23"
				( objectStatus "@baseboard_fab2_lib.baseboard_fab2(sch_1):page76_i112" )
			)
			( gate "C2D17"
				( objectStatus "@baseboard_fab2_lib.baseboard_fab2(sch_1):page76_i114" )
			)
			( gate "C2D2"
				( objectStatus "@baseboard_fab2_lib.baseboard_fab2(sch_1):page228_i257" )
			)
			( gate "C8P26"
				( objectStatus "@baseboard_fab2_lib.baseboard_fab2(sch_1):page76_i118" )
			)
			( gate "C2D37"
				( objectStatus "@baseboard_fab2_lib.baseboard_fab2(sch_1):page76_i119" )
			)
			( gate "C2D34"
				( objectStatus "@baseboard_fab2_lib.baseboard_fab2(sch_1):page76_i122" )
			)
			( gate "C2D1"
				( objectStatus "@baseboard_fab2_lib.baseboard_fab2(sch_1):page228_i258" )
			)
			( gate "C2D16"
				( objectStatus "@baseboard_fab2_lib.baseboard_fab2(sch_1):page76_i124" )
			)
			( gate "C8P29"
				( objectStatus "@baseboard_fab2_lib.baseboard_fab2(sch_1):page76_i125" )
			)
			( gate "C8P10"
				( objectStatus "@baseboard_fab2_lib.baseboard_fab2(sch_1):page76_i127" )
			)
			( gate "C8P16"
				( objectStatus "@baseboard_fab2_lib.baseboard_fab2(sch_1):page76_i129" )
			)
			( gate "C7W1"
				( objectStatus "@baseboard_fab2_lib.baseboard_fab2(sch_1):page166_i36" )
			)
			( gate "C8P13"
				( objectStatus "@baseboard_fab2_lib.baseboard_fab2(sch_1):page76_i132" )
			)
			( gate "C8P28"
				( objectStatus "@baseboard_fab2_lib.baseboard_fab2(sch_1):page76_i137" )
			)
			( gate "C8P11"
				( objectStatus "@baseboard_fab2_lib.baseboard_fab2(sch_1):page76_i139" )
			)
			( gate "R8D40"
				( objectStatus "@baseboard_fab2_lib.baseboard_fab2(sch_1):page196_i130" )
			)
			( gate "C2D15"
				( objectStatus "@baseboard_fab2_lib.baseboard_fab2(sch_1):page76_i159" )
			)
			( gate "C2D38"
				( objectStatus "@baseboard_fab2_lib.baseboard_fab2(sch_1):page76_i160" )
			)
			( gate "C2D35"
				( objectStatus "@baseboard_fab2_lib.baseboard_fab2(sch_1):page76_i161" )
			)
			( gate "C3D7"
				( objectStatus "@baseboard_fab2_lib.baseboard_fab2(sch_1):page76_i164" )
			)
			( gate "C2D39"
				( objectStatus "@baseboard_fab2_lib.baseboard_fab2(sch_1):page76_i165" )
			)
			( gate "C3D17"
				( objectStatus "@baseboard_fab2_lib.baseboard_fab2(sch_1):page76_i166" )
			)
			( gate "C3D18"
				( objectStatus "@baseboard_fab2_lib.baseboard_fab2(sch_1):page76_i169" )
			)
			( gate "C3D6"
				( objectStatus "@baseboard_fab2_lib.baseboard_fab2(sch_1):page76_i170" )
			)
			( gate "C3D14"
				( objectStatus "@baseboard_fab2_lib.baseboard_fab2(sch_1):page76_i171" )
			)
			( gate "C3D23"
				( objectStatus "@baseboard_fab2_lib.baseboard_fab2(sch_1):page76_i172" )
			)
			( gate "C3D15"
				( objectStatus "@baseboard_fab2_lib.baseboard_fab2(sch_1):page76_i174" )
			)
			( gate "C3D24"
				( objectStatus "@baseboard_fab2_lib.baseboard_fab2(sch_1):page76_i175" )
			)
			( gate "C3D16"
				( objectStatus "@baseboard_fab2_lib.baseboard_fab2(sch_1):page76_i176" )
			)
			( gate "C7P12"
				( objectStatus "@baseboard_fab2_lib.baseboard_fab2(sch_1):page76_i179" )
			)
			( gate "C7P14"
				( objectStatus "@baseboard_fab2_lib.baseboard_fab2(sch_1):page76_i261" )
			)
			( gate "C8P23"
				( objectStatus "@baseboard_fab2_lib.baseboard_fab2(sch_1):page76_i260" )
			)
			( gate "C8P22"
				( objectStatus "@baseboard_fab2_lib.baseboard_fab2(sch_1):page76_i264" )
			)
			( gate "C7P6"
				( objectStatus "@baseboard_fab2_lib.baseboard_fab2(sch_1):page76_i268" )
			)
			( gate "C3D10"
				( objectStatus "@baseboard_fab2_lib.baseboard_fab2(sch_1):page76_i196" )
			)
			( gate "C2D18"
				( objectStatus "@baseboard_fab2_lib.baseboard_fab2(sch_1):page76_i197" )
			)
			( gate "C2D28"
				( objectStatus "@baseboard_fab2_lib.baseboard_fab2(sch_1):page76_i198" )
			)
			( gate "C2D29"
				( objectStatus "@baseboard_fab2_lib.baseboard_fab2(sch_1):page76_i199" )
			)
			( gate "C8W3"
				( objectStatus "@baseboard_fab2_lib.baseboard_fab2(sch_1):page42_i211" )
			)
			( gate "C5U1"
				( objectStatus "@baseboard_fab2_lib.baseboard_fab2(sch_1):page217_i316" )
			)
			( gate "C2D46"
				( objectStatus "@baseboard_fab2_lib.baseboard_fab2(sch_1):page225_i264" )
			)
			( gate "C2D47"
				( objectStatus "@baseboard_fab2_lib.baseboard_fab2(sch_1):page225_i263" )
			)
			( gate "C3D25"
				( objectStatus "@baseboard_fab2_lib.baseboard_fab2(sch_1):page225_i262" )
			)
			( gate "C7P16"
				( objectStatus "@baseboard_fab2_lib.baseboard_fab2(sch_1):page76_i206" )
			)
			( gate "C3D20"
				( objectStatus "@baseboard_fab2_lib.baseboard_fab2(sch_1):page76_i207" )
			)
			( gate "C3D19"
				( objectStatus "@baseboard_fab2_lib.baseboard_fab2(sch_1):page76_i208" )
			)
			( gate "C7P19"
				( objectStatus "@baseboard_fab2_lib.baseboard_fab2(sch_1):page76_i215" )
			)
			( gate "C8P24"
				( objectStatus "@baseboard_fab2_lib.baseboard_fab2(sch_1):page76_i217" )
			)
			( gate "J1G1"
				( objectStatus "@baseboard_fab2_lib.baseboard_fab2(sch_1):page77_i43" )
			)
			( gate "J1G1"
				( objectStatus "@baseboard_fab2_lib.baseboard_fab2(sch_1):page77_i66" )
			)
			( gate "J1G1"
				( objectStatus "@baseboard_fab2_lib.baseboard_fab2(sch_1):page77_i111" )
			)
			( gate "J1G1"
				( objectStatus "@baseboard_fab2_lib.baseboard_fab2(sch_1):page77_i171" )
			)
			( gate "C1F22"
				( objectStatus "@baseboard_fab2_lib.baseboard_fab2(sch_1):page77_i181" )
			)
			( gate "C9T7"
				( objectStatus "@baseboard_fab2_lib.baseboard_fab2(sch_1):page78_i2" )
			)
			( gate "J9T1"
				( objectStatus "@baseboard_fab2_lib.baseboard_fab2(sch_1):page78_i13" )
			)
			( gate "J9T1"
				( objectStatus "@baseboard_fab2_lib.baseboard_fab2(sch_1):page78_i75" )
			)
			( gate "J9T1"
				( objectStatus "@baseboard_fab2_lib.baseboard_fab2(sch_1):page78_i120" )
			)
			( gate "J9T1"
				( objectStatus "@baseboard_fab2_lib.baseboard_fab2(sch_1):page78_i144" )
			)
			( gate "J1G2"
				( objectStatus "@baseboard_fab2_lib.baseboard_fab2(sch_1):page79_i43" )
			)
			( gate "J1G2"
				( objectStatus "@baseboard_fab2_lib.baseboard_fab2(sch_1):page79_i64" )
			)
			( gate "J1G2"
				( objectStatus "@baseboard_fab2_lib.baseboard_fab2(sch_1):page79_i111" )
			)
			( gate "J1G2"
				( objectStatus "@baseboard_fab2_lib.baseboard_fab2(sch_1):page79_i169" )
			)
			( gate "C9U7"
				( objectStatus "@baseboard_fab2_lib.baseboard_fab2(sch_1):page79_i178" )
			)
			( gate "C1G10"
				( objectStatus "@baseboard_fab2_lib.baseboard_fab2(sch_1):page80_i3" )
			)
			( gate "J9U1"
				( objectStatus "@baseboard_fab2_lib.baseboard_fab2(sch_1):page80_i24" )
			)
			( gate "J9U1"
				( objectStatus "@baseboard_fab2_lib.baseboard_fab2(sch_1):page80_i56" )
			)
			( gate "J9U1"
				( objectStatus "@baseboard_fab2_lib.baseboard_fab2(sch_1):page80_i101" )
			)
			( gate "J9U1"
				( objectStatus "@baseboard_fab2_lib.baseboard_fab2(sch_1):page80_i138" )
			)
			( gate "J1G3"
				( objectStatus "@baseboard_fab2_lib.baseboard_fab2(sch_1):page81_i67" )
			)
			( gate "J1G3"
				( objectStatus "@baseboard_fab2_lib.baseboard_fab2(sch_1):page81_i169" )
			)
			( gate "C9U10"
				( objectStatus "@baseboard_fab2_lib.baseboard_fab2(sch_1):page81_i178" )
			)
			( gate "J1G3"
				( objectStatus "@baseboard_fab2_lib.baseboard_fab2(sch_1):page81_i185" )
			)
			( gate "J1G3"
				( objectStatus "@baseboard_fab2_lib.baseboard_fab2(sch_1):page81_i186" )
			)
			( gate "J9U2"
				( objectStatus "@baseboard_fab2_lib.baseboard_fab2(sch_1):page82_i64" )
			)
			( gate "J9U2"
				( objectStatus "@baseboard_fab2_lib.baseboard_fab2(sch_1):page82_i171" )
			)
			( gate "C1G19"
				( objectStatus "@baseboard_fab2_lib.baseboard_fab2(sch_1):page82_i180" )
			)
			( gate "J9U2"
				( objectStatus "@baseboard_fab2_lib.baseboard_fab2(sch_1):page82_i187" )
			)
			( gate "J9U2"
				( objectStatus "@baseboard_fab2_lib.baseboard_fab2(sch_1):page82_i188" )
			)
			( gate "J1B1"
				( objectStatus "@baseboard_fab2_lib.baseboard_fab2(sch_1):page83_i43" )
			)
			( gate "J1B1"
				( objectStatus "@baseboard_fab2_lib.baseboard_fab2(sch_1):page83_i66" )
			)
			( gate "J1B1"
				( objectStatus "@baseboard_fab2_lib.baseboard_fab2(sch_1):page83_i111" )
			)
			( gate "J1B1"
				( objectStatus "@baseboard_fab2_lib.baseboard_fab2(sch_1):page83_i167" )
			)
			( gate "C1B9"
				( objectStatus "@baseboard_fab2_lib.baseboard_fab2(sch_1):page83_i176" )
			)
			( gate "C9M1"
				( objectStatus "@baseboard_fab2_lib.baseboard_fab2(sch_1):page84_i4" )
			)
			( gate "J9M1"
				( objectStatus "@baseboard_fab2_lib.baseboard_fab2(sch_1):page84_i14" )
			)
			( gate "J9M1"
				( objectStatus "@baseboard_fab2_lib.baseboard_fab2(sch_1):page84_i57" )
			)
			( gate "J9M1"
				( objectStatus "@baseboard_fab2_lib.baseboard_fab2(sch_1):page84_i102" )
			)
			( gate "J9M1"
				( objectStatus "@baseboard_fab2_lib.baseboard_fab2(sch_1):page84_i138" )
			)
			( gate "J1A2"
				( objectStatus "@baseboard_fab2_lib.baseboard_fab2(sch_1):page85_i43" )
			)
			( gate "J1A2"
				( objectStatus "@baseboard_fab2_lib.baseboard_fab2(sch_1):page85_i66" )
			)
			( gate "J1A2"
				( objectStatus "@baseboard_fab2_lib.baseboard_fab2(sch_1):page85_i111" )
			)
			( gate "J1A2"
				( objectStatus "@baseboard_fab2_lib.baseboard_fab2(sch_1):page85_i172" )
			)
			( gate "C9L7"
				( objectStatus "@baseboard_fab2_lib.baseboard_fab2(sch_1):page85_i181" )
			)
			( gate "J9L2"
				( objectStatus "@baseboard_fab2_lib.baseboard_fab2(sch_1):page86_i12" )
			)
			( gate "J9L2"
				( objectStatus "@baseboard_fab2_lib.baseboard_fab2(sch_1):page86_i55" )
			)
			( gate "J9L2"
				( objectStatus "@baseboard_fab2_lib.baseboard_fab2(sch_1):page86_i100" )
			)
			( gate "J9L2"
				( objectStatus "@baseboard_fab2_lib.baseboard_fab2(sch_1):page86_i138" )
			)
			( gate "C1A17"
				( objectStatus "@baseboard_fab2_lib.baseboard_fab2(sch_1):page86_i182" )
			)
			( gate "J1A1"
				( objectStatus "@baseboard_fab2_lib.baseboard_fab2(sch_1):page87_i169" )
			)
			( gate "C1A5"
				( objectStatus "@baseboard_fab2_lib.baseboard_fab2(sch_1):page87_i178" )
			)
			( gate "J1A1"
				( objectStatus "@baseboard_fab2_lib.baseboard_fab2(sch_1):page87_i185" )
			)
			( gate "J1A1"
				( objectStatus "@baseboard_fab2_lib.baseboard_fab2(sch_1):page87_i186" )
			)
			( gate "J1A1"
				( objectStatus "@baseboard_fab2_lib.baseboard_fab2(sch_1):page87_i187" )
			)
			( gate "J9L1"
				( objectStatus "@baseboard_fab2_lib.baseboard_fab2(sch_1):page88_i25" )
			)
			( gate "J9L1"
				( objectStatus "@baseboard_fab2_lib.baseboard_fab2(sch_1):page88_i87" )
			)
			( gate "J9L1"
				( objectStatus "@baseboard_fab2_lib.baseboard_fab2(sch_1):page88_i111" )
			)
			( gate "J9L1"
				( objectStatus "@baseboard_fab2_lib.baseboard_fab2(sch_1):page88_i168" )
			)
			( gate "C9L1"
				( objectStatus "@baseboard_fab2_lib.baseboard_fab2(sch_1):page88_i177" )
			)
			( gate "R4T2"
				( objectStatus "@baseboard_fab2_lib.baseboard_fab2(sch_1):page89_i1" )
			)
			( gate "R4T1"
				( objectStatus "@baseboard_fab2_lib.baseboard_fab2(sch_1):page89_i2" )
			)
			( gate "R6F4"
				( objectStatus "@baseboard_fab2_lib.baseboard_fab2(sch_1):page89_i3" )
			)
			( gate "R6F1"
				( objectStatus "@baseboard_fab2_lib.baseboard_fab2(sch_1):page89_i4" )
			)
			( gate "R6F5"
				( objectStatus "@baseboard_fab2_lib.baseboard_fab2(sch_1):page89_i5" )
			)
			( gate "R6F2"
				( objectStatus "@baseboard_fab2_lib.baseboard_fab2(sch_1):page89_i6" )
			)
			( gate "R6F3"
				( objectStatus "@baseboard_fab2_lib.baseboard_fab2(sch_1):page89_i7" )
			)
			( gate "Q1P2"
				( objectStatus "@baseboard_fab2_lib.baseboard_fab2(sch_1):page196_i129" )
			)
			( gate "R2P12"
				( objectStatus "@baseboard_fab2_lib.baseboard_fab2(sch_1):page89_i23" )
			)
			( gate "R8D29"
				( objectStatus "@baseboard_fab2_lib.baseboard_fab2(sch_1):page89_i26" )
			)
			( gate "R8D31"
				( objectStatus "@baseboard_fab2_lib.baseboard_fab2(sch_1):page89_i27" )
			)
			( gate "R8D30"
				( objectStatus "@baseboard_fab2_lib.baseboard_fab2(sch_1):page89_i34" )
			)
			( gate "Q8D1"
				( objectStatus "@baseboard_fab2_lib.baseboard_fab2(sch_1):page89_i35" )
			)
			( gate "R3D22"
				( objectStatus "@baseboard_fab2_lib.baseboard_fab2(sch_1):page90_i17" )
			)
			( gate "R3D16"
				( objectStatus "@baseboard_fab2_lib.baseboard_fab2(sch_1):page90_i24" )
			)
			( gate "R3D23"
				( objectStatus "@baseboard_fab2_lib.baseboard_fab2(sch_1):page90_i25" )
			)
			( gate "R3D26"
				( objectStatus "@baseboard_fab2_lib.baseboard_fab2(sch_1):page90_i28" )
			)
			( gate "R5D3"
				( objectStatus "@baseboard_fab2_lib.baseboard_fab2(sch_1):page90_i29" )
			)
			( gate "R6D7"
				( objectStatus "@baseboard_fab2_lib.baseboard_fab2(sch_1):page90_i31" )
			)
			( gate "R6D13"
				( objectStatus "@baseboard_fab2_lib.baseboard_fab2(sch_1):page90_i33" )
			)
			( gate "R6D15"
				( objectStatus "@baseboard_fab2_lib.baseboard_fab2(sch_1):page90_i48" )
			)
			( gate "R6D10"
				( objectStatus "@baseboard_fab2_lib.baseboard_fab2(sch_1):page90_i49" )
			)
			( gate "R6D14"
				( objectStatus "@baseboard_fab2_lib.baseboard_fab2(sch_1):page90_i52" )
			)
			( gate "R4P14"
				( objectStatus "@baseboard_fab2_lib.baseboard_fab2(sch_1):page90_i53" )
			)
			( gate "R3D24"
				( objectStatus "@baseboard_fab2_lib.baseboard_fab2(sch_1):page90_i59" )
			)
			( gate "R3D17"
				( objectStatus "@baseboard_fab2_lib.baseboard_fab2(sch_1):page90_i60" )
			)
			( gate "R3D25"
				( objectStatus "@baseboard_fab2_lib.baseboard_fab2(sch_1):page90_i66" )
			)
			( gate "R4P6"
				( objectStatus "@baseboard_fab2_lib.baseboard_fab2(sch_1):page90_i68" )
			)
			( gate "R2U30"
				( objectStatus "@baseboard_fab2_lib.baseboard_fab2(sch_1):page125_i88" )
			)
			( gate "R4P7"
				( objectStatus "@baseboard_fab2_lib.baseboard_fab2(sch_1):page90_i72" )
			)
			( gate "R7P15"
				( objectStatus "@baseboard_fab2_lib.baseboard_fab2(sch_1):page90_i74" )
			)
			( gate "R7P22"
				( objectStatus "@baseboard_fab2_lib.baseboard_fab2(sch_1):page90_i76" )
			)
			( gate "R5P2"
				( objectStatus "@baseboard_fab2_lib.baseboard_fab2(sch_1):page90_i79" )
			)
			( gate "R5P3"
				( objectStatus "@baseboard_fab2_lib.baseboard_fab2(sch_1):page90_i80" )
			)
			( gate "R6D5"
				( objectStatus "@baseboard_fab2_lib.baseboard_fab2(sch_1):page90_i81" )
			)
			( gate "R8P1"
				( objectStatus "@baseboard_fab2_lib.baseboard_fab2(sch_1):page90_i85" )
			)
			( gate "R8P2"
				( objectStatus "@baseboard_fab2_lib.baseboard_fab2(sch_1):page90_i86" )
			)
			( gate "R3D9"
				( objectStatus "@baseboard_fab2_lib.baseboard_fab2(sch_1):page90_i88" )
			)
			( gate "J8B1"
				( objectStatus "@baseboard_fab2_lib.baseboard_fab2(sch_1):page91_i1" )
			)
			( gate "R8B8"
				( objectStatus "@baseboard_fab2_lib.baseboard_fab2(sch_1):page91_i14" )
			)
			( gate "R8B10"
				( objectStatus "@baseboard_fab2_lib.baseboard_fab2(sch_1):page91_i16" )
			)
			( gate "R8B16"
				( objectStatus "@baseboard_fab2_lib.baseboard_fab2(sch_1):page91_i17" )
			)
			( gate "R8B17"
				( objectStatus "@baseboard_fab2_lib.baseboard_fab2(sch_1):page91_i18" )
			)
			( gate "R8B18"
				( objectStatus "@baseboard_fab2_lib.baseboard_fab2(sch_1):page91_i20" )
			)
			( gate "R8B19"
				( objectStatus "@baseboard_fab2_lib.baseboard_fab2(sch_1):page91_i21" )
			)
			( gate "R8B5"
				( objectStatus "@baseboard_fab2_lib.baseboard_fab2(sch_1):page91_i22" )
			)
			( gate "R8B3"
				( objectStatus "@baseboard_fab2_lib.baseboard_fab2(sch_1):page91_i24" )
			)
			( gate "R8B13"
				( objectStatus "@baseboard_fab2_lib.baseboard_fab2(sch_1):page91_i34" )
			)
			( gate "R8B11"
				( objectStatus "@baseboard_fab2_lib.baseboard_fab2(sch_1):page91_i35" )
			)
			( gate "R8B7"
				( objectStatus "@baseboard_fab2_lib.baseboard_fab2(sch_1):page91_i36" )
			)
			( gate "R8B6"
				( objectStatus "@baseboard_fab2_lib.baseboard_fab2(sch_1):page91_i37" )
			)
			( gate "U3P2"
				( objectStatus "@baseboard_fab2_lib.baseboard_fab2(sch_1):page92_i1" )
			)
			( gate "R3P41"
				( objectStatus "@baseboard_fab2_lib.baseboard_fab2(sch_1):page92_i9" )
			)
			( gate "R3P46"
				( objectStatus "@baseboard_fab2_lib.baseboard_fab2(sch_1):page92_i12" )
			)
			( gate "R3P43"
				( objectStatus "@baseboard_fab2_lib.baseboard_fab2(sch_1):page92_i13" )
			)
			( gate "R3P42"
				( objectStatus "@baseboard_fab2_lib.baseboard_fab2(sch_1):page92_i14" )
			)
			( gate "R7E2"
				( objectStatus "@baseboard_fab2_lib.baseboard_fab2(sch_1):page92_i19" )
			)
			( gate "R7D34"
				( objectStatus "@baseboard_fab2_lib.baseboard_fab2(sch_1):page92_i24" )
			)
			( gate "R7D31"
				( objectStatus "@baseboard_fab2_lib.baseboard_fab2(sch_1):page92_i29" )
			)
			( gate "R7D29"
				( objectStatus "@baseboard_fab2_lib.baseboard_fab2(sch_1):page92_i30" )
			)
			( gate "U7D2"
				( objectStatus "@baseboard_fab2_lib.baseboard_fab2(sch_1):page92_i32" )
			)
			( gate "C3P49"
				( objectStatus "@baseboard_fab2_lib.baseboard_fab2(sch_1):page92_i37" )
			)
			( gate "R3P49"
				( objectStatus "@baseboard_fab2_lib.baseboard_fab2(sch_1):page92_i38" )
			)
			( gate "R1W39"
				( objectStatus "@baseboard_fab2_lib.baseboard_fab2(sch_1):page176_i175" )
			)
			( gate "R3R1"
				( objectStatus "@baseboard_fab2_lib.baseboard_fab2(sch_1):page92_i46" )
			)
			( gate "R7D32"
				( objectStatus "@baseboard_fab2_lib.baseboard_fab2(sch_1):page92_i48" )
			)
			( gate "R2T36"
				( objectStatus "@baseboard_fab2_lib.baseboard_fab2(sch_1):page93_i148" )
			)
			( gate "C7D5"
				( objectStatus "@baseboard_fab2_lib.baseboard_fab2(sch_1):page92_i52" )
			)
			( gate "R7D26"
				( objectStatus "@baseboard_fab2_lib.baseboard_fab2(sch_1):page92_i54" )
			)
			( gate "R3R3"
				( objectStatus "@baseboard_fab2_lib.baseboard_fab2(sch_1):page92_i61" )
			)
			( gate "R6D9"
				( objectStatus "@baseboard_fab2_lib.baseboard_fab2(sch_1):page92_i64" )
			)
			( gate "R7P27"
				( objectStatus "@baseboard_fab2_lib.baseboard_fab2(sch_1):page92_i65" )
			)
			( gate "R7D28"
				( objectStatus "@baseboard_fab2_lib.baseboard_fab2(sch_1):page92_i67" )
			)
			( gate "R7D27"
				( objectStatus "@baseboard_fab2_lib.baseboard_fab2(sch_1):page92_i68" )
			)
			( gate "R7D25"
				( objectStatus "@baseboard_fab2_lib.baseboard_fab2(sch_1):page92_i70" )
			)
			( gate "R3R2"
				( objectStatus "@baseboard_fab2_lib.baseboard_fab2(sch_1):page92_i75" )
			)
			( gate "C7D4"
				( objectStatus "@baseboard_fab2_lib.baseboard_fab2(sch_1):page92_i79" )
			)
			( gate "C3P50"
				( objectStatus "@baseboard_fab2_lib.baseboard_fab2(sch_1):page92_i84" )
			)
			( gate "R2T44"
				( objectStatus "@baseboard_fab2_lib.baseboard_fab2(sch_1):page92_i92" )
			)
			( gate "R2T40"
				( objectStatus "@baseboard_fab2_lib.baseboard_fab2(sch_1):page92_i93" )
			)
			( gate "R2T37"
				( objectStatus "@baseboard_fab2_lib.baseboard_fab2(sch_1):page92_i94" )
			)
			( gate "R2T43"
				( objectStatus "@baseboard_fab2_lib.baseboard_fab2(sch_1):page92_i96" )
			)
			( gate "R3P59"
				( objectStatus "@baseboard_fab2_lib.baseboard_fab2(sch_1):page92_i97" )
			)
			( gate "R3P58"
				( objectStatus "@baseboard_fab2_lib.baseboard_fab2(sch_1):page92_i98" )
			)
			( gate "R7P18"
				( objectStatus "@baseboard_fab2_lib.baseboard_fab2(sch_1):page92_i100" )
			)
			( gate "R4R2"
				( objectStatus "@baseboard_fab2_lib.baseboard_fab2(sch_1):page92_i101" )
			)
			( gate "R2T27"
				( objectStatus "@baseboard_fab2_lib.baseboard_fab2(sch_1):page93_i13" )
			)
			( gate "R2T32"
				( objectStatus "@baseboard_fab2_lib.baseboard_fab2(sch_1):page93_i15" )
			)
			( gate "R2T20"
				( objectStatus "@baseboard_fab2_lib.baseboard_fab2(sch_1):page93_i16" )
			)
			( gate "R2T17"
				( objectStatus "@baseboard_fab2_lib.baseboard_fab2(sch_1):page93_i23" )
			)
			( gate "U2T4"
				( objectStatus "@baseboard_fab2_lib.baseboard_fab2(sch_1):page93_i30" )
			)
			( gate "R2T38"
				( objectStatus "@baseboard_fab2_lib.baseboard_fab2(sch_1):page93_i39" )
			)
			( gate "R2T33"
				( objectStatus "@baseboard_fab2_lib.baseboard_fab2(sch_1):page93_i40" )
			)
			( gate "R2T30"
				( objectStatus "@baseboard_fab2_lib.baseboard_fab2(sch_1):page93_i42" )
			)
			( gate "R7D24"
				( objectStatus "@baseboard_fab2_lib.baseboard_fab2(sch_1):page93_i62" )
			)
			( gate "R2T19"
				( objectStatus "@baseboard_fab2_lib.baseboard_fab2(sch_1):page93_i63" )
			)
			( gate "R2T16"
				( objectStatus "@baseboard_fab2_lib.baseboard_fab2(sch_1):page93_i67" )
			)
			( gate "R2T31"
				( objectStatus "@baseboard_fab2_lib.baseboard_fab2(sch_1):page93_i68" )
			)
			( gate "C2T33"
				( objectStatus "@baseboard_fab2_lib.baseboard_fab2(sch_1):page93_i72" )
			)
			( gate "R4R3"
				( objectStatus "@baseboard_fab2_lib.baseboard_fab2(sch_1):page93_i79" )
			)
			( gate "R2T26"
				( objectStatus "@baseboard_fab2_lib.baseboard_fab2(sch_1):page93_i87" )
			)
			( gate "R2T57"
				( objectStatus "@baseboard_fab2_lib.baseboard_fab2(sch_1):page93_i88" )
			)
			( gate "R2T61"
				( objectStatus "@baseboard_fab2_lib.baseboard_fab2(sch_1):page93_i89" )
			)
			( gate "R2T62"
				( objectStatus "@baseboard_fab2_lib.baseboard_fab2(sch_1):page93_i93" )
			)
			( gate "R2T58"
				( objectStatus "@baseboard_fab2_lib.baseboard_fab2(sch_1):page93_i94" )
			)
			( gate "C2T32"
				( objectStatus "@baseboard_fab2_lib.baseboard_fab2(sch_1):page93_i95" )
			)
			( gate "R1U43"
				( objectStatus "@baseboard_fab2_lib.baseboard_fab2(sch_1):page152_i106" )
			)
			( gate "R2T39"
				( objectStatus "@baseboard_fab2_lib.baseboard_fab2(sch_1):page93_i98" )
			)
			( gate "R2T68"
				( objectStatus "@baseboard_fab2_lib.baseboard_fab2(sch_1):page93_i102" )
			)
			( gate "R2T60"
				( objectStatus "@baseboard_fab2_lib.baseboard_fab2(sch_1):page93_i103" )
			)
			( gate "R7P28"
				( objectStatus "@baseboard_fab2_lib.baseboard_fab2(sch_1):page93_i106" )
			)
			( gate "R2T59"
				( objectStatus "@baseboard_fab2_lib.baseboard_fab2(sch_1):page93_i107" )
			)
			( gate "R2T69"
				( objectStatus "@baseboard_fab2_lib.baseboard_fab2(sch_1):page93_i108" )
			)
			( gate "R2T71"
				( objectStatus "@baseboard_fab2_lib.baseboard_fab2(sch_1):page93_i109" )
			)
			( gate "R7D43"
				( objectStatus "@baseboard_fab2_lib.baseboard_fab2(sch_1):page93_i110" )
			)
			( gate "R2T65"
				( objectStatus "@baseboard_fab2_lib.baseboard_fab2(sch_1):page93_i111" )
			)
			( gate "R2T66"
				( objectStatus "@baseboard_fab2_lib.baseboard_fab2(sch_1):page93_i112" )
			)
			( gate "R2T67"
				( objectStatus "@baseboard_fab2_lib.baseboard_fab2(sch_1):page93_i113" )
			)
			( gate "R7D41"
				( objectStatus "@baseboard_fab2_lib.baseboard_fab2(sch_1):page93_i114" )
			)
			( gate "R8F38"
				( objectStatus "@baseboard_fab2_lib.baseboard_fab2(sch_1):page93_i119" )
			)
			( gate "R2T64"
				( objectStatus "@baseboard_fab2_lib.baseboard_fab2(sch_1):page93_i121" )
			)
			( gate "R1T36"
				( objectStatus "@baseboard_fab2_lib.baseboard_fab2(sch_1):page93_i122" )
			)
			( gate "R1T37"
				( objectStatus "@baseboard_fab2_lib.baseboard_fab2(sch_1):page93_i123" )
			)
			( gate "R2T50"
				( objectStatus "@baseboard_fab2_lib.baseboard_fab2(sch_1):page93_i127" )
			)
			( gate "R8F37"
				( objectStatus "@baseboard_fab2_lib.baseboard_fab2(sch_1):page93_i131" )
			)
			( gate "R2T63"
				( objectStatus "@baseboard_fab2_lib.baseboard_fab2(sch_1):page93_i133" )
			)
			( gate "R1T35"
				( objectStatus "@baseboard_fab2_lib.baseboard_fab2(sch_1):page93_i135" )
			)
			( gate "R1T38"
				( objectStatus "@baseboard_fab2_lib.baseboard_fab2(sch_1):page93_i137" )
			)
			( gate "R2T72"
				( objectStatus "@baseboard_fab2_lib.baseboard_fab2(sch_1):page93_i143" )
			)
			( gate "R2T73"
				( objectStatus "@baseboard_fab2_lib.baseboard_fab2(sch_1):page93_i144" )
			)
			( gate "Q3U1"
				( objectStatus "@baseboard_fab2_lib.baseboard_fab2(sch_1):page94_i49" )
			)
			( gate "R7G7"
				( objectStatus "@baseboard_fab2_lib.baseboard_fab2(sch_1):page94_i51" )
			)
			( gate "Q7E1"
				( objectStatus "@baseboard_fab2_lib.baseboard_fab2(sch_1):page94_i60" )
			)
			( gate "Q7E1"
				( objectStatus "@baseboard_fab2_lib.baseboard_fab2(sch_1):page94_i64" )
			)
			( gate "R3R4"
				( objectStatus "@baseboard_fab2_lib.baseboard_fab2(sch_1):page94_i66" )
			)
			( gate "Q7E2"
				( objectStatus "@baseboard_fab2_lib.baseboard_fab2(sch_1):page94_i69" )
			)
			( gate "Q7E2"
				( objectStatus "@baseboard_fab2_lib.baseboard_fab2(sch_1):page94_i75" )
			)
			( gate "Q4B1"
				( objectStatus "@baseboard_fab2_lib.baseboard_fab2(sch_1):page94_i77" )
			)
			( gate "R3R10"
				( objectStatus "@baseboard_fab2_lib.baseboard_fab2(sch_1):page94_i79" )
			)
			( gate "R6M4"
				( objectStatus "@baseboard_fab2_lib.baseboard_fab2(sch_1):page94_i82" )
			)
			( gate "Q4B1"
				( objectStatus "@baseboard_fab2_lib.baseboard_fab2(sch_1):page94_i84" )
			)
			( gate "Q3U1"
				( objectStatus "@baseboard_fab2_lib.baseboard_fab2(sch_1):page94_i89" )
			)
			( gate "R4U1"
				( objectStatus "@baseboard_fab2_lib.baseboard_fab2(sch_1):page94_i91" )
			)
			( gate "R4U3"
				( objectStatus "@baseboard_fab2_lib.baseboard_fab2(sch_1):page94_i94" )
			)
			( gate "Q4U1"
				( objectStatus "@baseboard_fab2_lib.baseboard_fab2(sch_1):page94_i98" )
			)
			( gate "R4U2"
				( objectStatus "@baseboard_fab2_lib.baseboard_fab2(sch_1):page94_i100" )
			)
			( gate "Q4U1"
				( objectStatus "@baseboard_fab2_lib.baseboard_fab2(sch_1):page94_i102" )
			)
			( gate "R4U4"
				( objectStatus "@baseboard_fab2_lib.baseboard_fab2(sch_1):page94_i104" )
			)
			( gate "Q2U1"
				( objectStatus "@baseboard_fab2_lib.baseboard_fab2(sch_1):page95_i28" )
			)
			( gate "Q4B2"
				( objectStatus "@baseboard_fab2_lib.baseboard_fab2(sch_1):page95_i32" )
			)
			( gate "Q4B2"
				( objectStatus "@baseboard_fab2_lib.baseboard_fab2(sch_1):page95_i33" )
			)
			( gate "Q7E3"
				( objectStatus "@baseboard_fab2_lib.baseboard_fab2(sch_1):page95_i51" )
			)
			( gate "Q7E3"
				( objectStatus "@baseboard_fab2_lib.baseboard_fab2(sch_1):page95_i52" )
			)
			( gate "Q7E5"
				( objectStatus "@baseboard_fab2_lib.baseboard_fab2(sch_1):page95_i59" )
			)
			( gate "R7E10"
				( objectStatus "@baseboard_fab2_lib.baseboard_fab2(sch_1):page95_i62" )
			)
			( gate "Q7E6"
				( objectStatus "@baseboard_fab2_lib.baseboard_fab2(sch_1):page95_i69" )
			)
			( gate "R7E11"
				( objectStatus "@baseboard_fab2_lib.baseboard_fab2(sch_1):page95_i72" )
			)
			( gate "C7E3"
				( objectStatus "@baseboard_fab2_lib.baseboard_fab2(sch_1):page95_i92" )
			)
			( gate "Q8D2"
				( objectStatus "@baseboard_fab2_lib.baseboard_fab2(sch_1):page134_i15" )
			)
			( gate "R7E7"
				( objectStatus "@baseboard_fab2_lib.baseboard_fab2(sch_1):page95_i106" )
			)
			( gate "R7E9"
				( objectStatus "@baseboard_fab2_lib.baseboard_fab2(sch_1):page95_i108" )
			)
			( gate "Q7E5"
				( objectStatus "@baseboard_fab2_lib.baseboard_fab2(sch_1):page95_i111" )
			)
			( gate "Q7E6"
				( objectStatus "@baseboard_fab2_lib.baseboard_fab2(sch_1):page95_i112" )
			)
			( gate "Q2U1"
				( objectStatus "@baseboard_fab2_lib.baseboard_fab2(sch_1):page95_i113" )
			)
			( gate "C7E4"
				( objectStatus "@baseboard_fab2_lib.baseboard_fab2(sch_1):page95_i115" )
			)
			( gate "U7E2"
				( objectStatus "@baseboard_fab2_lib.baseboard_fab2(sch_1):page95_i117" )
			)
			( gate "U7E3"
				( objectStatus "@baseboard_fab2_lib.baseboard_fab2(sch_1):page95_i118" )
			)
			( gate "R25W93"
				( objectStatus "@baseboard_fab2_lib.baseboard_fab2(sch_1):page149_i90" )
			)
			( gate "R6D12"
				( objectStatus "@baseboard_fab2_lib.baseboard_fab2(sch_1):page96_i2" )
			)
			( gate "R6D8"
				( objectStatus "@baseboard_fab2_lib.baseboard_fab2(sch_1):page96_i3" )
			)
			( gate "R3P29"
				( objectStatus "@baseboard_fab2_lib.baseboard_fab2(sch_1):page96_i5" )
			)
			( gate "R3P38"
				( objectStatus "@baseboard_fab2_lib.baseboard_fab2(sch_1):page96_i7" )
			)
			( gate "R3D20"
				( objectStatus "@baseboard_fab2_lib.baseboard_fab2(sch_1):page96_i25" )
			)
			( gate "R3D15"
				( objectStatus "@baseboard_fab2_lib.baseboard_fab2(sch_1):page96_i26" )
			)
			( gate "R7M9"
				( objectStatus "@baseboard_fab2_lib.baseboard_fab2(sch_1):page96_i28" )
			)
			( gate "R3D21"
				( objectStatus "@baseboard_fab2_lib.baseboard_fab2(sch_1):page96_i30" )
			)
			( gate "R3P36"
				( objectStatus "@baseboard_fab2_lib.baseboard_fab2(sch_1):page96_i36" )
			)
			( gate "U3P1"
				( objectStatus "@baseboard_fab2_lib.baseboard_fab2(sch_1):page96_i42" )
			)
			( gate "U4C2"
				( objectStatus "@baseboard_fab2_lib.baseboard_fab2(sch_1):page96_i46" )
			)
			( gate "R4C8"
				( objectStatus "@baseboard_fab2_lib.baseboard_fab2(sch_1):page96_i55" )
			)
			( gate "R4C9"
				( objectStatus "@baseboard_fab2_lib.baseboard_fab2(sch_1):page96_i69" )
			)
			( gate "R3P32"
				( objectStatus "@baseboard_fab2_lib.baseboard_fab2(sch_1):page96_i71" )
			)
			( gate "C3P42"
				( objectStatus "@baseboard_fab2_lib.baseboard_fab2(sch_1):page96_i73" )
			)
			( gate "C4C3"
				( objectStatus "@baseboard_fab2_lib.baseboard_fab2(sch_1):page96_i75" )
			)
			( gate "R3D18"
				( objectStatus "@baseboard_fab2_lib.baseboard_fab2(sch_1):page97_i33" )
			)
			( gate "R4R4"
				( objectStatus "@baseboard_fab2_lib.baseboard_fab2(sch_1):page97_i42" )
			)
			( gate "R7P20"
				( objectStatus "@baseboard_fab2_lib.baseboard_fab2(sch_1):page97_i44" )
			)
			( gate "R4P21"
				( objectStatus "@baseboard_fab2_lib.baseboard_fab2(sch_1):page97_i72" )
			)
			( gate "R4C10"
				( objectStatus "@baseboard_fab2_lib.baseboard_fab2(sch_1):page97_i76" )
			)
			( gate "R4P5"
				( objectStatus "@baseboard_fab2_lib.baseboard_fab2(sch_1):page97_i80" )
			)
			( gate "R7P13"
				( objectStatus "@baseboard_fab2_lib.baseboard_fab2(sch_1):page97_i81" )
			)
			( gate "R4F5"
				( objectStatus "@baseboard_fab2_lib.baseboard_fab2(sch_1):page98_i4" )
			)
			( gate "R4F3"
				( objectStatus "@baseboard_fab2_lib.baseboard_fab2(sch_1):page98_i5" )
			)
			( gate "C4F9"
				( objectStatus "@baseboard_fab2_lib.baseboard_fab2(sch_1):page98_i7" )
			)
			( gate "R6M1"
				( objectStatus "@baseboard_fab2_lib.baseboard_fab2(sch_1):page98_i9" )
			)
			( gate "R6L16"
				( objectStatus "@baseboard_fab2_lib.baseboard_fab2(sch_1):page98_i12" )
			)
			( gate "R6M2"
				( objectStatus "@baseboard_fab2_lib.baseboard_fab2(sch_1):page98_i14" )
			)
			( gate "C6M2"
				( objectStatus "@baseboard_fab2_lib.baseboard_fab2(sch_1):page98_i33" )
			)
			( gate "R4F4"
				( objectStatus "@baseboard_fab2_lib.baseboard_fab2(sch_1):page98_i36" )
			)
			( gate "R4G2"
				( objectStatus "@baseboard_fab2_lib.baseboard_fab2(sch_1):page98_i38" )
			)
			( gate "R4G3"
				( objectStatus "@baseboard_fab2_lib.baseboard_fab2(sch_1):page98_i40" )
			)
			( gate "R4G1"
				( objectStatus "@baseboard_fab2_lib.baseboard_fab2(sch_1):page98_i42" )
			)
			( gate "C4G1"
				( objectStatus "@baseboard_fab2_lib.baseboard_fab2(sch_1):page98_i43" )
			)
			( gate "R4G21"
				( objectStatus "@baseboard_fab2_lib.baseboard_fab2(sch_1):page98_i46" )
			)
			( gate "R4G22"
				( objectStatus "@baseboard_fab2_lib.baseboard_fab2(sch_1):page98_i48" )
			)
			( gate "R4G20"
				( objectStatus "@baseboard_fab2_lib.baseboard_fab2(sch_1):page98_i50" )
			)
			( gate "C4G17"
				( objectStatus "@baseboard_fab2_lib.baseboard_fab2(sch_1):page98_i51" )
			)
			( gate "R6L13"
				( objectStatus "@baseboard_fab2_lib.baseboard_fab2(sch_1):page98_i54" )
			)
			( gate "R6L12"
				( objectStatus "@baseboard_fab2_lib.baseboard_fab2(sch_1):page98_i56" )
			)
			( gate "R6L14"
				( objectStatus "@baseboard_fab2_lib.baseboard_fab2(sch_1):page98_i58" )
			)
			( gate "C6L7"
				( objectStatus "@baseboard_fab2_lib.baseboard_fab2(sch_1):page98_i59" )
			)
			( gate "R6L2"
				( objectStatus "@baseboard_fab2_lib.baseboard_fab2(sch_1):page98_i62" )
			)
			( gate "R6L1"
				( objectStatus "@baseboard_fab2_lib.baseboard_fab2(sch_1):page98_i64" )
			)
			( gate "R6L3"
				( objectStatus "@baseboard_fab2_lib.baseboard_fab2(sch_1):page98_i66" )
			)
			( gate "C6L2"
				( objectStatus "@baseboard_fab2_lib.baseboard_fab2(sch_1):page98_i67" )
			)
			( gate "C6F2"
				( objectStatus "@baseboard_fab2_lib.baseboard_fab2(sch_1):page99_i2" )
			)
			( gate "C6F3"
				( objectStatus "@baseboard_fab2_lib.baseboard_fab2(sch_1):page99_i7" )
			)
			( gate "R4T9"
				( objectStatus "@baseboard_fab2_lib.baseboard_fab2(sch_1):page99_i9" )
			)
			( gate "R4T10"
				( objectStatus "@baseboard_fab2_lib.baseboard_fab2(sch_1):page99_i10" )
			)
			( gate "R4T8"
				( objectStatus "@baseboard_fab2_lib.baseboard_fab2(sch_1):page99_i11" )
			)
			( gate "R4T7"
				( objectStatus "@baseboard_fab2_lib.baseboard_fab2(sch_1):page99_i13" )
			)
			( gate "U6F1"
				( objectStatus "@baseboard_fab2_lib.baseboard_fab2(sch_1):page99_i15" )
			)
			( gate "R4T6"
				( objectStatus "@baseboard_fab2_lib.baseboard_fab2(sch_1):page99_i17" )
			)
			( gate "R4T5"
				( objectStatus "@baseboard_fab2_lib.baseboard_fab2(sch_1):page99_i19" )
			)
			( gate "R4T4"
				( objectStatus "@baseboard_fab2_lib.baseboard_fab2(sch_1):page99_i20" )
			)
			( gate "C7E1"
				( objectStatus "@baseboard_fab2_lib.baseboard_fab2(sch_1):page99_i23" )
			)
			( gate "C4G22"
				( objectStatus "@baseboard_fab2_lib.baseboard_fab2(sch_1):page99_i27" )
			)
			( gate "C7E2"
				( objectStatus "@baseboard_fab2_lib.baseboard_fab2(sch_1):page99_i32" )
			)
			( gate "R3R9"
				( objectStatus "@baseboard_fab2_lib.baseboard_fab2(sch_1):page99_i34" )
			)
			( gate "R3R8"
				( objectStatus "@baseboard_fab2_lib.baseboard_fab2(sch_1):page99_i35" )
			)
			( gate "C4G25"
				( objectStatus "@baseboard_fab2_lib.baseboard_fab2(sch_1):page99_i41" )
			)
			( gate "R6U13"
				( objectStatus "@baseboard_fab2_lib.baseboard_fab2(sch_1):page99_i42" )
			)
			( gate "C8U11"
				( objectStatus "@baseboard_fab2_lib.baseboard_fab2(sch_1):page225_i307" )
			)
			( gate "C3B4"
				( objectStatus "@baseboard_fab2_lib.baseboard_fab2(sch_1):page99_i47" )
			)
			( gate "C3B5"
				( objectStatus "@baseboard_fab2_lib.baseboard_fab2(sch_1):page99_i53" )
			)
			( gate "R7M5"
				( objectStatus "@baseboard_fab2_lib.baseboard_fab2(sch_1):page99_i55" )
			)
			( gate "R7M4"
				( objectStatus "@baseboard_fab2_lib.baseboard_fab2(sch_1):page99_i56" )
			)
			( gate "U7E1"
				( objectStatus "@baseboard_fab2_lib.baseboard_fab2(sch_1):page99_i61" )
			)
			( gate "U4G1"
				( objectStatus "@baseboard_fab2_lib.baseboard_fab2(sch_1):page99_i63" )
			)
			( gate "R3R13"
				( objectStatus "@baseboard_fab2_lib.baseboard_fab2(sch_1):page99_i65" )
			)
			( gate "R3P60"
				( objectStatus "@baseboard_fab2_lib.baseboard_fab2(sch_1):page99_i67" )
			)
			( gate "R6T1"
				( objectStatus "@baseboard_fab2_lib.baseboard_fab2(sch_1):page99_i70" )
			)
			( gate "R6T2"
				( objectStatus "@baseboard_fab2_lib.baseboard_fab2(sch_1):page99_i72" )
			)
			( gate "U3B1"
				( objectStatus "@baseboard_fab2_lib.baseboard_fab2(sch_1):page99_i75" )
			)
			( gate "R7M7"
				( objectStatus "@baseboard_fab2_lib.baseboard_fab2(sch_1):page99_i77" )
			)
			( gate "R7M2"
				( objectStatus "@baseboard_fab2_lib.baseboard_fab2(sch_1):page99_i79" )
			)
			( gate "R4T3"
				( objectStatus "@baseboard_fab2_lib.baseboard_fab2(sch_1):page99_i83" )
			)
			( gate "R3R7"
				( objectStatus "@baseboard_fab2_lib.baseboard_fab2(sch_1):page99_i88" )
			)
			( gate "R6T3"
				( objectStatus "@baseboard_fab2_lib.baseboard_fab2(sch_1):page99_i92" )
			)
			( gate "R7M3"
				( objectStatus "@baseboard_fab2_lib.baseboard_fab2(sch_1):page99_i98" )
			)
			( gate "R3R12"
				( objectStatus "@baseboard_fab2_lib.baseboard_fab2(sch_1):page99_i101" )
			)
			( gate "R3R5"
				( objectStatus "@baseboard_fab2_lib.baseboard_fab2(sch_1):page99_i103" )
			)
			( gate "R6U18"
				( objectStatus "@baseboard_fab2_lib.baseboard_fab2(sch_1):page99_i104" )
			)
			( gate "R6U17"
				( objectStatus "@baseboard_fab2_lib.baseboard_fab2(sch_1):page99_i106" )
			)
			( gate "R7M6"
				( objectStatus "@baseboard_fab2_lib.baseboard_fab2(sch_1):page99_i107" )
			)
			( gate "R7M1"
				( objectStatus "@baseboard_fab2_lib.baseboard_fab2(sch_1):page99_i109" )
			)
			( gate "R3R14"
				( objectStatus "@baseboard_fab2_lib.baseboard_fab2(sch_1):page99_i110" )
			)
			( gate "R6T4"
				( objectStatus "@baseboard_fab2_lib.baseboard_fab2(sch_1):page99_i111" )
			)
			( gate "R7M8"
				( objectStatus "@baseboard_fab2_lib.baseboard_fab2(sch_1):page99_i112" )
			)
			( gate "R1F6"
				( objectStatus "@baseboard_fab2_lib.baseboard_fab2(sch_1):page100_i2" )
			)
			( gate "R9L11"
				( objectStatus "@baseboard_fab2_lib.baseboard_fab2(sch_1):page100_i4" )
			)
			( gate "R1F5"
				( objectStatus "@baseboard_fab2_lib.baseboard_fab2(sch_1):page100_i6" )
			)
			( gate "R1F4"
				( objectStatus "@baseboard_fab2_lib.baseboard_fab2(sch_1):page100_i7" )
			)
			( gate "C1F19"
				( objectStatus "@baseboard_fab2_lib.baseboard_fab2(sch_1):page100_i8" )
			)
			( gate "R9M1"
				( objectStatus "@baseboard_fab2_lib.baseboard_fab2(sch_1):page100_i11" )
			)
			( gate "R9M2"
				( objectStatus "@baseboard_fab2_lib.baseboard_fab2(sch_1):page100_i13" )
			)
			( gate "C9M2"
				( objectStatus "@baseboard_fab2_lib.baseboard_fab2(sch_1):page100_i15" )
			)
			( gate "R1G2"
				( objectStatus "@baseboard_fab2_lib.baseboard_fab2(sch_1):page100_i19" )
			)
			( gate "R1G3"
				( objectStatus "@baseboard_fab2_lib.baseboard_fab2(sch_1):page100_i20" )
			)
			( gate "R9L7"
				( objectStatus "@baseboard_fab2_lib.baseboard_fab2(sch_1):page100_i22" )
			)
			( gate "R9L6"
				( objectStatus "@baseboard_fab2_lib.baseboard_fab2(sch_1):page100_i24" )
			)
			( gate "R1G1"
				( objectStatus "@baseboard_fab2_lib.baseboard_fab2(sch_1):page100_i25" )
			)
			( gate "C1G8"
				( objectStatus "@baseboard_fab2_lib.baseboard_fab2(sch_1):page100_i26" )
			)
			( gate "R9L8"
				( objectStatus "@baseboard_fab2_lib.baseboard_fab2(sch_1):page100_i29" )
			)
			( gate "C9L8"
				( objectStatus "@baseboard_fab2_lib.baseboard_fab2(sch_1):page100_i30" )
			)
			( gate "R1G15"
				( objectStatus "@baseboard_fab2_lib.baseboard_fab2(sch_1):page100_i35" )
			)
			( gate "R1G17"
				( objectStatus "@baseboard_fab2_lib.baseboard_fab2(sch_1):page100_i36" )
			)
			( gate "R9L2"
				( objectStatus "@baseboard_fab2_lib.baseboard_fab2(sch_1):page100_i38" )
			)
			( gate "R9L1"
				( objectStatus "@baseboard_fab2_lib.baseboard_fab2(sch_1):page100_i40" )
			)
			( gate "R1G14"
				( objectStatus "@baseboard_fab2_lib.baseboard_fab2(sch_1):page100_i41" )
			)
			( gate "C1G18"
				( objectStatus "@baseboard_fab2_lib.baseboard_fab2(sch_1):page100_i42" )
			)
			( gate "R9L3"
				( objectStatus "@baseboard_fab2_lib.baseboard_fab2(sch_1):page100_i45" )
			)
			( gate "C9L3"
				( objectStatus "@baseboard_fab2_lib.baseboard_fab2(sch_1):page100_i46" )
			)
			( gate "R8F29"
				( objectStatus "@baseboard_fab2_lib.baseboard_fab2(sch_1):page101_i20" )
			)
			( gate "R8F25"
				( objectStatus "@baseboard_fab2_lib.baseboard_fab2(sch_1):page101_i28" )
			)
			( gate "EU8F2"
				( objectStatus "@baseboard_fab2_lib.baseboard_fab2(sch_1):page101_i34" )
			)
			( gate "R2T25"
				( objectStatus "@baseboard_fab2_lib.baseboard_fab2(sch_1):page101_i48" )
			)
			( gate "Y8F1"
				( objectStatus "@baseboard_fab2_lib.baseboard_fab2(sch_1):page101_i52" )
			)
			( gate "L1A1"
				( objectStatus "@baseboard_fab2_lib.baseboard_fab2(sch_1):page227_i153" )
			)
			( gate "C2T31"
				( objectStatus "@baseboard_fab2_lib.baseboard_fab2(sch_1):page101_i89" )
			)
			( gate "C2T27"
				( objectStatus "@baseboard_fab2_lib.baseboard_fab2(sch_1):page101_i90" )
			)
			( gate "R2T23"
				( objectStatus "@baseboard_fab2_lib.baseboard_fab2(sch_1):page101_i94" )
			)
			( gate "R2T52"
				( objectStatus "@baseboard_fab2_lib.baseboard_fab2(sch_1):page101_i95" )
			)
			( gate "C2T38"
				( objectStatus "@baseboard_fab2_lib.baseboard_fab2(sch_1):page101_i97" )
			)
			( gate "C2T37"
				( objectStatus "@baseboard_fab2_lib.baseboard_fab2(sch_1):page101_i99" )
			)
			( gate "C2T18"
				( objectStatus "@baseboard_fab2_lib.baseboard_fab2(sch_1):page101_i104" )
			)
			( gate "R2T21"
				( objectStatus "@baseboard_fab2_lib.baseboard_fab2(sch_1):page101_i105" )
			)
			( gate "C2T19"
				( objectStatus "@baseboard_fab2_lib.baseboard_fab2(sch_1):page101_i106" )
			)
			( gate "C2T34"
				( objectStatus "@baseboard_fab2_lib.baseboard_fab2(sch_1):page101_i109" )
			)
			( gate "C2T30"
				( objectStatus "@baseboard_fab2_lib.baseboard_fab2(sch_1):page101_i110" )
			)
			( gate "C2T25"
				( objectStatus "@baseboard_fab2_lib.baseboard_fab2(sch_1):page101_i111" )
			)
			( gate "C2T17"
				( objectStatus "@baseboard_fab2_lib.baseboard_fab2(sch_1):page101_i112" )
			)
			( gate "C2T22"
				( objectStatus "@baseboard_fab2_lib.baseboard_fab2(sch_1):page101_i113" )
			)
			( gate "FB2T2"
				( objectStatus "@baseboard_fab2_lib.baseboard_fab2(sch_1):page101_i114" )
			)
			( gate "C2T28"
				( objectStatus "@baseboard_fab2_lib.baseboard_fab2(sch_1):page101_i116" )
			)
			( gate "R2T42"
				( objectStatus "@baseboard_fab2_lib.baseboard_fab2(sch_1):page101_i124" )
			)
			( gate "R2T46"
				( objectStatus "@baseboard_fab2_lib.baseboard_fab2(sch_1):page101_i125" )
			)
			( gate "R8G24"
				( objectStatus "@baseboard_fab2_lib.baseboard_fab2(sch_1):page101_i143" )
			)
			( gate "R2T47"
				( objectStatus "@baseboard_fab2_lib.baseboard_fab2(sch_1):page101_i130" )
			)
			( gate "EU4D2"
				( objectStatus "@baseboard_fab2_lib.baseboard_fab2(sch_1):page102_i1" )
			)
			( gate "FB6P1"
				( objectStatus "@baseboard_fab2_lib.baseboard_fab2(sch_1):page102_i8" )
			)
			( gate "C3D22"
				( objectStatus "@baseboard_fab2_lib.baseboard_fab2(sch_1):page102_i10" )
			)
			( gate "C6P4"
				( objectStatus "@baseboard_fab2_lib.baseboard_fab2(sch_1):page102_i11" )
			)
			( gate "C6P6"
				( objectStatus "@baseboard_fab2_lib.baseboard_fab2(sch_1):page102_i12" )
			)
			( gate "C6P10"
				( objectStatus "@baseboard_fab2_lib.baseboard_fab2(sch_1):page102_i13" )
			)
			( gate "C6P5"
				( objectStatus "@baseboard_fab2_lib.baseboard_fab2(sch_1):page102_i14" )
			)
			( gate "C6P12"
				( objectStatus "@baseboard_fab2_lib.baseboard_fab2(sch_1):page102_i15" )
			)
			( gate "C6P11"
				( objectStatus "@baseboard_fab2_lib.baseboard_fab2(sch_1):page102_i16" )
			)
			( gate "C4D24"
				( objectStatus "@baseboard_fab2_lib.baseboard_fab2(sch_1):page102_i18" )
			)
			( gate "C4D23"
				( objectStatus "@baseboard_fab2_lib.baseboard_fab2(sch_1):page102_i19" )
			)
			( gate "R3D14"
				( objectStatus "@baseboard_fab2_lib.baseboard_fab2(sch_1):page102_i21" )
			)
			( gate "R6P25"
				( objectStatus "@baseboard_fab2_lib.baseboard_fab2(sch_1):page102_i26" )
			)
			( gate "C4D22"
				( objectStatus "@baseboard_fab2_lib.baseboard_fab2(sch_1):page102_i28" )
			)
			( gate "C4D27"
				( objectStatus "@baseboard_fab2_lib.baseboard_fab2(sch_1):page102_i30" )
			)
			( gate "R4D38"
				( objectStatus "@baseboard_fab2_lib.baseboard_fab2(sch_1):page102_i37" )
			)
			( gate "R4D35"
				( objectStatus "@baseboard_fab2_lib.baseboard_fab2(sch_1):page102_i38" )
			)
			( gate "R4D40"
				( objectStatus "@baseboard_fab2_lib.baseboard_fab2(sch_1):page102_i45" )
			)
			( gate "R6P23"
				( objectStatus "@baseboard_fab2_lib.baseboard_fab2(sch_1):page102_i46" )
			)
			( gate "R6P22"
				( objectStatus "@baseboard_fab2_lib.baseboard_fab2(sch_1):page102_i47" )
			)
			( gate "R4D41"
				( objectStatus "@baseboard_fab2_lib.baseboard_fab2(sch_1):page102_i53" )
			)
			( gate "C6P9"
				( objectStatus "@baseboard_fab2_lib.baseboard_fab2(sch_1):page102_i79" )
			)
			( gate "R6P21"
				( objectStatus "@baseboard_fab2_lib.baseboard_fab2(sch_1):page102_i80" )
			)
			( gate "R6P20"
				( objectStatus "@baseboard_fab2_lib.baseboard_fab2(sch_1):page102_i81" )
			)
			( gate "R4W3"
				( objectStatus "@baseboard_fab2_lib.baseboard_fab2(sch_1):page102_i105" )
			)
			( gate "Q4W1"
				( objectStatus "@baseboard_fab2_lib.baseboard_fab2(sch_1):page102_i102" )
			)
			( gate "R4D69"
				( objectStatus "@baseboard_fab2_lib.baseboard_fab2(sch_1):page102_i93" )
			)
			( gate "R4D70"
				( objectStatus "@baseboard_fab2_lib.baseboard_fab2(sch_1):page102_i94" )
			)
			( gate "R4D25"
				( objectStatus "@baseboard_fab2_lib.baseboard_fab2(sch_1):page103_i1" )
			)
			( gate "R4D23"
				( objectStatus "@baseboard_fab2_lib.baseboard_fab2(sch_1):page103_i9" )
			)
			( gate "R4D28"
				( objectStatus "@baseboard_fab2_lib.baseboard_fab2(sch_1):page103_i14" )
			)
			( gate "R4D19"
				( objectStatus "@baseboard_fab2_lib.baseboard_fab2(sch_1):page103_i19" )
			)
			( gate "R4D21"
				( objectStatus "@baseboard_fab2_lib.baseboard_fab2(sch_1):page103_i24" )
			)
			( gate "R4D13"
				( objectStatus "@baseboard_fab2_lib.baseboard_fab2(sch_1):page103_i29" )
			)
			( gate "R4D16"
				( objectStatus "@baseboard_fab2_lib.baseboard_fab2(sch_1):page103_i34" )
			)
			( gate "R4D9"
				( objectStatus "@baseboard_fab2_lib.baseboard_fab2(sch_1):page103_i39" )
			)
			( gate "R4D11"
				( objectStatus "@baseboard_fab2_lib.baseboard_fab2(sch_1):page103_i44" )
			)
			( gate "R4D2"
				( objectStatus "@baseboard_fab2_lib.baseboard_fab2(sch_1):page103_i49" )
			)
			( gate "R4D1"
				( objectStatus "@baseboard_fab2_lib.baseboard_fab2(sch_1):page103_i54" )
			)
			( gate "R4D4"
				( objectStatus "@baseboard_fab2_lib.baseboard_fab2(sch_1):page103_i59" )
			)
			( gate "R4D3"
				( objectStatus "@baseboard_fab2_lib.baseboard_fab2(sch_1):page103_i64" )
			)
			( gate "R4D29"
				( objectStatus "@baseboard_fab2_lib.baseboard_fab2(sch_1):page103_i69" )
			)
			( gate "R4D6"
				( objectStatus "@baseboard_fab2_lib.baseboard_fab2(sch_1):page103_i74" )
			)
			( gate "R4D5"
				( objectStatus "@baseboard_fab2_lib.baseboard_fab2(sch_1):page103_i79" )
			)
			( gate "R4D8"
				( objectStatus "@baseboard_fab2_lib.baseboard_fab2(sch_1):page103_i84" )
			)
			( gate "R4D7"
				( objectStatus "@baseboard_fab2_lib.baseboard_fab2(sch_1):page103_i89" )
			)
			( gate "R4D12"
				( objectStatus "@baseboard_fab2_lib.baseboard_fab2(sch_1):page103_i94" )
			)
			( gate "R4D10"
				( objectStatus "@baseboard_fab2_lib.baseboard_fab2(sch_1):page103_i99" )
			)
			( gate "R4D17"
				( objectStatus "@baseboard_fab2_lib.baseboard_fab2(sch_1):page103_i104" )
			)
			( gate "R4D14"
				( objectStatus "@baseboard_fab2_lib.baseboard_fab2(sch_1):page103_i109" )
			)
			( gate "R4D22"
				( objectStatus "@baseboard_fab2_lib.baseboard_fab2(sch_1):page103_i114" )
			)
			( gate "R4D20"
				( objectStatus "@baseboard_fab2_lib.baseboard_fab2(sch_1):page103_i119" )
			)
			( gate "R7P9"
				( objectStatus "@baseboard_fab2_lib.baseboard_fab2(sch_1):page103_i121" )
			)
			( gate "R7P12"
				( objectStatus "@baseboard_fab2_lib.baseboard_fab2(sch_1):page103_i123" )
			)
			( gate "R7P6"
				( objectStatus "@baseboard_fab2_lib.baseboard_fab2(sch_1):page103_i125" )
			)
			( gate "R7P7"
				( objectStatus "@baseboard_fab2_lib.baseboard_fab2(sch_1):page103_i127" )
			)
			( gate "R7P3"
				( objectStatus "@baseboard_fab2_lib.baseboard_fab2(sch_1):page103_i129" )
			)
			( gate "R7P4"
				( objectStatus "@baseboard_fab2_lib.baseboard_fab2(sch_1):page103_i131" )
			)
			( gate "R7P1"
				( objectStatus "@baseboard_fab2_lib.baseboard_fab2(sch_1):page103_i133" )
			)
			( gate "R7P2"
				( objectStatus "@baseboard_fab2_lib.baseboard_fab2(sch_1):page103_i135" )
			)
			( gate "R6P7"
				( objectStatus "@baseboard_fab2_lib.baseboard_fab2(sch_1):page103_i137" )
			)
			( gate "R6P8"
				( objectStatus "@baseboard_fab2_lib.baseboard_fab2(sch_1):page103_i139" )
			)
			( gate "R6P5"
				( objectStatus "@baseboard_fab2_lib.baseboard_fab2(sch_1):page103_i141" )
			)
			( gate "R6P6"
				( objectStatus "@baseboard_fab2_lib.baseboard_fab2(sch_1):page103_i143" )
			)
			( gate "R6P3"
				( objectStatus "@baseboard_fab2_lib.baseboard_fab2(sch_1):page103_i145" )
			)
			( gate "R6P4"
				( objectStatus "@baseboard_fab2_lib.baseboard_fab2(sch_1):page103_i147" )
			)
			( gate "R6P1"
				( objectStatus "@baseboard_fab2_lib.baseboard_fab2(sch_1):page103_i149" )
			)
			( gate "R6P2"
				( objectStatus "@baseboard_fab2_lib.baseboard_fab2(sch_1):page103_i151" )
			)
			( gate "R6P11"
				( objectStatus "@baseboard_fab2_lib.baseboard_fab2(sch_1):page103_i153" )
			)
			( gate "R6P9"
				( objectStatus "@baseboard_fab2_lib.baseboard_fab2(sch_1):page103_i155" )
			)
			( gate "R6P13"
				( objectStatus "@baseboard_fab2_lib.baseboard_fab2(sch_1):page103_i157" )
			)
			( gate "R6P12"
				( objectStatus "@baseboard_fab2_lib.baseboard_fab2(sch_1):page103_i159" )
			)
			( gate "R4D24"
				( objectStatus "@baseboard_fab2_lib.baseboard_fab2(sch_1):page103_i161" )
			)
			( gate "R4D18"
				( objectStatus "@baseboard_fab2_lib.baseboard_fab2(sch_1):page103_i163" )
			)
			( gate "R6P17"
				( objectStatus "@baseboard_fab2_lib.baseboard_fab2(sch_1):page103_i165" )
			)
			( gate "R6P15"
				( objectStatus "@baseboard_fab2_lib.baseboard_fab2(sch_1):page103_i167" )
			)
			( gate "C6F1"
				( objectStatus "@baseboard_fab2_lib.baseboard_fab2(sch_1):page104_i25" )
			)
			( gate "C3F2"
				( objectStatus "@baseboard_fab2_lib.baseboard_fab2(sch_1):page104_i34" )
			)
			( gate "R6F8"
				( objectStatus "@baseboard_fab2_lib.baseboard_fab2(sch_1):page104_i37" )
			)
			( gate "R6F6"
				( objectStatus "@baseboard_fab2_lib.baseboard_fab2(sch_1):page104_i41" )
			)
			( gate "R3F1"
				( objectStatus "@baseboard_fab2_lib.baseboard_fab2(sch_1):page104_i51" )
			)
			( gate "R3F3"
				( objectStatus "@baseboard_fab2_lib.baseboard_fab2(sch_1):page104_i53" )
			)
			( gate "R6F7"
				( objectStatus "@baseboard_fab2_lib.baseboard_fab2(sch_1):page104_i67" )
			)
			( gate "R6F9"
				( objectStatus "@baseboard_fab2_lib.baseboard_fab2(sch_1):page104_i68" )
			)
			( gate "R3F2"
				( objectStatus "@baseboard_fab2_lib.baseboard_fab2(sch_1):page104_i69" )
			)
			( gate "R3F4"
				( objectStatus "@baseboard_fab2_lib.baseboard_fab2(sch_1):page104_i70" )
			)
			( gate "Y6F1"
				( objectStatus "@baseboard_fab2_lib.baseboard_fab2(sch_1):page104_i71" )
			)
			( gate "Y3F1"
				( objectStatus "@baseboard_fab2_lib.baseboard_fab2(sch_1):page104_i72" )
			)
			( gate "R6F10"
				( objectStatus "@baseboard_fab2_lib.baseboard_fab2(sch_1):page104_i78" )
			)
			( gate "R6F11"
				( objectStatus "@baseboard_fab2_lib.baseboard_fab2(sch_1):page104_i79" )
			)
			( gate "R3F5"
				( objectStatus "@baseboard_fab2_lib.baseboard_fab2(sch_1):page104_i84" )
			)
			( gate "R3F6"
				( objectStatus "@baseboard_fab2_lib.baseboard_fab2(sch_1):page104_i88" )
			)
			( gate "R8D43"
				( objectStatus "@baseboard_fab2_lib.baseboard_fab2(sch_1):page104_i93" )
			)
			( gate "R7D40"
				( objectStatus "@baseboard_fab2_lib.baseboard_fab2(sch_1):page104_i94" )
			)
			( gate "R7D36"
				( objectStatus "@baseboard_fab2_lib.baseboard_fab2(sch_1):page104_i96" )
			)
			( gate "R7D38"
				( objectStatus "@baseboard_fab2_lib.baseboard_fab2(sch_1):page104_i97" )
			)
			( gate "C7G24"
				( objectStatus "@baseboard_fab2_lib.baseboard_fab2(sch_1):page105_i1" )
			)
			( gate "C7G6"
				( objectStatus "@baseboard_fab2_lib.baseboard_fab2(sch_1):page105_i6" )
			)
			( gate "C7G7"
				( objectStatus "@baseboard_fab2_lib.baseboard_fab2(sch_1):page105_i7" )
			)
			( gate "C7G10"
				( objectStatus "@baseboard_fab2_lib.baseboard_fab2(sch_1):page105_i8" )
			)
			( gate "C7G12"
				( objectStatus "@baseboard_fab2_lib.baseboard_fab2(sch_1):page105_i12" )
			)
			( gate "C7G13"
				( objectStatus "@baseboard_fab2_lib.baseboard_fab2(sch_1):page105_i13" )
			)
			( gate "C7G5"
				( objectStatus "@baseboard_fab2_lib.baseboard_fab2(sch_1):page105_i20" )
			)
			( gate "C7G9"
				( objectStatus "@baseboard_fab2_lib.baseboard_fab2(sch_1):page105_i21" )
			)
			( gate "C7G8"
				( objectStatus "@baseboard_fab2_lib.baseboard_fab2(sch_1):page105_i22" )
			)
			( gate "C7G11"
				( objectStatus "@baseboard_fab2_lib.baseboard_fab2(sch_1):page105_i27" )
			)
			( gate "C7G14"
				( objectStatus "@baseboard_fab2_lib.baseboard_fab2(sch_1):page105_i28" )
			)
			( gate "C7G16"
				( objectStatus "@baseboard_fab2_lib.baseboard_fab2(sch_1):page105_i31" )
			)
			( gate "C7G18"
				( objectStatus "@baseboard_fab2_lib.baseboard_fab2(sch_1):page105_i32" )
			)
			( gate "C7G22"
				( objectStatus "@baseboard_fab2_lib.baseboard_fab2(sch_1):page105_i37" )
			)
			( gate "C7G17"
				( objectStatus "@baseboard_fab2_lib.baseboard_fab2(sch_1):page105_i44" )
			)
			( gate "C7G15"
				( objectStatus "@baseboard_fab2_lib.baseboard_fab2(sch_1):page105_i45" )
			)
			( gate "C7G21"
				( objectStatus "@baseboard_fab2_lib.baseboard_fab2(sch_1):page105_i51" )
			)
			( gate "C7G23"
				( objectStatus "@baseboard_fab2_lib.baseboard_fab2(sch_1):page105_i52" )
			)
			( gate "C7G26"
				( objectStatus "@baseboard_fab2_lib.baseboard_fab2(sch_1):page105_i55" )
			)
			( gate "C8G4"
				( objectStatus "@baseboard_fab2_lib.baseboard_fab2(sch_1):page105_i56" )
			)
			( gate "C8G2"
				( objectStatus "@baseboard_fab2_lib.baseboard_fab2(sch_1):page105_i58" )
			)
			( gate "C8G6"
				( objectStatus "@baseboard_fab2_lib.baseboard_fab2(sch_1):page105_i61" )
			)
			( gate "C8G7"
				( objectStatus "@baseboard_fab2_lib.baseboard_fab2(sch_1):page105_i62" )
			)
			( gate "C7G25"
				( objectStatus "@baseboard_fab2_lib.baseboard_fab2(sch_1):page105_i69" )
			)
			( gate "C8G1"
				( objectStatus "@baseboard_fab2_lib.baseboard_fab2(sch_1):page105_i70" )
			)
			( gate "C8G3"
				( objectStatus "@baseboard_fab2_lib.baseboard_fab2(sch_1):page105_i71" )
			)
			( gate "C8G5"
				( objectStatus "@baseboard_fab2_lib.baseboard_fab2(sch_1):page105_i75" )
			)
			( gate "C8G8"
				( objectStatus "@baseboard_fab2_lib.baseboard_fab2(sch_1):page105_i76" )
			)
			( gate "C8G9"
				( objectStatus "@baseboard_fab2_lib.baseboard_fab2(sch_1):page105_i93" )
			)
			( gate "C8G10"
				( objectStatus "@baseboard_fab2_lib.baseboard_fab2(sch_1):page105_i96" )
			)
			( gate "C6B18"
				( objectStatus "@baseboard_fab2_lib.baseboard_fab2(sch_1):page105_i153" )
			)
			( gate "C6B19"
				( objectStatus "@baseboard_fab2_lib.baseboard_fab2(sch_1):page105_i160" )
			)
			( gate "C6B15"
				( objectStatus "@baseboard_fab2_lib.baseboard_fab2(sch_1):page105_i163" )
			)
			( gate "C6B11"
				( objectStatus "@baseboard_fab2_lib.baseboard_fab2(sch_1):page105_i166" )
			)
			( gate "C6B6"
				( objectStatus "@baseboard_fab2_lib.baseboard_fab2(sch_1):page105_i169" )
			)
			( gate "C6B20"
				( objectStatus "@baseboard_fab2_lib.baseboard_fab2(sch_1):page105_i173" )
			)
			( gate "C6B17"
				( objectStatus "@baseboard_fab2_lib.baseboard_fab2(sch_1):page105_i175" )
			)
			( gate "C6B16"
				( objectStatus "@baseboard_fab2_lib.baseboard_fab2(sch_1):page105_i180" )
			)
			( gate "C6B14"
				( objectStatus "@baseboard_fab2_lib.baseboard_fab2(sch_1):page105_i181" )
			)
			( gate "C6B9"
				( objectStatus "@baseboard_fab2_lib.baseboard_fab2(sch_1):page105_i185" )
			)
			( gate "C6B12"
				( objectStatus "@baseboard_fab2_lib.baseboard_fab2(sch_1):page105_i187" )
			)
			( gate "C6B13"
				( objectStatus "@baseboard_fab2_lib.baseboard_fab2(sch_1):page105_i189" )
			)
			( gate "C6B10"
				( objectStatus "@baseboard_fab2_lib.baseboard_fab2(sch_1):page105_i193" )
			)
			( gate "C6B4"
				( objectStatus "@baseboard_fab2_lib.baseboard_fab2(sch_1):page105_i196" )
			)
			( gate "C6B8"
				( objectStatus "@baseboard_fab2_lib.baseboard_fab2(sch_1):page105_i198" )
			)
			( gate "C6B5"
				( objectStatus "@baseboard_fab2_lib.baseboard_fab2(sch_1):page105_i201" )
			)
			( gate "C3M25"
				( objectStatus "@baseboard_fab2_lib.baseboard_fab2(sch_1):page105_i205" )
			)
			( gate "C3M34"
				( objectStatus "@baseboard_fab2_lib.baseboard_fab2(sch_1):page105_i206" )
			)
			( gate "C3M28"
				( objectStatus "@baseboard_fab2_lib.baseboard_fab2(sch_1):page105_i212" )
			)
			( gate "C3M33"
				( objectStatus "@baseboard_fab2_lib.baseboard_fab2(sch_1):page105_i217" )
			)
			( gate "C3M36"
				( objectStatus "@baseboard_fab2_lib.baseboard_fab2(sch_1):page105_i218" )
			)
			( gate "C3M32"
				( objectStatus "@baseboard_fab2_lib.baseboard_fab2(sch_1):page105_i223" )
			)
			( gate "C3M35"
				( objectStatus "@baseboard_fab2_lib.baseboard_fab2(sch_1):page105_i225" )
			)
			( gate "C3M26"
				( objectStatus "@baseboard_fab2_lib.baseboard_fab2(sch_1):page105_i229" )
			)
			( gate "C3M3"
				( objectStatus "@baseboard_fab2_lib.baseboard_fab2(sch_1):page105_i232" )
			)
			( gate "C3M11"
				( objectStatus "@baseboard_fab2_lib.baseboard_fab2(sch_1):page105_i234" )
			)
			( gate "C3M13"
				( objectStatus "@baseboard_fab2_lib.baseboard_fab2(sch_1):page105_i239" )
			)
			( gate "C3M4"
				( objectStatus "@baseboard_fab2_lib.baseboard_fab2(sch_1):page105_i244" )
			)
			( gate "C3M12"
				( objectStatus "@baseboard_fab2_lib.baseboard_fab2(sch_1):page105_i246" )
			)
			( gate "C3M2"
				( objectStatus "@baseboard_fab2_lib.baseboard_fab2(sch_1):page105_i247" )
			)
			( gate "C3M14"
				( objectStatus "@baseboard_fab2_lib.baseboard_fab2(sch_1):page105_i253" )
			)
			( gate "C3M1"
				( objectStatus "@baseboard_fab2_lib.baseboard_fab2(sch_1):page105_i255" )
			)
			( gate "C1R2"
				( objectStatus "@baseboard_fab2_lib.baseboard_fab2(sch_1):page106_i10" )
			)
			( gate "C1R4"
				( objectStatus "@baseboard_fab2_lib.baseboard_fab2(sch_1):page106_i26" )
			)
			( gate "C1R1"
				( objectStatus "@baseboard_fab2_lib.baseboard_fab2(sch_1):page106_i29" )
			)
			( gate "C1R3"
				( objectStatus "@baseboard_fab2_lib.baseboard_fab2(sch_1):page106_i37" )
			)
			( gate "C1R6"
				( objectStatus "@baseboard_fab2_lib.baseboard_fab2(sch_1):page106_i40" )
			)
			( gate "C1R8"
				( objectStatus "@baseboard_fab2_lib.baseboard_fab2(sch_1):page106_i55" )
			)
			( gate "C1R5"
				( objectStatus "@baseboard_fab2_lib.baseboard_fab2(sch_1):page106_i59" )
			)
			( gate "C1R7"
				( objectStatus "@baseboard_fab2_lib.baseboard_fab2(sch_1):page106_i70" )
			)
			( gate "C2M14"
				( objectStatus "@baseboard_fab2_lib.baseboard_fab2(sch_1):page106_i76" )
			)
			( gate "C1M18"
				( objectStatus "@baseboard_fab2_lib.baseboard_fab2(sch_1):page106_i78" )
			)
			( gate "C1M16"
				( objectStatus "@baseboard_fab2_lib.baseboard_fab2(sch_1):page106_i82" )
			)
			( gate "C1M14"
				( objectStatus "@baseboard_fab2_lib.baseboard_fab2(sch_1):page106_i85" )
			)
			( gate "C2M15"
				( objectStatus "@baseboard_fab2_lib.baseboard_fab2(sch_1):page106_i86" )
			)
			( gate "C1M19"
				( objectStatus "@baseboard_fab2_lib.baseboard_fab2(sch_1):page106_i90" )
			)
			( gate "C1M17"
				( objectStatus "@baseboard_fab2_lib.baseboard_fab2(sch_1):page106_i92" )
			)
			( gate "C1M15"
				( objectStatus "@baseboard_fab2_lib.baseboard_fab2(sch_1):page106_i95" )
			)
			( gate "C1M12"
				( objectStatus "@baseboard_fab2_lib.baseboard_fab2(sch_1):page106_i100" )
			)
			( gate "C1M10"
				( objectStatus "@baseboard_fab2_lib.baseboard_fab2(sch_1):page106_i102" )
			)
			( gate "C1M8"
				( objectStatus "@baseboard_fab2_lib.baseboard_fab2(sch_1):page106_i105" )
			)
			( gate "C1M6"
				( objectStatus "@baseboard_fab2_lib.baseboard_fab2(sch_1):page106_i109" )
			)
			( gate "C1M13"
				( objectStatus "@baseboard_fab2_lib.baseboard_fab2(sch_1):page106_i111" )
			)
			( gate "C1M9"
				( objectStatus "@baseboard_fab2_lib.baseboard_fab2(sch_1):page106_i114" )
			)
			( gate "C1M11"
				( objectStatus "@baseboard_fab2_lib.baseboard_fab2(sch_1):page106_i117" )
			)
			( gate "C1M7"
				( objectStatus "@baseboard_fab2_lib.baseboard_fab2(sch_1):page106_i122" )
			)
			( gate "C2R7"
				( objectStatus "@baseboard_fab2_lib.baseboard_fab2(sch_1):page106_i123" )
			)
			( gate "C1R10"
				( objectStatus "@baseboard_fab2_lib.baseboard_fab2(sch_1):page106_i128" )
			)
			( gate "C2R14"
				( objectStatus "@baseboard_fab2_lib.baseboard_fab2(sch_1):page106_i130" )
			)
			( gate "C1R9"
				( objectStatus "@baseboard_fab2_lib.baseboard_fab2(sch_1):page106_i134" )
			)
			( gate "C2R13"
				( objectStatus "@baseboard_fab2_lib.baseboard_fab2(sch_1):page106_i137" )
			)
			( gate "C2R8"
				( objectStatus "@baseboard_fab2_lib.baseboard_fab2(sch_1):page106_i141" )
			)
			( gate "C2R10"
				( objectStatus "@baseboard_fab2_lib.baseboard_fab2(sch_1):page106_i142" )
			)
			( gate "C2R9"
				( objectStatus "@baseboard_fab2_lib.baseboard_fab2(sch_1):page106_i147" )
			)
			( gate "C3P13"
				( objectStatus "@baseboard_fab2_lib.baseboard_fab2(sch_1):page107_i207" )
			)
			( gate "C3P17"
				( objectStatus "@baseboard_fab2_lib.baseboard_fab2(sch_1):page107_i208" )
			)
			( gate "C3P11"
				( objectStatus "@baseboard_fab2_lib.baseboard_fab2(sch_1):page107_i212" )
			)
			( gate "C3P20"
				( objectStatus "@baseboard_fab2_lib.baseboard_fab2(sch_1):page107_i215" )
			)
			( gate "C3P25"
				( objectStatus "@baseboard_fab2_lib.baseboard_fab2(sch_1):page107_i216" )
			)
			( gate "C3P18"
				( objectStatus "@baseboard_fab2_lib.baseboard_fab2(sch_1):page107_i219" )
			)
			( gate "C3P27"
				( objectStatus "@baseboard_fab2_lib.baseboard_fab2(sch_1):page107_i223" )
			)
			( gate "C3P15"
				( objectStatus "@baseboard_fab2_lib.baseboard_fab2(sch_1):page107_i226" )
			)
			( gate "C3P23"
				( objectStatus "@baseboard_fab2_lib.baseboard_fab2(sch_1):page107_i229" )
			)
			( gate "C3P28"
				( objectStatus "@baseboard_fab2_lib.baseboard_fab2(sch_1):page107_i232" )
			)
			( gate "C3P32"
				( objectStatus "@baseboard_fab2_lib.baseboard_fab2(sch_1):page107_i234" )
			)
			( gate "C3P37"
				( objectStatus "@baseboard_fab2_lib.baseboard_fab2(sch_1):page107_i235" )
			)
			( gate "C3P35"
				( objectStatus "@baseboard_fab2_lib.baseboard_fab2(sch_1):page107_i240" )
			)
			( gate "C3P40"
				( objectStatus "@baseboard_fab2_lib.baseboard_fab2(sch_1):page107_i241" )
			)
			( gate "C3P30"
				( objectStatus "@baseboard_fab2_lib.baseboard_fab2(sch_1):page107_i245" )
			)
			( gate "C3P39"
				( objectStatus "@baseboard_fab2_lib.baseboard_fab2(sch_1):page107_i248" )
			)
			( gate "C2U4"
				( objectStatus "@baseboard_fab2_lib.baseboard_fab2(sch_1):page107_i257" )
			)
			( gate "C2U6"
				( objectStatus "@baseboard_fab2_lib.baseboard_fab2(sch_1):page107_i260" )
			)
			( gate "C2U8"
				( objectStatus "@baseboard_fab2_lib.baseboard_fab2(sch_1):page107_i264" )
			)
			( gate "C2U12"
				( objectStatus "@baseboard_fab2_lib.baseboard_fab2(sch_1):page107_i265" )
			)
			( gate "C2U10"
				( objectStatus "@baseboard_fab2_lib.baseboard_fab2(sch_1):page107_i267" )
			)
			( gate "C2U3"
				( objectStatus "@baseboard_fab2_lib.baseboard_fab2(sch_1):page107_i272" )
			)
			( gate "C2U5"
				( objectStatus "@baseboard_fab2_lib.baseboard_fab2(sch_1):page107_i274" )
			)
			( gate "C2U7"
				( objectStatus "@baseboard_fab2_lib.baseboard_fab2(sch_1):page107_i277" )
			)
			( gate "C2U11"
				( objectStatus "@baseboard_fab2_lib.baseboard_fab2(sch_1):page107_i278" )
			)
			( gate "C2U9"
				( objectStatus "@baseboard_fab2_lib.baseboard_fab2(sch_1):page107_i279" )
			)
			( gate "C2U16"
				( objectStatus "@baseboard_fab2_lib.baseboard_fab2(sch_1):page107_i286" )
			)
			( gate "C2U14"
				( objectStatus "@baseboard_fab2_lib.baseboard_fab2(sch_1):page107_i287" )
			)
			( gate "C2U18"
				( objectStatus "@baseboard_fab2_lib.baseboard_fab2(sch_1):page107_i294" )
			)
			( gate "C2U15"
				( objectStatus "@baseboard_fab2_lib.baseboard_fab2(sch_1):page107_i296" )
			)
			( gate "C2U13"
				( objectStatus "@baseboard_fab2_lib.baseboard_fab2(sch_1):page107_i297" )
			)
			( gate "C2U17"
				( objectStatus "@baseboard_fab2_lib.baseboard_fab2(sch_1):page107_i300" )
			)
			( gate "C3P34"
				( objectStatus "@baseboard_fab2_lib.baseboard_fab2(sch_1):page107_i489" )
			)
			( gate "R2U27"
				( objectStatus "@baseboard_fab2_lib.baseboard_fab2(sch_1):page107_i497" )
			)
			( gate "C3P31"
				( objectStatus "@baseboard_fab2_lib.baseboard_fab2(sch_1):page107_i488" )
			)
			( gate "C3P26"
				( objectStatus "@baseboard_fab2_lib.baseboard_fab2(sch_1):page107_i487" )
			)
			( gate "C3P38"
				( objectStatus "@baseboard_fab2_lib.baseboard_fab2(sch_1):page107_i486" )
			)
			( gate "R2U25"
				( objectStatus "@baseboard_fab2_lib.baseboard_fab2(sch_1):page107_i496" )
			)
			( gate "R2U23"
				( objectStatus "@baseboard_fab2_lib.baseboard_fab2(sch_1):page107_i495" )
			)
			( gate "R2U29"
				( objectStatus "@baseboard_fab2_lib.baseboard_fab2(sch_1):page107_i494" )
			)
			( gate "C3P19"
				( objectStatus "@baseboard_fab2_lib.baseboard_fab2(sch_1):page107_i485" )
			)
			( gate "C3P22"
				( objectStatus "@baseboard_fab2_lib.baseboard_fab2(sch_1):page107_i484" )
			)
			( gate "C3P14"
				( objectStatus "@baseboard_fab2_lib.baseboard_fab2(sch_1):page107_i483" )
			)
			( gate "R2U19"
				( objectStatus "@baseboard_fab2_lib.baseboard_fab2(sch_1):page107_i493" )
			)
			( gate "R2U17"
				( objectStatus "@baseboard_fab2_lib.baseboard_fab2(sch_1):page107_i492" )
			)
			( gate "C3P10"
				( objectStatus "@baseboard_fab2_lib.baseboard_fab2(sch_1):page107_i482" )
			)
			( gate "R2U21"
				( objectStatus "@baseboard_fab2_lib.baseboard_fab2(sch_1):page107_i491" )
			)
			( gate "R2U15"
				( objectStatus "@baseboard_fab2_lib.baseboard_fab2(sch_1):page107_i490" )
			)
			( gate "RF13"
				( objectStatus "@baseboard_fab2_lib.baseboard_fab2(sch_1):page211_i96" )
			)
			( gate "C4G23"
				( objectStatus "@baseboard_fab2_lib.baseboard_fab2(sch_1):page221_i2" )
			)
			( gate "C2U20"
				( objectStatus "@baseboard_fab2_lib.baseboard_fab2(sch_1):page108_i1" )
			)
			( gate "C2U24"
				( objectStatus "@baseboard_fab2_lib.baseboard_fab2(sch_1):page108_i2" )
			)
			( gate "C2U21"
				( objectStatus "@baseboard_fab2_lib.baseboard_fab2(sch_1):page108_i5" )
			)
			( gate "C2U25"
				( objectStatus "@baseboard_fab2_lib.baseboard_fab2(sch_1):page108_i7" )
			)
			( gate "R2U37"
				( objectStatus "@baseboard_fab2_lib.baseboard_fab2(sch_1):page108_i173" )
			)
			( gate "J8G1"
				( objectStatus "@baseboard_fab2_lib.baseboard_fab2(sch_1):page108_i258" )
			)
			( gate "C2U23"
				( objectStatus "@baseboard_fab2_lib.baseboard_fab2(sch_1):page108_i315" )
			)
			( gate "C2U22"
				( objectStatus "@baseboard_fab2_lib.baseboard_fab2(sch_1):page108_i318" )
			)
			( gate "R2U31"
				( objectStatus "@baseboard_fab2_lib.baseboard_fab2(sch_1):page108_i330" )
			)
			( gate "R2U32"
				( objectStatus "@baseboard_fab2_lib.baseboard_fab2(sch_1):page108_i339" )
			)
			( gate "R7E22"
				( objectStatus "@baseboard_fab2_lib.baseboard_fab2(sch_1):page108_i341" )
			)
			( gate "R7E21"
				( objectStatus "@baseboard_fab2_lib.baseboard_fab2(sch_1):page108_i343" )
			)
			( gate "R1L13"
				( objectStatus "@baseboard_fab2_lib.baseboard_fab2(sch_1):page111_i6" )
			)
			( gate "C9A2"
				( objectStatus "@baseboard_fab2_lib.baseboard_fab2(sch_1):page111_i10" )
			)
			( gate "R9A14"
				( objectStatus "@baseboard_fab2_lib.baseboard_fab2(sch_1):page111_i11" )
			)
			( gate "C9A5"
				( objectStatus "@baseboard_fab2_lib.baseboard_fab2(sch_1):page111_i12" )
			)
			( gate "R1L23"
				( objectStatus "@baseboard_fab2_lib.baseboard_fab2(sch_1):page111_i13" )
			)
			( gate "C1L8"
				( objectStatus "@baseboard_fab2_lib.baseboard_fab2(sch_1):page111_i14" )
			)
			( gate "C9A6"
				( objectStatus "@baseboard_fab2_lib.baseboard_fab2(sch_1):page111_i25" )
			)
			( gate "J9A3"
				( objectStatus "@baseboard_fab2_lib.baseboard_fab2(sch_1):page111_i26" )
			)
			( gate "C1L5"
				( objectStatus "@baseboard_fab2_lib.baseboard_fab2(sch_1):page111_i30" )
			)
			( gate "R2P2"
				( objectStatus "@baseboard_fab2_lib.baseboard_fab2(sch_1):page111_i37" )
			)
			( gate "R9A4"
				( objectStatus "@baseboard_fab2_lib.baseboard_fab2(sch_1):page111_i55" )
			)
			( gate "R1L17"
				( objectStatus "@baseboard_fab2_lib.baseboard_fab2(sch_1):page111_i56" )
			)
			( gate "R9A17"
				( objectStatus "@baseboard_fab2_lib.baseboard_fab2(sch_1):page111_i57" )
			)
			( gate "C9A4"
				( objectStatus "@baseboard_fab2_lib.baseboard_fab2(sch_1):page111_i59" )
			)
			( gate "R9A15"
				( objectStatus "@baseboard_fab2_lib.baseboard_fab2(sch_1):page111_i60" )
			)
			( gate "R1L29"
				( objectStatus "@baseboard_fab2_lib.baseboard_fab2(sch_1):page111_i68" )
			)
			( gate "R9A3"
				( objectStatus "@baseboard_fab2_lib.baseboard_fab2(sch_1):page111_i74" )
			)
			( gate "R9A2"
				( objectStatus "@baseboard_fab2_lib.baseboard_fab2(sch_1):page111_i83" )
			)
			( gate "U1L4"
				( objectStatus "@baseboard_fab2_lib.baseboard_fab2(sch_1):page111_i85" )
			)
			( gate "C1L11"
				( objectStatus "@baseboard_fab2_lib.baseboard_fab2(sch_1):page111_i87" )
			)
			( gate "R8E2"
				( objectStatus "@baseboard_fab2_lib.baseboard_fab2(sch_1):page111_i89" )
			)
			( gate "Q9A1"
				( objectStatus "@baseboard_fab2_lib.baseboard_fab2(sch_1):page111_i93" )
			)
			( gate "Q9A1"
				( objectStatus "@baseboard_fab2_lib.baseboard_fab2(sch_1):page111_i94" )
			)
			( gate "R9A1"
				( objectStatus "@baseboard_fab2_lib.baseboard_fab2(sch_1):page111_i95" )
			)
			( gate "U1M7"
				( objectStatus "@baseboard_fab2_lib.baseboard_fab2(sch_1):page112_i40" )
			)
			( gate "C1M36"
				( objectStatus "@baseboard_fab2_lib.baseboard_fab2(sch_1):page112_i42" )
			)
			( gate "C1M37"
				( objectStatus "@baseboard_fab2_lib.baseboard_fab2(sch_1):page112_i47" )
			)
			( gate "R6P46"
				( objectStatus "@baseboard_fab2_lib.baseboard_fab2(sch_1):page112_i49" )
			)
			( gate "R7P30"
				( objectStatus "@baseboard_fab2_lib.baseboard_fab2(sch_1):page112_i50" )
			)
			( gate "R1M3"
				( objectStatus "@baseboard_fab2_lib.baseboard_fab2(sch_1):page112_i51" )
			)
			( gate "R4P15"
				( objectStatus "@baseboard_fab2_lib.baseboard_fab2(sch_1):page112_i53" )
			)
			( gate "R1M4"
				( objectStatus "@baseboard_fab2_lib.baseboard_fab2(sch_1):page112_i54" )
			)
			( gate "R6T7"
				( objectStatus "@baseboard_fab2_lib.baseboard_fab2(sch_1):page112_i55" )
			)
			( gate "R6T6"
				( objectStatus "@baseboard_fab2_lib.baseboard_fab2(sch_1):page112_i56" )
			)
			( gate "R4P12"
				( objectStatus "@baseboard_fab2_lib.baseboard_fab2(sch_1):page112_i57" )
			)
			( gate "R4P23"
				( objectStatus "@baseboard_fab2_lib.baseboard_fab2(sch_1):page112_i58" )
			)
			( gate "R4P24"
				( objectStatus "@baseboard_fab2_lib.baseboard_fab2(sch_1):page112_i59" )
			)
			( gate "R1L15"
				( objectStatus "@baseboard_fab2_lib.baseboard_fab2(sch_1):page112_i60" )
			)
			( gate "R7P29"
				( objectStatus "@baseboard_fab2_lib.baseboard_fab2(sch_1):page112_i61" )
			)
			( gate "R6T5"
				( objectStatus "@baseboard_fab2_lib.baseboard_fab2(sch_1):page112_i62" )
			)
			( gate "R1L39"
				( objectStatus "@baseboard_fab2_lib.baseboard_fab2(sch_1):page112_i76" )
			)
			( gate "R1L41"
				( objectStatus "@baseboard_fab2_lib.baseboard_fab2(sch_1):page112_i77" )
			)
			( gate "R9A11"
				( objectStatus "@baseboard_fab2_lib.baseboard_fab2(sch_1):page112_i78" )
			)
			( gate "R8A13"
				( objectStatus "@baseboard_fab2_lib.baseboard_fab2(sch_1):page112_i79" )
			)
			( gate "R8A14"
				( objectStatus "@baseboard_fab2_lib.baseboard_fab2(sch_1):page112_i80" )
			)
			( gate "R3M10"
				( objectStatus "@baseboard_fab2_lib.baseboard_fab2(sch_1):page112_i85" )
			)
			( gate "R8B2"
				( objectStatus "@baseboard_fab2_lib.baseboard_fab2(sch_1):page112_i94" )
			)
			( gate "R8B1"
				( objectStatus "@baseboard_fab2_lib.baseboard_fab2(sch_1):page112_i95" )
			)
			( gate "U1L1"
				( objectStatus "@baseboard_fab2_lib.baseboard_fab2(sch_1):page112_i108" )
			)
			( gate "U1L5"
				( objectStatus "@baseboard_fab2_lib.baseboard_fab2(sch_1):page112_i109" )
			)
			( gate "R6T9"
				( objectStatus "@baseboard_fab2_lib.baseboard_fab2(sch_1):page112_i120" )
			)
			( gate "R6T8"
				( objectStatus "@baseboard_fab2_lib.baseboard_fab2(sch_1):page112_i121" )
			)
			( gate "U1M4"
				( objectStatus "@baseboard_fab2_lib.baseboard_fab2(sch_1):page112_i127" )
			)
			( gate "C1M30"
				( objectStatus "@baseboard_fab2_lib.baseboard_fab2(sch_1):page112_i131" )
			)
			( gate "C1L1"
				( objectStatus "@baseboard_fab2_lib.baseboard_fab2(sch_1):page112_i136" )
			)
			( gate "C1L19"
				( objectStatus "@baseboard_fab2_lib.baseboard_fab2(sch_1):page112_i140" )
			)
			( gate "U1M2"
				( objectStatus "@baseboard_fab2_lib.baseboard_fab2(sch_1):page113_i107" )
			)
			( gate "C1M31"
				( objectStatus "@baseboard_fab2_lib.baseboard_fab2(sch_1):page113_i116" )
			)
			( gate "C1M32"
				( objectStatus "@baseboard_fab2_lib.baseboard_fab2(sch_1):page113_i117" )
			)
			( gate "C1M28"
				( objectStatus "@baseboard_fab2_lib.baseboard_fab2(sch_1):page113_i119" )
			)
			( gate "U1M6"
				( objectStatus "@baseboard_fab2_lib.baseboard_fab2(sch_1):page113_i127" )
			)
			( gate "C1M29"
				( objectStatus "@baseboard_fab2_lib.baseboard_fab2(sch_1):page113_i147" )
			)
			( gate "R9B14"
				( objectStatus "@baseboard_fab2_lib.baseboard_fab2(sch_1):page113_i168" )
			)
			( gate "J9B4"
				( objectStatus "@baseboard_fab2_lib.baseboard_fab2(sch_1):page113_i175" )
			)
			( gate "R9B9"
				( objectStatus "@baseboard_fab2_lib.baseboard_fab2(sch_1):page113_i179" )
			)
			( gate "R9B10"
				( objectStatus "@baseboard_fab2_lib.baseboard_fab2(sch_1):page113_i180" )
			)
			( gate "U9A5"
				( objectStatus "@baseboard_fab2_lib.baseboard_fab2(sch_1):page113_i185" )
			)
			( gate "U6M1"
				( objectStatus "@baseboard_fab2_lib.baseboard_fab2(sch_1):page113_i190" )
			)
			( gate "R1M22"
				( objectStatus "@baseboard_fab2_lib.baseboard_fab2(sch_1):page113_i195" )
			)
			( gate "U1M5"
				( objectStatus "@baseboard_fab2_lib.baseboard_fab2(sch_1):page113_i196" )
			)
			( gate "R1M23"
				( objectStatus "@baseboard_fab2_lib.baseboard_fab2(sch_1):page113_i199" )
			)
			( gate "R1M19"
				( objectStatus "@baseboard_fab2_lib.baseboard_fab2(sch_1):page113_i202" )
			)
			( gate "R9B12"
				( objectStatus "@baseboard_fab2_lib.baseboard_fab2(sch_1):page113_i203" )
			)
			( gate "R1M20"
				( objectStatus "@baseboard_fab2_lib.baseboard_fab2(sch_1):page113_i204" )
			)
			( gate "R1M21"
				( objectStatus "@baseboard_fab2_lib.baseboard_fab2(sch_1):page113_i205" )
			)
			( gate "U4R1"
				( objectStatus "@baseboard_fab2_lib.baseboard_fab2(sch_1):page113_i206" )
			)
			( gate "R9B11"
				( objectStatus "@baseboard_fab2_lib.baseboard_fab2(sch_1):page113_i239" )
			)
			( gate "R9B13"
				( objectStatus "@baseboard_fab2_lib.baseboard_fab2(sch_1):page113_i240" )
			)
			( gate "C4R2"
				( objectStatus "@baseboard_fab2_lib.baseboard_fab2(sch_1):page113_i246" )
			)
			( gate "C1M33"
				( objectStatus "@baseboard_fab2_lib.baseboard_fab2(sch_1):page113_i248" )
			)
			( gate "C6M6"
				( objectStatus "@baseboard_fab2_lib.baseboard_fab2(sch_1):page113_i250" )
			)
			( gate "U2M1"
				( objectStatus "@baseboard_fab2_lib.baseboard_fab2(sch_1):page113_i255" )
			)
			( gate "C1M34"
				( objectStatus "@baseboard_fab2_lib.baseboard_fab2(sch_1):page113_i265" )
			)
			( gate "C1M35"
				( objectStatus "@baseboard_fab2_lib.baseboard_fab2(sch_1):page113_i266" )
			)
			( gate "C1L20"
				( objectStatus "@baseboard_fab2_lib.baseboard_fab2(sch_1):page113_i267" )
			)
			( gate "U7C1"
				( objectStatus "@baseboard_fab2_lib.baseboard_fab2(sch_1):page114_i40" )
			)
			( gate "C3N38"
				( objectStatus "@baseboard_fab2_lib.baseboard_fab2(sch_1):page212_i146" )
			)
			( gate "C7C5"
				( objectStatus "@baseboard_fab2_lib.baseboard_fab2(sch_1):page114_i47" )
			)
			( gate "R7C1"
				( objectStatus "@baseboard_fab2_lib.baseboard_fab2(sch_1):page114_i48" )
			)
			( gate "Y7C1"
				( objectStatus "@baseboard_fab2_lib.baseboard_fab2(sch_1):page114_i49" )
			)
			( gate "C7C4"
				( objectStatus "@baseboard_fab2_lib.baseboard_fab2(sch_1):page114_i50" )
			)
			( gate "R7C6"
				( objectStatus "@baseboard_fab2_lib.baseboard_fab2(sch_1):page114_i54" )
			)
			( gate "Y7C2"
				( objectStatus "@baseboard_fab2_lib.baseboard_fab2(sch_1):page114_i55" )
			)
			( gate "C3N26"
				( objectStatus "@baseboard_fab2_lib.baseboard_fab2(sch_1):page212_i145" )
			)
			( gate "R8B20"
				( objectStatus "@baseboard_fab2_lib.baseboard_fab2(sch_1):page114_i110" )
			)
			( gate "R8B21"
				( objectStatus "@baseboard_fab2_lib.baseboard_fab2(sch_1):page114_i124" )
			)
			( gate "R3N1"
				( objectStatus "@baseboard_fab2_lib.baseboard_fab2(sch_1):page114_i149" )
			)
			( gate "U7C1"
				( objectStatus "@baseboard_fab2_lib.baseboard_fab2(sch_1):page115_i74" )
			)
			( gate "R8B9"
				( objectStatus "@baseboard_fab2_lib.baseboard_fab2(sch_1):page115_i90" )
			)
			( gate "R8B32"
				( objectStatus "@baseboard_fab2_lib.baseboard_fab2(sch_1):page115_i114" )
			)
			( gate "R3M11"
				( objectStatus "@baseboard_fab2_lib.baseboard_fab2(sch_1):page116_i108" )
			)
			( gate "R3M12"
				( objectStatus "@baseboard_fab2_lib.baseboard_fab2(sch_1):page116_i181" )
			)
			( gate "C25W21"
				( objectStatus "@baseboard_fab2_lib.baseboard_fab2(sch_1):page145_i159" )
			)
			( gate "C25W20"
				( objectStatus "@baseboard_fab2_lib.baseboard_fab2(sch_1):page145_i158" )
			)
			( gate "U7C1"
				( objectStatus "@baseboard_fab2_lib.baseboard_fab2(sch_1):page116_i220" )
			)
			( gate "R7B8"
				( objectStatus "@baseboard_fab2_lib.baseboard_fab2(sch_1):page116_i229" )
			)
			( gate "R7B7"
				( objectStatus "@baseboard_fab2_lib.baseboard_fab2(sch_1):page116_i230" )
			)
			( gate "R3M9"
				( objectStatus "@baseboard_fab2_lib.baseboard_fab2(sch_1):page116_i234" )
			)
			( gate "R3M8"
				( objectStatus "@baseboard_fab2_lib.baseboard_fab2(sch_1):page116_i235" )
			)
			( gate "U7C1"
				( objectStatus "@baseboard_fab2_lib.baseboard_fab2(sch_1):page117_i9" )
			)
			( gate "R3N9"
				( objectStatus "@baseboard_fab2_lib.baseboard_fab2(sch_1):page118_i66" )
			)
			( gate "R3N14"
				( objectStatus "@baseboard_fab2_lib.baseboard_fab2(sch_1):page118_i67" )
			)
			( gate "R3N13"
				( objectStatus "@baseboard_fab2_lib.baseboard_fab2(sch_1):page118_i71" )
			)
			( gate "U7C1"
				( objectStatus "@baseboard_fab2_lib.baseboard_fab2(sch_1):page118_i73" )
			)
			( gate "Y8C1"
				( objectStatus "@baseboard_fab2_lib.baseboard_fab2(sch_1):page118_i76" )
			)
			( gate "R2N4"
				( objectStatus "@baseboard_fab2_lib.baseboard_fab2(sch_1):page118_i96" )
			)
			( gate "R2M6"
				( objectStatus "@baseboard_fab2_lib.baseboard_fab2(sch_1):page118_i99" )
			)
			( gate "R8C24"
				( objectStatus "@baseboard_fab2_lib.baseboard_fab2(sch_1):page118_i120" )
			)
			( gate "R8C23"
				( objectStatus "@baseboard_fab2_lib.baseboard_fab2(sch_1):page118_i125" )
			)
			( gate "R2N6"
				( objectStatus "@baseboard_fab2_lib.baseboard_fab2(sch_1):page118_i128" )
			)
			( gate "R7D23"
				( objectStatus "@baseboard_fab2_lib.baseboard_fab2(sch_1):page118_i131" )
			)
			( gate "C7D1"
				( objectStatus "@baseboard_fab2_lib.baseboard_fab2(sch_1):page118_i136" )
			)
			( gate "U7D1"
				( objectStatus "@baseboard_fab2_lib.baseboard_fab2(sch_1):page118_i142" )
			)
			( gate "R7C23"
				( objectStatus "@baseboard_fab2_lib.baseboard_fab2(sch_1):page118_i144" )
			)
			( gate "U7C1"
				( objectStatus "@baseboard_fab2_lib.baseboard_fab2(sch_1):page119_i115" )
			)
			( gate "R2M3"
				( objectStatus "@baseboard_fab2_lib.baseboard_fab2(sch_1):page119_i172" )
			)
			( gate "R2N1"
				( objectStatus "@baseboard_fab2_lib.baseboard_fab2(sch_1):page119_i173" )
			)
			( gate "R2M7"
				( objectStatus "@baseboard_fab2_lib.baseboard_fab2(sch_1):page119_i174" )
			)
			( gate "Q9A2"
				( objectStatus "@baseboard_fab2_lib.baseboard_fab2(sch_1):page119_i175" )
			)
			( gate "R9A20"
				( objectStatus "@baseboard_fab2_lib.baseboard_fab2(sch_1):page119_i178" )
			)
			( gate "DS9A5"
				( objectStatus "@baseboard_fab2_lib.baseboard_fab2(sch_1):page119_i179" )
			)
			( gate "Q9A2"
				( objectStatus "@baseboard_fab2_lib.baseboard_fab2(sch_1):page119_i180" )
			)
			( gate "R9A18"
				( objectStatus "@baseboard_fab2_lib.baseboard_fab2(sch_1):page119_i183" )
			)
			( gate "R9A21"
				( objectStatus "@baseboard_fab2_lib.baseboard_fab2(sch_1):page119_i186" )
			)
			( gate "R7C26"
				( objectStatus "@baseboard_fab2_lib.baseboard_fab2(sch_1):page119_i189" )
			)
			( gate "R2U48"
				( objectStatus "@baseboard_fab2_lib.baseboard_fab2(sch_1):page119_i213" )
			)
			( gate "R7W17"
				( objectStatus "@baseboard_fab2_lib.baseboard_fab2(sch_1):page119_i229" )
			)
			( gate "U7C1"
				( objectStatus "@baseboard_fab2_lib.baseboard_fab2(sch_1):page120_i147" )
			)
			( gate "R7W16"
				( objectStatus "@baseboard_fab2_lib.baseboard_fab2(sch_1):page120_i276" )
			)
			( gate "R2M1"
				( objectStatus "@baseboard_fab2_lib.baseboard_fab2(sch_1):page120_i218" )
			)
			( gate "R2N26"
				( objectStatus "@baseboard_fab2_lib.baseboard_fab2(sch_1):page120_i219" )
			)
			( gate "R7C15"
				( objectStatus "@baseboard_fab2_lib.baseboard_fab2(sch_1):page121_i31" )
			)
			( gate "R7C16"
				( objectStatus "@baseboard_fab2_lib.baseboard_fab2(sch_1):page121_i33" )
			)
			( gate "U7C1"
				( objectStatus "@baseboard_fab2_lib.baseboard_fab2(sch_1):page121_i34" )
			)
			( gate "R8C26"
				( objectStatus "@baseboard_fab2_lib.baseboard_fab2(sch_1):page121_i35" )
			)
			( gate "R3N10"
				( objectStatus "@baseboard_fab2_lib.baseboard_fab2(sch_1):page121_i37" )
			)
			( gate "R7C20"
				( objectStatus "@baseboard_fab2_lib.baseboard_fab2(sch_1):page121_i73" )
			)
			( gate "R3P3"
				( objectStatus "@baseboard_fab2_lib.baseboard_fab2(sch_1):page121_i89" )
			)
			( gate "R3P2"
				( objectStatus "@baseboard_fab2_lib.baseboard_fab2(sch_1):page121_i90" )
			)
			( gate "R2P1"
				( objectStatus "@baseboard_fab2_lib.baseboard_fab2(sch_1):page121_i91" )
			)
			( gate "R7C14"
				( objectStatus "@baseboard_fab2_lib.baseboard_fab2(sch_1):page121_i98" )
			)
			( gate "R8D11"
				( objectStatus "@baseboard_fab2_lib.baseboard_fab2(sch_1):page121_i101" )
			)
			( gate "U7C1"
				( objectStatus "@baseboard_fab2_lib.baseboard_fab2(sch_1):page122_i63" )
			)
			( gate "U7C1"
				( objectStatus "@baseboard_fab2_lib.baseboard_fab2(sch_1):page123_i13" )
			)
			( gate "U7C1"
				( objectStatus "@baseboard_fab2_lib.baseboard_fab2(sch_1):page123_i21" )
			)
			( gate "U7C1"
				( objectStatus "@baseboard_fab2_lib.baseboard_fab2(sch_1):page124_i15" )
			)
			( gate "U7C1"
				( objectStatus "@baseboard_fab2_lib.baseboard_fab2(sch_1):page124_i16" )
			)
			( gate "U7C1"
				( objectStatus "@baseboard_fab2_lib.baseboard_fab2(sch_1):page124_i17" )
			)
			( gate "R2R11"
				( objectStatus "@baseboard_fab2_lib.baseboard_fab2(sch_1):page125_i11" )
			)
			( gate "R8E6"
				( objectStatus "@baseboard_fab2_lib.baseboard_fab2(sch_1):page125_i21" )
			)
			( gate "R8E4"
				( objectStatus "@baseboard_fab2_lib.baseboard_fab2(sch_1):page125_i24" )
			)
			( gate "R8C18"
				( objectStatus "@baseboard_fab2_lib.baseboard_fab2(sch_1):page125_i40" )
			)
			( gate "R8C17"
				( objectStatus "@baseboard_fab2_lib.baseboard_fab2(sch_1):page125_i41" )
			)
			( gate "R8D5"
				( objectStatus "@baseboard_fab2_lib.baseboard_fab2(sch_1):page125_i50" )
			)
			( gate "R7D13"
				( objectStatus "@baseboard_fab2_lib.baseboard_fab2(sch_1):page125_i60" )
			)
			( gate "R25W141"
				( objectStatus "@baseboard_fab2_lib.baseboard_fab2(sch_1):page145_i160" )
			)
			( gate "R3N2"
				( objectStatus "@baseboard_fab2_lib.baseboard_fab2(sch_1):page125_i72" )
			)
			( gate "R3N17"
				( objectStatus "@baseboard_fab2_lib.baseboard_fab2(sch_1):page125_i78" )
			)
			( gate "R2N14"
				( objectStatus "@baseboard_fab2_lib.baseboard_fab2(sch_1):page125_i83" )
			)
			( gate "R7D19"
				( objectStatus "@baseboard_fab2_lib.baseboard_fab2(sch_1):page126_i6" )
			)
			( gate "R12W20"
				( objectStatus "@baseboard_fab2_lib.baseboard_fab2(sch_1):page197_i110" )
			)
			( gate "R1D35"
				( objectStatus "@baseboard_fab2_lib.baseboard_fab2(sch_1):page126_i12" )
			)
			( gate "Q8E2"
				( objectStatus "@baseboard_fab2_lib.baseboard_fab2(sch_1):page126_i13" )
			)
			( gate "R8C9"
				( objectStatus "@baseboard_fab2_lib.baseboard_fab2(sch_1):page126_i20" )
			)
			( gate "R3P62"
				( objectStatus "@baseboard_fab2_lib.baseboard_fab2(sch_1):page126_i22" )
			)
			( gate "R3P64"
				( objectStatus "@baseboard_fab2_lib.baseboard_fab2(sch_1):page126_i23" )
			)
			( gate "FB3M1"
				( objectStatus "@baseboard_fab2_lib.baseboard_fab2(sch_1):page127_i8" )
			)
			( gate "C3M21"
				( objectStatus "@baseboard_fab2_lib.baseboard_fab2(sch_1):page127_i9" )
			)
			( gate "FB3M2"
				( objectStatus "@baseboard_fab2_lib.baseboard_fab2(sch_1):page127_i17" )
			)
			( gate "C3M22"
				( objectStatus "@baseboard_fab2_lib.baseboard_fab2(sch_1):page127_i18" )
			)
			( gate "FB3M3"
				( objectStatus "@baseboard_fab2_lib.baseboard_fab2(sch_1):page127_i26" )
			)
			( gate "C3M30"
				( objectStatus "@baseboard_fab2_lib.baseboard_fab2(sch_1):page127_i27" )
			)
			( gate "C2M5"
				( objectStatus "@baseboard_fab2_lib.baseboard_fab2(sch_1):page127_i43" )
			)
			( gate "C2M7"
				( objectStatus "@baseboard_fab2_lib.baseboard_fab2(sch_1):page127_i44" )
			)
			( gate "FB2M1"
				( objectStatus "@baseboard_fab2_lib.baseboard_fab2(sch_1):page127_i46" )
			)
			( gate "C2M10"
				( objectStatus "@baseboard_fab2_lib.baseboard_fab2(sch_1):page127_i49" )
			)
			( gate "C2M9"
				( objectStatus "@baseboard_fab2_lib.baseboard_fab2(sch_1):page127_i50" )
			)
			( gate "FB3M4"
				( objectStatus "@baseboard_fab2_lib.baseboard_fab2(sch_1):page127_i56" )
			)
			( gate "C3M31"
				( objectStatus "@baseboard_fab2_lib.baseboard_fab2(sch_1):page127_i57" )
			)
			( gate "C2N6"
				( objectStatus "@baseboard_fab2_lib.baseboard_fab2(sch_1):page127_i64" )
			)
			( gate "C2N5"
				( objectStatus "@baseboard_fab2_lib.baseboard_fab2(sch_1):page127_i65" )
			)
			( gate "FB2M2"
				( objectStatus "@baseboard_fab2_lib.baseboard_fab2(sch_1):page127_i69" )
			)
			( gate "L2M1"
				( objectStatus "@baseboard_fab2_lib.baseboard_fab2(sch_1):page127_i71" )
			)
			( gate "C2M8"
				( objectStatus "@baseboard_fab2_lib.baseboard_fab2(sch_1):page127_i74" )
			)
			( gate "C2M6"
				( objectStatus "@baseboard_fab2_lib.baseboard_fab2(sch_1):page127_i76" )
			)
			( gate "C2M25"
				( objectStatus "@baseboard_fab2_lib.baseboard_fab2(sch_1):page127_i78" )
			)
			( gate "C3M29"
				( objectStatus "@baseboard_fab2_lib.baseboard_fab2(sch_1):page127_i80" )
			)
			( gate "C3M24"
				( objectStatus "@baseboard_fab2_lib.baseboard_fab2(sch_1):page127_i81" )
			)
			( gate "C3M23"
				( objectStatus "@baseboard_fab2_lib.baseboard_fab2(sch_1):page127_i82" )
			)
			( gate "C3M27"
				( objectStatus "@baseboard_fab2_lib.baseboard_fab2(sch_1):page127_i83" )
			)
			( gate "C3M20"
				( objectStatus "@baseboard_fab2_lib.baseboard_fab2(sch_1):page127_i84" )
			)
			( gate "C3M18"
				( objectStatus "@baseboard_fab2_lib.baseboard_fab2(sch_1):page127_i85" )
			)
			( gate "C3M17"
				( objectStatus "@baseboard_fab2_lib.baseboard_fab2(sch_1):page127_i86" )
			)
			( gate "C3M19"
				( objectStatus "@baseboard_fab2_lib.baseboard_fab2(sch_1):page127_i87" )
			)
			( gate "C7B25"
				( objectStatus "@baseboard_fab2_lib.baseboard_fab2(sch_1):page129_i35" )
			)
			( gate "C7B27"
				( objectStatus "@baseboard_fab2_lib.baseboard_fab2(sch_1):page129_i69" )
			)
			( gate "C7B28"
				( objectStatus "@baseboard_fab2_lib.baseboard_fab2(sch_1):page129_i70" )
			)
			( gate "C7C2"
				( objectStatus "@baseboard_fab2_lib.baseboard_fab2(sch_1):page129_i71" )
			)
			( gate "C3M40"
				( objectStatus "@baseboard_fab2_lib.baseboard_fab2(sch_1):page129_i72" )
			)
			( gate "C3M37"
				( objectStatus "@baseboard_fab2_lib.baseboard_fab2(sch_1):page129_i73" )
			)
			( gate "C3N9"
				( objectStatus "@baseboard_fab2_lib.baseboard_fab2(sch_1):page129_i74" )
			)
			( gate "C3N8"
				( objectStatus "@baseboard_fab2_lib.baseboard_fab2(sch_1):page129_i75" )
			)
			( gate "C7C3"
				( objectStatus "@baseboard_fab2_lib.baseboard_fab2(sch_1):page129_i76" )
			)
			( gate "C7C1"
				( objectStatus "@baseboard_fab2_lib.baseboard_fab2(sch_1):page129_i77" )
			)
			( gate "C7B29"
				( objectStatus "@baseboard_fab2_lib.baseboard_fab2(sch_1):page129_i78" )
			)
			( gate "C7B26"
				( objectStatus "@baseboard_fab2_lib.baseboard_fab2(sch_1):page129_i79" )
			)
			( gate "C3M44"
				( objectStatus "@baseboard_fab2_lib.baseboard_fab2(sch_1):page129_i80" )
			)
			( gate "C3M41"
				( objectStatus "@baseboard_fab2_lib.baseboard_fab2(sch_1):page129_i81" )
			)
			( gate "C3M45"
				( objectStatus "@baseboard_fab2_lib.baseboard_fab2(sch_1):page129_i82" )
			)
			( gate "C3N13"
				( objectStatus "@baseboard_fab2_lib.baseboard_fab2(sch_1):page129_i83" )
			)
			( gate "C7D2"
				( objectStatus "@baseboard_fab2_lib.baseboard_fab2(sch_1):page130_i2" )
			)
			( gate "C2N26"
				( objectStatus "@baseboard_fab2_lib.baseboard_fab2(sch_1):page130_i4" )
			)
			( gate "C2N19"
				( objectStatus "@baseboard_fab2_lib.baseboard_fab2(sch_1):page130_i7" )
			)
			( gate "C2N24"
				( objectStatus "@baseboard_fab2_lib.baseboard_fab2(sch_1):page130_i8" )
			)
			( gate "C2N22"
				( objectStatus "@baseboard_fab2_lib.baseboard_fab2(sch_1):page130_i9" )
			)
			( gate "C2N20"
				( objectStatus "@baseboard_fab2_lib.baseboard_fab2(sch_1):page130_i12" )
			)
			( gate "C2N21"
				( objectStatus "@baseboard_fab2_lib.baseboard_fab2(sch_1):page130_i15" )
			)
			( gate "C3N29"
				( objectStatus "@baseboard_fab2_lib.baseboard_fab2(sch_1):page130_i16" )
			)
			( gate "C8C3"
				( objectStatus "@baseboard_fab2_lib.baseboard_fab2(sch_1):page130_i19" )
			)
			( gate "C8C4"
				( objectStatus "@baseboard_fab2_lib.baseboard_fab2(sch_1):page130_i20" )
			)
			( gate "C8C5"
				( objectStatus "@baseboard_fab2_lib.baseboard_fab2(sch_1):page130_i21" )
			)
			( gate "C8C6"
				( objectStatus "@baseboard_fab2_lib.baseboard_fab2(sch_1):page130_i22" )
			)
			( gate "C2N23"
				( objectStatus "@baseboard_fab2_lib.baseboard_fab2(sch_1):page130_i24" )
			)
			( gate "C2N14"
				( objectStatus "@baseboard_fab2_lib.baseboard_fab2(sch_1):page130_i25" )
			)
			( gate "C2N17"
				( objectStatus "@baseboard_fab2_lib.baseboard_fab2(sch_1):page130_i28" )
			)
			( gate "C2N18"
				( objectStatus "@baseboard_fab2_lib.baseboard_fab2(sch_1):page130_i29" )
			)
			( gate "C8B2"
				( objectStatus "@baseboard_fab2_lib.baseboard_fab2(sch_1):page130_i30" )
			)
			( gate "C8B3"
				( objectStatus "@baseboard_fab2_lib.baseboard_fab2(sch_1):page130_i32" )
			)
			( gate "C2N25"
				( objectStatus "@baseboard_fab2_lib.baseboard_fab2(sch_1):page130_i34" )
			)
			( gate "C2M16"
				( objectStatus "@baseboard_fab2_lib.baseboard_fab2(sch_1):page130_i37" )
			)
			( gate "C7D3"
				( objectStatus "@baseboard_fab2_lib.baseboard_fab2(sch_1):page130_i38" )
			)
			( gate "C8B4"
				( objectStatus "@baseboard_fab2_lib.baseboard_fab2(sch_1):page130_i39" )
			)
			( gate "C8B1"
				( objectStatus "@baseboard_fab2_lib.baseboard_fab2(sch_1):page130_i41" )
			)
			( gate "C3N23"
				( objectStatus "@baseboard_fab2_lib.baseboard_fab2(sch_1):page130_i42" )
			)
			( gate "C2M1"
				( objectStatus "@baseboard_fab2_lib.baseboard_fab2(sch_1):page130_i43" )
			)
			( gate "C2M2"
				( objectStatus "@baseboard_fab2_lib.baseboard_fab2(sch_1):page130_i45" )
			)
			( gate "C2N15"
				( objectStatus "@baseboard_fab2_lib.baseboard_fab2(sch_1):page130_i47" )
			)
			( gate "C3N21"
				( objectStatus "@baseboard_fab2_lib.baseboard_fab2(sch_1):page130_i49" )
			)
			( gate "C3N25"
				( objectStatus "@baseboard_fab2_lib.baseboard_fab2(sch_1):page130_i50" )
			)
			( gate "C2N16"
				( objectStatus "@baseboard_fab2_lib.baseboard_fab2(sch_1):page130_i52" )
			)
			( gate "C3N22"
				( objectStatus "@baseboard_fab2_lib.baseboard_fab2(sch_1):page130_i53" )
			)
			( gate "C7B15"
				( objectStatus "@baseboard_fab2_lib.baseboard_fab2(sch_1):page131_i1" )
			)
			( gate "C7B19"
				( objectStatus "@baseboard_fab2_lib.baseboard_fab2(sch_1):page131_i2" )
			)
			( gate "C7B16"
				( objectStatus "@baseboard_fab2_lib.baseboard_fab2(sch_1):page131_i3" )
			)
			( gate "C7B21"
				( objectStatus "@baseboard_fab2_lib.baseboard_fab2(sch_1):page131_i4" )
			)
			( gate "C7B20"
				( objectStatus "@baseboard_fab2_lib.baseboard_fab2(sch_1):page131_i6" )
			)
			( gate "C7B23"
				( objectStatus "@baseboard_fab2_lib.baseboard_fab2(sch_1):page131_i7" )
			)
			( gate "C8B10"
				( objectStatus "@baseboard_fab2_lib.baseboard_fab2(sch_1):page131_i8" )
			)
			( gate "C7B22"
				( objectStatus "@baseboard_fab2_lib.baseboard_fab2(sch_1):page131_i10" )
			)
			( gate "C7B24"
				( objectStatus "@baseboard_fab2_lib.baseboard_fab2(sch_1):page131_i11" )
			)
			( gate "C7B18"
				( objectStatus "@baseboard_fab2_lib.baseboard_fab2(sch_1):page131_i12" )
			)
			( gate "C8B9"
				( objectStatus "@baseboard_fab2_lib.baseboard_fab2(sch_1):page131_i14" )
			)
			( gate "C8B11"
				( objectStatus "@baseboard_fab2_lib.baseboard_fab2(sch_1):page131_i15" )
			)
			( gate "C8B14"
				( objectStatus "@baseboard_fab2_lib.baseboard_fab2(sch_1):page131_i16" )
			)
			( gate "C7B17"
				( objectStatus "@baseboard_fab2_lib.baseboard_fab2(sch_1):page131_i18" )
			)
			( gate "C8B13"
				( objectStatus "@baseboard_fab2_lib.baseboard_fab2(sch_1):page131_i20" )
			)
			( gate "C8B16"
				( objectStatus "@baseboard_fab2_lib.baseboard_fab2(sch_1):page131_i22" )
			)
			( gate "C8B15"
				( objectStatus "@baseboard_fab2_lib.baseboard_fab2(sch_1):page131_i24" )
			)
			( gate "C2M22"
				( objectStatus "@baseboard_fab2_lib.baseboard_fab2(sch_1):page131_i27" )
			)
			( gate "C2M21"
				( objectStatus "@baseboard_fab2_lib.baseboard_fab2(sch_1):page131_i28" )
			)
			( gate "C2M18"
				( objectStatus "@baseboard_fab2_lib.baseboard_fab2(sch_1):page131_i29" )
			)
			( gate "C2M19"
				( objectStatus "@baseboard_fab2_lib.baseboard_fab2(sch_1):page131_i31" )
			)
			( gate "C3M38"
				( objectStatus "@baseboard_fab2_lib.baseboard_fab2(sch_1):page131_i32" )
			)
			( gate "C2M17"
				( objectStatus "@baseboard_fab2_lib.baseboard_fab2(sch_1):page131_i34" )
			)
			( gate "C2M11"
				( objectStatus "@baseboard_fab2_lib.baseboard_fab2(sch_1):page131_i35" )
			)
			( gate "C8A13"
				( objectStatus "@baseboard_fab2_lib.baseboard_fab2(sch_1):page131_i37" )
			)
			( gate "C2M20"
				( objectStatus "@baseboard_fab2_lib.baseboard_fab2(sch_1):page131_i39" )
			)
			( gate "C2N13"
				( objectStatus "@baseboard_fab2_lib.baseboard_fab2(sch_1):page131_i40" )
			)
			( gate "C2N2"
				( objectStatus "@baseboard_fab2_lib.baseboard_fab2(sch_1):page131_i41" )
			)
			( gate "C3M43"
				( objectStatus "@baseboard_fab2_lib.baseboard_fab2(sch_1):page131_i42" )
			)
			( gate "C2N7"
				( objectStatus "@baseboard_fab2_lib.baseboard_fab2(sch_1):page131_i43" )
			)
			( gate "C3M39"
				( objectStatus "@baseboard_fab2_lib.baseboard_fab2(sch_1):page131_i44" )
			)
			( gate "C3M42"
				( objectStatus "@baseboard_fab2_lib.baseboard_fab2(sch_1):page131_i45" )
			)
			( gate "C2N8"
				( objectStatus "@baseboard_fab2_lib.baseboard_fab2(sch_1):page131_i47" )
			)
			( gate "C2M13"
				( objectStatus "@baseboard_fab2_lib.baseboard_fab2(sch_1):page131_i48" )
			)
			( gate "C2N10"
				( objectStatus "@baseboard_fab2_lib.baseboard_fab2(sch_1):page131_i50" )
			)
			( gate "C2M12"
				( objectStatus "@baseboard_fab2_lib.baseboard_fab2(sch_1):page131_i52" )
			)
			( gate "C3L25"
				( objectStatus "@baseboard_fab2_lib.baseboard_fab2(sch_1):page132_i1" )
			)
			( gate "C3M7"
				( objectStatus "@baseboard_fab2_lib.baseboard_fab2(sch_1):page132_i2" )
			)
			( gate "C3L26"
				( objectStatus "@baseboard_fab2_lib.baseboard_fab2(sch_1):page132_i3" )
			)
			( gate "C3L27"
				( objectStatus "@baseboard_fab2_lib.baseboard_fab2(sch_1):page132_i4" )
			)
			( gate "C3M6"
				( objectStatus "@baseboard_fab2_lib.baseboard_fab2(sch_1):page132_i6" )
			)
			( gate "C7C9"
				( objectStatus "@baseboard_fab2_lib.baseboard_fab2(sch_1):page132_i7" )
			)
			( gate "C3N27"
				( objectStatus "@baseboard_fab2_lib.baseboard_fab2(sch_1):page132_i8" )
			)
			( gate "C3N30"
				( objectStatus "@baseboard_fab2_lib.baseboard_fab2(sch_1):page132_i9" )
			)
			( gate "C7A36"
				( objectStatus "@baseboard_fab2_lib.baseboard_fab2(sch_1):page132_i11" )
			)
			( gate "C3N12"
				( objectStatus "@baseboard_fab2_lib.baseboard_fab2(sch_1):page132_i12" )
			)
			( gate "C3N10"
				( objectStatus "@baseboard_fab2_lib.baseboard_fab2(sch_1):page132_i13" )
			)
			( gate "C3N24"
				( objectStatus "@baseboard_fab2_lib.baseboard_fab2(sch_1):page132_i16" )
			)
			( gate "C3N28"
				( objectStatus "@baseboard_fab2_lib.baseboard_fab2(sch_1):page132_i17" )
			)
			( gate "C3N11"
				( objectStatus "@baseboard_fab2_lib.baseboard_fab2(sch_1):page132_i19" )
			)
			( gate "C3N31"
				( objectStatus "@baseboard_fab2_lib.baseboard_fab2(sch_1):page132_i20" )
			)
			( gate "C7A33"
				( objectStatus "@baseboard_fab2_lib.baseboard_fab2(sch_1):page132_i23" )
			)
			( gate "C7B4"
				( objectStatus "@baseboard_fab2_lib.baseboard_fab2(sch_1):page132_i24" )
			)
			( gate "C2N9"
				( objectStatus "@baseboard_fab2_lib.baseboard_fab2(sch_1):page132_i26" )
			)
			( gate "C2N3"
				( objectStatus "@baseboard_fab2_lib.baseboard_fab2(sch_1):page132_i27" )
			)
			( gate "C2N4"
				( objectStatus "@baseboard_fab2_lib.baseboard_fab2(sch_1):page132_i28" )
			)
			( gate "C2N12"
				( objectStatus "@baseboard_fab2_lib.baseboard_fab2(sch_1):page132_i29" )
			)
			( gate "C2N11"
				( objectStatus "@baseboard_fab2_lib.baseboard_fab2(sch_1):page132_i30" )
			)
			( gate "C3N19"
				( objectStatus "@baseboard_fab2_lib.baseboard_fab2(sch_1):page132_i31" )
			)
			( gate "C3N3"
				( objectStatus "@baseboard_fab2_lib.baseboard_fab2(sch_1):page132_i32" )
			)
			( gate "C3N1"
				( objectStatus "@baseboard_fab2_lib.baseboard_fab2(sch_1):page132_i34" )
			)
			( gate "C3N7"
				( objectStatus "@baseboard_fab2_lib.baseboard_fab2(sch_1):page132_i35" )
			)
			( gate "C3N16"
				( objectStatus "@baseboard_fab2_lib.baseboard_fab2(sch_1):page132_i36" )
			)
			( gate "C7A32"
				( objectStatus "@baseboard_fab2_lib.baseboard_fab2(sch_1):page132_i38" )
			)
			( gate "C7A31"
				( objectStatus "@baseboard_fab2_lib.baseboard_fab2(sch_1):page132_i40" )
			)
			( gate "C3N18"
				( objectStatus "@baseboard_fab2_lib.baseboard_fab2(sch_1):page132_i42" )
			)
			( gate "C3N2"
				( objectStatus "@baseboard_fab2_lib.baseboard_fab2(sch_1):page132_i43" )
			)
			( gate "C3N6"
				( objectStatus "@baseboard_fab2_lib.baseboard_fab2(sch_1):page132_i44" )
			)
			( gate "C3N17"
				( objectStatus "@baseboard_fab2_lib.baseboard_fab2(sch_1):page132_i45" )
			)
			( gate "C3N4"
				( objectStatus "@baseboard_fab2_lib.baseboard_fab2(sch_1):page132_i46" )
			)
			( gate "C3N5"
				( objectStatus "@baseboard_fab2_lib.baseboard_fab2(sch_1):page132_i48" )
			)
			( gate "C3N15"
				( objectStatus "@baseboard_fab2_lib.baseboard_fab2(sch_1):page132_i49" )
			)
			( gate "C3N20"
				( objectStatus "@baseboard_fab2_lib.baseboard_fab2(sch_1):page132_i51" )
			)
			( gate "C3L23"
				( objectStatus "@baseboard_fab2_lib.baseboard_fab2(sch_1):page132_i52" )
			)
			( gate "C3L22"
				( objectStatus "@baseboard_fab2_lib.baseboard_fab2(sch_1):page132_i54" )
			)
			( gate "C3L24"
				( objectStatus "@baseboard_fab2_lib.baseboard_fab2(sch_1):page132_i56" )
			)
			( gate "R3N3"
				( objectStatus "@baseboard_fab2_lib.baseboard_fab2(sch_1):page133_i120" )
			)
			( gate "R2N12"
				( objectStatus "@baseboard_fab2_lib.baseboard_fab2(sch_1):page133_i122" )
			)
			( gate "R7D8"
				( objectStatus "@baseboard_fab2_lib.baseboard_fab2(sch_1):page133_i200" )
			)
			( gate "R7D10"
				( objectStatus "@baseboard_fab2_lib.baseboard_fab2(sch_1):page133_i202" )
			)
			( gate "R7D12"
				( objectStatus "@baseboard_fab2_lib.baseboard_fab2(sch_1):page133_i237" )
			)
			( gate "R7D3"
				( objectStatus "@baseboard_fab2_lib.baseboard_fab2(sch_1):page133_i243" )
			)
			( gate "R7D4"
				( objectStatus "@baseboard_fab2_lib.baseboard_fab2(sch_1):page133_i245" )
			)
			( gate "R2N16"
				( objectStatus "@baseboard_fab2_lib.baseboard_fab2(sch_1):page133_i247" )
			)
			( gate "R2R5"
				( objectStatus "@baseboard_fab2_lib.baseboard_fab2(sch_1):page133_i258" )
			)
			( gate "R2N9"
				( objectStatus "@baseboard_fab2_lib.baseboard_fab2(sch_1):page133_i267" )
			)
			( gate "R8B23"
				( objectStatus "@baseboard_fab2_lib.baseboard_fab2(sch_1):page133_i280" )
			)
			( gate "R8B30"
				( objectStatus "@baseboard_fab2_lib.baseboard_fab2(sch_1):page133_i282" )
			)
			( gate "R2M4"
				( objectStatus "@baseboard_fab2_lib.baseboard_fab2(sch_1):page133_i284" )
			)
			( gate "R8C4"
				( objectStatus "@baseboard_fab2_lib.baseboard_fab2(sch_1):page133_i286" )
			)
			( gate "R7B6"
				( objectStatus "@baseboard_fab2_lib.baseboard_fab2(sch_1):page133_i295" )
			)
			( gate "R7C8"
				( objectStatus "@baseboard_fab2_lib.baseboard_fab2(sch_1):page133_i296" )
			)
			( gate "R7C5"
				( objectStatus "@baseboard_fab2_lib.baseboard_fab2(sch_1):page133_i297" )
			)
			( gate "R8D14"
				( objectStatus "@baseboard_fab2_lib.baseboard_fab2(sch_1):page133_i301" )
			)
			( gate "R8C6"
				( objectStatus "@baseboard_fab2_lib.baseboard_fab2(sch_1):page133_i303" )
			)
			( gate "R8C2"
				( objectStatus "@baseboard_fab2_lib.baseboard_fab2(sch_1):page133_i304" )
			)
			( gate "R7D6"
				( objectStatus "@baseboard_fab2_lib.baseboard_fab2(sch_1):page133_i306" )
			)
			( gate "R8B31"
				( objectStatus "@baseboard_fab2_lib.baseboard_fab2(sch_1):page133_i307" )
			)
			( gate "R2N7"
				( objectStatus "@baseboard_fab2_lib.baseboard_fab2(sch_1):page133_i309" )
			)
			( gate "R3P8"
				( objectStatus "@baseboard_fab2_lib.baseboard_fab2(sch_1):page133_i322" )
			)
			( gate "R8C1"
				( objectStatus "@baseboard_fab2_lib.baseboard_fab2(sch_1):page133_i326" )
			)
			( gate "R8C7"
				( objectStatus "@baseboard_fab2_lib.baseboard_fab2(sch_1):page133_i327" )
			)
			( gate "R7D7"
				( objectStatus "@baseboard_fab2_lib.baseboard_fab2(sch_1):page133_i331" )
			)
			( gate "R7D2"
				( objectStatus "@baseboard_fab2_lib.baseboard_fab2(sch_1):page133_i332" )
			)
			( gate "R8C25"
				( objectStatus "@baseboard_fab2_lib.baseboard_fab2(sch_1):page133_i333" )
			)
			( gate "R2N32"
				( objectStatus "@baseboard_fab2_lib.baseboard_fab2(sch_1):page133_i341" )
			)
			( gate "R2M8"
				( objectStatus "@baseboard_fab2_lib.baseboard_fab2(sch_1):page133_i349" )
			)
			( gate "R2N29"
				( objectStatus "@baseboard_fab2_lib.baseboard_fab2(sch_1):page133_i352" )
			)
			( gate "C5P29"
				( objectStatus "@baseboard_fab2_lib.baseboard_fab2(sch_1):page42_i220" )
			)
			( gate "R7D44"
				( objectStatus "@baseboard_fab2_lib.baseboard_fab2(sch_1):page133_i356" )
			)
			( gate "R2P22"
				( objectStatus "@baseboard_fab2_lib.baseboard_fab2(sch_1):page133_i360" )
			)
			( gate "R8D44"
				( objectStatus "@baseboard_fab2_lib.baseboard_fab2(sch_1):page133_i362" )
			)
			( gate "R2P17"
				( objectStatus "@baseboard_fab2_lib.baseboard_fab2(sch_1):page134_i3" )
			)
			( gate "Q7E8"
				( objectStatus "@baseboard_fab2_lib.baseboard_fab2(sch_1):page95_i123" )
			)
			( gate "R7C21"
				( objectStatus "@baseboard_fab2_lib.baseboard_fab2(sch_1):page134_i9" )
			)
			( gate "Q7E4"
				( objectStatus "@baseboard_fab2_lib.baseboard_fab2(sch_1):page95_i122" )
			)
			( gate "R7D18"
				( objectStatus "@baseboard_fab2_lib.baseboard_fab2(sch_1):page134_i11" )
			)
			( gate "R2P19"
				( objectStatus "@baseboard_fab2_lib.baseboard_fab2(sch_1):page135_i107" )
			)
			( gate "R2N23"
				( objectStatus "@baseboard_fab2_lib.baseboard_fab2(sch_1):page135_i112" )
			)
			( gate "R2N24"
				( objectStatus "@baseboard_fab2_lib.baseboard_fab2(sch_1):page135_i113" )
			)
			( gate "R9A12"
				( objectStatus "@baseboard_fab2_lib.baseboard_fab2(sch_1):page135_i117" )
			)
			( gate "R9A13"
				( objectStatus "@baseboard_fab2_lib.baseboard_fab2(sch_1):page135_i118" )
			)
			( gate "R8D21"
				( objectStatus "@baseboard_fab2_lib.baseboard_fab2(sch_1):page135_i120" )
			)
			( gate "R7D30"
				( objectStatus "@baseboard_fab2_lib.baseboard_fab2(sch_1):page135_i121" )
			)
			( gate "J8G2"
				( objectStatus "@baseboard_fab2_lib.baseboard_fab2(sch_1):page135_i124" )
			)
			( gate "R9A16"
				( objectStatus "@baseboard_fab2_lib.baseboard_fab2(sch_1):page135_i129" )
			)
			( gate "J9A1"
				( objectStatus "@baseboard_fab2_lib.baseboard_fab2(sch_1):page135_i131" )
			)
			( gate "R7G26"
				( objectStatus "@baseboard_fab2_lib.baseboard_fab2(sch_1):page136_i101" )
			)
			( gate "R7G28"
				( objectStatus "@baseboard_fab2_lib.baseboard_fab2(sch_1):page136_i102" )
			)
			( gate "R8E20"
				( objectStatus "@baseboard_fab2_lib.baseboard_fab2(sch_1):page136_i126" )
			)
			( gate "C8E8"
				( objectStatus "@baseboard_fab2_lib.baseboard_fab2(sch_1):page136_i128" )
			)
			( gate "U8E3"
				( objectStatus "@baseboard_fab2_lib.baseboard_fab2(sch_1):page136_i130" )
			)
			( gate "R8E14"
				( objectStatus "@baseboard_fab2_lib.baseboard_fab2(sch_1):page136_i133" )
			)
			( gate "Q8E1"
				( objectStatus "@baseboard_fab2_lib.baseboard_fab2(sch_1):page136_i134" )
			)
			( gate "R7G31"
				( objectStatus "@baseboard_fab2_lib.baseboard_fab2(sch_1):page136_i139" )
			)
			( gate "R8E16"
				( objectStatus "@baseboard_fab2_lib.baseboard_fab2(sch_1):page136_i140" )
			)
			( gate "R2N28"
				( objectStatus "@baseboard_fab2_lib.baseboard_fab2(sch_1):page136_i147" )
			)
			( gate "R7G29"
				( objectStatus "@baseboard_fab2_lib.baseboard_fab2(sch_1):page136_i148" )
			)
			( gate "R7G27"
				( objectStatus "@baseboard_fab2_lib.baseboard_fab2(sch_1):page136_i155" )
			)
			( gate "R3T14"
				( objectStatus "@baseboard_fab2_lib.baseboard_fab2(sch_1):page136_i156" )
			)
			( gate "J7G3"
				( objectStatus "@baseboard_fab2_lib.baseboard_fab2(sch_1):page136_i174" )
			)
			( gate "R7C11"
				( objectStatus "@baseboard_fab2_lib.baseboard_fab2(sch_1):page137_i11" )
			)
			( gate "R7C10"
				( objectStatus "@baseboard_fab2_lib.baseboard_fab2(sch_1):page137_i13" )
			)
			( gate "C7C19"
				( objectStatus "@baseboard_fab2_lib.baseboard_fab2(sch_1):page137_i14" )
			)
			( gate "R1U63"
				( objectStatus "@baseboard_fab2_lib.baseboard_fab2(sch_1):page137_i15" )
			)
			( gate "R3N4"
				( objectStatus "@baseboard_fab2_lib.baseboard_fab2(sch_1):page137_i19" )
			)
			( gate "C3N32"
				( objectStatus "@baseboard_fab2_lib.baseboard_fab2(sch_1):page137_i20" )
			)
			( gate "R7C13"
				( objectStatus "@baseboard_fab2_lib.baseboard_fab2(sch_1):page137_i67" )
			)
			( gate "R1U64"
				( objectStatus "@baseboard_fab2_lib.baseboard_fab2(sch_1):page137_i69" )
			)
			( gate "J9G1"
				( objectStatus "@baseboard_fab2_lib.baseboard_fab2(sch_1):page137_i128" )
			)
			( gate "R2T53"
				( objectStatus "@baseboard_fab2_lib.baseboard_fab2(sch_1):page138_i83" )
			)
			( gate "R2T54"
				( objectStatus "@baseboard_fab2_lib.baseboard_fab2(sch_1):page138_i84" )
			)
			( gate "R8D17"
				( objectStatus "@baseboard_fab2_lib.baseboard_fab2(sch_1):page138_i87" )
			)
			( gate "R8D15"
				( objectStatus "@baseboard_fab2_lib.baseboard_fab2(sch_1):page138_i88" )
			)
			( gate "R2N8"
				( objectStatus "@baseboard_fab2_lib.baseboard_fab2(sch_1):page138_i89" )
			)
			( gate "R2N5"
				( objectStatus "@baseboard_fab2_lib.baseboard_fab2(sch_1):page138_i90" )
			)
			( gate "R2U11"
				( objectStatus "@baseboard_fab2_lib.baseboard_fab2(sch_1):page138_i97" )
			)
			( gate "R2U3"
				( objectStatus "@baseboard_fab2_lib.baseboard_fab2(sch_1):page138_i98" )
			)
			( gate "R2U8"
				( objectStatus "@baseboard_fab2_lib.baseboard_fab2(sch_1):page138_i158" )
			)
			( gate "R2U12"
				( objectStatus "@baseboard_fab2_lib.baseboard_fab2(sch_1):page138_i159" )
			)
			( gate "C6W4"
				( objectStatus "@baseboard_fab2_lib.baseboard_fab2(sch_1):page247_i105" )
			)
			( gate "R8D7"
				( objectStatus "@baseboard_fab2_lib.baseboard_fab2(sch_1):page138_i163" )
			)
			( gate "R8D4"
				( objectStatus "@baseboard_fab2_lib.baseboard_fab2(sch_1):page138_i164" )
			)
			( gate "R2U9"
				( objectStatus "@baseboard_fab2_lib.baseboard_fab2(sch_1):page138_i165" )
			)
			( gate "R2U6"
				( objectStatus "@baseboard_fab2_lib.baseboard_fab2(sch_1):page138_i166" )
			)
			( gate "R8C20"
				( objectStatus "@baseboard_fab2_lib.baseboard_fab2(sch_1):page138_i167" )
			)
			( gate "R8C14"
				( objectStatus "@baseboard_fab2_lib.baseboard_fab2(sch_1):page138_i168" )
			)
			( gate "R8C11"
				( objectStatus "@baseboard_fab2_lib.baseboard_fab2(sch_1):page138_i169" )
			)
			( gate "R8C12"
				( objectStatus "@baseboard_fab2_lib.baseboard_fab2(sch_1):page138_i170" )
			)
			( gate "R2N20"
				( objectStatus "@baseboard_fab2_lib.baseboard_fab2(sch_1):page138_i171" )
			)
			( gate "R2N21"
				( objectStatus "@baseboard_fab2_lib.baseboard_fab2(sch_1):page138_i175" )
			)
			( gate "EU9E1"
				( objectStatus "@baseboard_fab2_lib.baseboard_fab2(sch_1):page139_i72" )
			)
			( gate "C9E7"
				( objectStatus "@baseboard_fab2_lib.baseboard_fab2(sch_1):page139_i76" )
			)
			( gate "C9E5"
				( objectStatus "@baseboard_fab2_lib.baseboard_fab2(sch_1):page139_i87" )
			)
			( gate "C9E4"
				( objectStatus "@baseboard_fab2_lib.baseboard_fab2(sch_1):page139_i88" )
			)
			( gate "C2M23"
				( objectStatus "@baseboard_fab2_lib.baseboard_fab2(sch_1):page139_i89" )
			)
			( gate "C2M24"
				( objectStatus "@baseboard_fab2_lib.baseboard_fab2(sch_1):page139_i90" )
			)
			( gate "Y9E1"
				( objectStatus "@baseboard_fab2_lib.baseboard_fab2(sch_1):page139_i109" )
			)
			( gate "R9E20"
				( objectStatus "@baseboard_fab2_lib.baseboard_fab2(sch_1):page139_i110" )
			)
			( gate "C32W5"
				( objectStatus "@baseboard_fab2_lib.baseboard_fab2(sch_1):page185_i217" )
			)
			( gate "R9E9"
				( objectStatus "@baseboard_fab2_lib.baseboard_fab2(sch_1):page139_i128" )
			)
			( gate "R9E5"
				( objectStatus "@baseboard_fab2_lib.baseboard_fab2(sch_1):page139_i129" )
			)
			( gate "R9E8"
				( objectStatus "@baseboard_fab2_lib.baseboard_fab2(sch_1):page139_i130" )
			)
			( gate "C1T4"
				( objectStatus "@baseboard_fab2_lib.baseboard_fab2(sch_1):page139_i134" )
			)
			( gate "C1R30"
				( objectStatus "@baseboard_fab2_lib.baseboard_fab2(sch_1):page139_i135" )
			)
			( gate "C1R22"
				( objectStatus "@baseboard_fab2_lib.baseboard_fab2(sch_1):page139_i136" )
			)
			( gate "C1R13"
				( objectStatus "@baseboard_fab2_lib.baseboard_fab2(sch_1):page139_i142" )
			)
			( gate "C1R20"
				( objectStatus "@baseboard_fab2_lib.baseboard_fab2(sch_1):page139_i143" )
			)
			( gate "C1T3"
				( objectStatus "@baseboard_fab2_lib.baseboard_fab2(sch_1):page139_i144" )
			)
			( gate "C1R14"
				( objectStatus "@baseboard_fab2_lib.baseboard_fab2(sch_1):page139_i145" )
			)
			( gate "C1R21"
				( objectStatus "@baseboard_fab2_lib.baseboard_fab2(sch_1):page139_i146" )
			)
			( gate "C1R26"
				( objectStatus "@baseboard_fab2_lib.baseboard_fab2(sch_1):page139_i149" )
			)
			( gate "C1R29"
				( objectStatus "@baseboard_fab2_lib.baseboard_fab2(sch_1):page139_i150" )
			)
			( gate "C1R19"
				( objectStatus "@baseboard_fab2_lib.baseboard_fab2(sch_1):page139_i151" )
			)
			( gate "C1R31"
				( objectStatus "@baseboard_fab2_lib.baseboard_fab2(sch_1):page139_i152" )
			)
			( gate "C1R17"
				( objectStatus "@baseboard_fab2_lib.baseboard_fab2(sch_1):page139_i153" )
			)
			( gate "C1R18"
				( objectStatus "@baseboard_fab2_lib.baseboard_fab2(sch_1):page139_i157" )
			)
			( gate "C1T5"
				( objectStatus "@baseboard_fab2_lib.baseboard_fab2(sch_1):page139_i158" )
			)
			( gate "C1R24"
				( objectStatus "@baseboard_fab2_lib.baseboard_fab2(sch_1):page139_i159" )
			)
			( gate "C1R15"
				( objectStatus "@baseboard_fab2_lib.baseboard_fab2(sch_1):page139_i160" )
			)
			( gate "C1R16"
				( objectStatus "@baseboard_fab2_lib.baseboard_fab2(sch_1):page139_i161" )
			)
			( gate "C9E1"
				( objectStatus "@baseboard_fab2_lib.baseboard_fab2(sch_1):page139_i163" )
			)
			( gate "R9F5"
				( objectStatus "@baseboard_fab2_lib.baseboard_fab2(sch_1):page139_i173" )
			)
			( gate "R9E23"
				( objectStatus "@baseboard_fab2_lib.baseboard_fab2(sch_1):page139_i174" )
			)
			( gate "R9E2"
				( objectStatus "@baseboard_fab2_lib.baseboard_fab2(sch_1):page139_i177" )
			)
			( gate "R9E3"
				( objectStatus "@baseboard_fab2_lib.baseboard_fab2(sch_1):page139_i178" )
			)
			( gate "R9E1"
				( objectStatus "@baseboard_fab2_lib.baseboard_fab2(sch_1):page139_i179" )
			)
			( gate "R9E22"
				( objectStatus "@baseboard_fab2_lib.baseboard_fab2(sch_1):page139_i181" )
			)
			( gate "R9E7"
				( objectStatus "@baseboard_fab2_lib.baseboard_fab2(sch_1):page139_i193" )
			)
			( gate "R1R1"
				( objectStatus "@baseboard_fab2_lib.baseboard_fab2(sch_1):page139_i195" )
			)
			( gate "R9E4"
				( objectStatus "@baseboard_fab2_lib.baseboard_fab2(sch_1):page139_i200" )
			)
			( gate "R9E18"
				( objectStatus "@baseboard_fab2_lib.baseboard_fab2(sch_1):page139_i201" )
			)
			( gate "R9E13"
				( objectStatus "@baseboard_fab2_lib.baseboard_fab2(sch_1):page139_i212" )
			)
			( gate "R1R12"
				( objectStatus "@baseboard_fab2_lib.baseboard_fab2(sch_1):page139_i213" )
			)
			( gate "R1T1"
				( objectStatus "@baseboard_fab2_lib.baseboard_fab2(sch_1):page139_i214" )
			)
			( gate "R9F1"
				( objectStatus "@baseboard_fab2_lib.baseboard_fab2(sch_1):page139_i225" )
			)
			( gate "R9E19"
				( objectStatus "@baseboard_fab2_lib.baseboard_fab2(sch_1):page139_i228" )
			)
			( gate "R9E17"
				( objectStatus "@baseboard_fab2_lib.baseboard_fab2(sch_1):page139_i229" )
			)
			( gate "R9E16"
				( objectStatus "@baseboard_fab2_lib.baseboard_fab2(sch_1):page139_i235" )
			)
			( gate "R1R15"
				( objectStatus "@baseboard_fab2_lib.baseboard_fab2(sch_1):page139_i237" )
			)
			( gate "R1T32"
				( objectStatus "@baseboard_fab2_lib.baseboard_fab2(sch_1):page139_i238" )
			)
			( gate "R1T34"
				( objectStatus "@baseboard_fab2_lib.baseboard_fab2(sch_1):page139_i239" )
			)
			( gate "R1T33"
				( objectStatus "@baseboard_fab2_lib.baseboard_fab2(sch_1):page139_i240" )
			)
			( gate "C9E12"
				( objectStatus "@baseboard_fab2_lib.baseboard_fab2(sch_1):page139_i241" )
			)
			( gate "U9E1"
				( objectStatus "@baseboard_fab2_lib.baseboard_fab2(sch_1):page140_i1" )
			)
			( gate "C1R25"
				( objectStatus "@baseboard_fab2_lib.baseboard_fab2(sch_1):page140_i3" )
			)
			( gate "R1R9"
				( objectStatus "@baseboard_fab2_lib.baseboard_fab2(sch_1):page140_i10" )
			)
			( gate "R1R3"
				( objectStatus "@baseboard_fab2_lib.baseboard_fab2(sch_1):page140_i11" )
			)
			( gate "R1R7"
				( objectStatus "@baseboard_fab2_lib.baseboard_fab2(sch_1):page140_i12" )
			)
			( gate "R1R6"
				( objectStatus "@baseboard_fab2_lib.baseboard_fab2(sch_1):page140_i14" )
			)
			( gate "R9E6"
				( objectStatus "@baseboard_fab2_lib.baseboard_fab2(sch_1):page140_i17" )
			)
			( gate "C9G4"
				( objectStatus "@baseboard_fab2_lib.baseboard_fab2(sch_1):page141_i46" )
			)
			( gate "C9G6"
				( objectStatus "@baseboard_fab2_lib.baseboard_fab2(sch_1):page141_i47" )
			)
			( gate "C9G5"
				( objectStatus "@baseboard_fab2_lib.baseboard_fab2(sch_1):page141_i48" )
			)
			( gate "R9G9"
				( objectStatus "@baseboard_fab2_lib.baseboard_fab2(sch_1):page141_i75" )
			)
			( gate "R9G11"
				( objectStatus "@baseboard_fab2_lib.baseboard_fab2(sch_1):page141_i76" )
			)
			( gate "R9G18"
				( objectStatus "@baseboard_fab2_lib.baseboard_fab2(sch_1):page141_i77" )
			)
			( gate "R9G17"
				( objectStatus "@baseboard_fab2_lib.baseboard_fab2(sch_1):page141_i78" )
			)
			( gate "R9G19"
				( objectStatus "@baseboard_fab2_lib.baseboard_fab2(sch_1):page141_i79" )
			)
			( gate "R9G20"
				( objectStatus "@baseboard_fab2_lib.baseboard_fab2(sch_1):page141_i80" )
			)
			( gate "R9G24"
				( objectStatus "@baseboard_fab2_lib.baseboard_fab2(sch_1):page141_i81" )
			)
			( gate "R9G22"
				( objectStatus "@baseboard_fab2_lib.baseboard_fab2(sch_1):page141_i82" )
			)
			( gate "C9G9"
				( objectStatus "@baseboard_fab2_lib.baseboard_fab2(sch_1):page141_i99" )
			)
			( gate "C9G12"
				( objectStatus "@baseboard_fab2_lib.baseboard_fab2(sch_1):page141_i100" )
			)
			( gate "C9G16"
				( objectStatus "@baseboard_fab2_lib.baseboard_fab2(sch_1):page141_i101" )
			)
			( gate "C9G13"
				( objectStatus "@baseboard_fab2_lib.baseboard_fab2(sch_1):page141_i102" )
			)
			( gate "C3W1"
				( objectStatus "@baseboard_fab2_lib.baseboard_fab2(sch_1):page114_i193" )
			)
			( gate "U8E4"
				( objectStatus "@baseboard_fab2_lib.baseboard_fab2(sch_1):page142_i1" )
			)
			( gate "R8E17"
				( objectStatus "@baseboard_fab2_lib.baseboard_fab2(sch_1):page142_i2" )
			)
			( gate "R8E23"
				( objectStatus "@baseboard_fab2_lib.baseboard_fab2(sch_1):page142_i3" )
			)
			( gate "R8E29"
				( objectStatus "@baseboard_fab2_lib.baseboard_fab2(sch_1):page142_i18" )
			)
			( gate "C8E5"
				( objectStatus "@baseboard_fab2_lib.baseboard_fab2(sch_1):page142_i20" )
			)
			( gate "R7D33"
				( objectStatus "@baseboard_fab2_lib.baseboard_fab2(sch_1):page92_i111" )
			)
			( gate "R3P45"
				( objectStatus "@baseboard_fab2_lib.baseboard_fab2(sch_1):page92_i110" )
			)
			( gate "R8E26"
				( objectStatus "@baseboard_fab2_lib.baseboard_fab2(sch_1):page142_i30" )
			)
			( gate "R8E28"
				( objectStatus "@baseboard_fab2_lib.baseboard_fab2(sch_1):page142_i31" )
			)
			( gate "R8E27"
				( objectStatus "@baseboard_fab2_lib.baseboard_fab2(sch_1):page142_i32" )
			)
			( gate "R8E21"
				( objectStatus "@baseboard_fab2_lib.baseboard_fab2(sch_1):page142_i33" )
			)
			( gate "U25W4"
				( objectStatus "@baseboard_fab2_lib.baseboard_fab2(sch_1):page145_i117" )
			)
			( gate "C25W4"
				( objectStatus "@baseboard_fab2_lib.baseboard_fab2(sch_1):page151_i141" )
			)
			( gate "C25W3"
				( objectStatus "@baseboard_fab2_lib.baseboard_fab2(sch_1):page151_i140" )
			)
			( gate "C25W2"
				( objectStatus "@baseboard_fab2_lib.baseboard_fab2(sch_1):page151_i139" )
			)
			( gate "R1T27"
				( objectStatus "@baseboard_fab2_lib.baseboard_fab2(sch_1):page143_i58" )
			)
			( gate "C25W5"
				( objectStatus "@baseboard_fab2_lib.baseboard_fab2(sch_1):page151_i142" )
			)
			( gate "C25W6"
				( objectStatus "@baseboard_fab2_lib.baseboard_fab2(sch_1):page151_i143" )
			)
			( gate "R25W32"
				( objectStatus "@baseboard_fab2_lib.baseboard_fab2(sch_1):page151_i227" )
			)
			( gate "R25W31"
				( objectStatus "@baseboard_fab2_lib.baseboard_fab2(sch_1):page151_i226" )
			)
			( gate "C9E9"
				( objectStatus "@baseboard_fab2_lib.baseboard_fab2(sch_1):page139_i249" )
			)
			( gate "CR10W2"
				( objectStatus "@baseboard_fab2_lib.baseboard_fab2(sch_1):page251_i10" )
			)
			( gate "Q6W4"
				( objectStatus "@baseboard_fab2_lib.baseboard_fab2(sch_1):page168_i43" )
			)
			( gate "R9F20"
				( objectStatus "@baseboard_fab2_lib.baseboard_fab2(sch_1):page145_i22" )
			)
			( gate "R2T41"
				( objectStatus "@baseboard_fab2_lib.baseboard_fab2(sch_1):page145_i136" )
			)
			( gate "R8B25"
				( objectStatus "@baseboard_fab2_lib.baseboard_fab2(sch_1):page151_i175" )
			)
			( gate "U9G1"
				( objectStatus "@baseboard_fab2_lib.baseboard_fab2(sch_1):page152_i1" )
			)
			( gate "R1U30"
				( objectStatus "@baseboard_fab2_lib.baseboard_fab2(sch_1):page152_i2" )
			)
			( gate "R1U46"
				( objectStatus "@baseboard_fab2_lib.baseboard_fab2(sch_1):page152_i6" )
			)
			( gate "R9G31"
				( objectStatus "@baseboard_fab2_lib.baseboard_fab2(sch_1):page152_i14" )
			)
			( gate "R1U36"
				( objectStatus "@baseboard_fab2_lib.baseboard_fab2(sch_1):page152_i15" )
			)
			( gate "R1U34"
				( objectStatus "@baseboard_fab2_lib.baseboard_fab2(sch_1):page152_i16" )
			)
			( gate "C1U19"
				( objectStatus "@baseboard_fab2_lib.baseboard_fab2(sch_1):page152_i18" )
			)
			( gate "R1U37"
				( objectStatus "@baseboard_fab2_lib.baseboard_fab2(sch_1):page152_i26" )
			)
			( gate "C1U22"
				( objectStatus "@baseboard_fab2_lib.baseboard_fab2(sch_1):page152_i27" )
			)
			( gate "R9G34"
				( objectStatus "@baseboard_fab2_lib.baseboard_fab2(sch_1):page152_i45" )
			)
			( gate "R9G27"
				( objectStatus "@baseboard_fab2_lib.baseboard_fab2(sch_1):page152_i47" )
			)
			( gate "R1U58"
				( objectStatus "@baseboard_fab2_lib.baseboard_fab2(sch_1):page152_i49" )
			)
			( gate "R1U56"
				( objectStatus "@baseboard_fab2_lib.baseboard_fab2(sch_1):page152_i50" )
			)
			( gate "R2U51"
				( objectStatus "@baseboard_fab2_lib.baseboard_fab2(sch_1):page152_i51" )
			)
			( gate "R2U40"
				( objectStatus "@baseboard_fab2_lib.baseboard_fab2(sch_1):page152_i53" )
			)
			( gate "R2U41"
				( objectStatus "@baseboard_fab2_lib.baseboard_fab2(sch_1):page152_i54" )
			)
			( gate "R1U41"
				( objectStatus "@baseboard_fab2_lib.baseboard_fab2(sch_1):page152_i56" )
			)
			( gate "R1U35"
				( objectStatus "@baseboard_fab2_lib.baseboard_fab2(sch_1):page152_i57" )
			)
			( gate "R4P17"
				( objectStatus "@baseboard_fab2_lib.baseboard_fab2(sch_1):page152_i58" )
			)
			( gate "R4P20"
				( objectStatus "@baseboard_fab2_lib.baseboard_fab2(sch_1):page152_i59" )
			)
			( gate "R7P5"
				( objectStatus "@baseboard_fab2_lib.baseboard_fab2(sch_1):page152_i61" )
			)
			( gate "R7P21"
				( objectStatus "@baseboard_fab2_lib.baseboard_fab2(sch_1):page152_i62" )
			)
			( gate "R1U53"
				( objectStatus "@baseboard_fab2_lib.baseboard_fab2(sch_1):page152_i64" )
			)
			( gate "R1U60"
				( objectStatus "@baseboard_fab2_lib.baseboard_fab2(sch_1):page152_i65" )
			)
			( gate "R2U49"
				( objectStatus "@baseboard_fab2_lib.baseboard_fab2(sch_1):page152_i66" )
			)
			( gate "R1U55"
				( objectStatus "@baseboard_fab2_lib.baseboard_fab2(sch_1):page152_i67" )
			)
			( gate "R1U62"
				( objectStatus "@baseboard_fab2_lib.baseboard_fab2(sch_1):page152_i68" )
			)
			( gate "R1U57"
				( objectStatus "@baseboard_fab2_lib.baseboard_fab2(sch_1):page152_i69" )
			)
			( gate "R1U61"
				( objectStatus "@baseboard_fab2_lib.baseboard_fab2(sch_1):page152_i70" )
			)
			( gate "R9G28"
				( objectStatus "@baseboard_fab2_lib.baseboard_fab2(sch_1):page152_i71" )
			)
			( gate "R9G32"
				( objectStatus "@baseboard_fab2_lib.baseboard_fab2(sch_1):page152_i72" )
			)
			( gate "R9G33"
				( objectStatus "@baseboard_fab2_lib.baseboard_fab2(sch_1):page152_i73" )
			)
			( gate "R1U59"
				( objectStatus "@baseboard_fab2_lib.baseboard_fab2(sch_1):page152_i74" )
			)
			( gate "R2U47"
				( objectStatus "@baseboard_fab2_lib.baseboard_fab2(sch_1):page152_i79" )
			)
			( gate "R9G29"
				( objectStatus "@baseboard_fab2_lib.baseboard_fab2(sch_1):page152_i92" )
			)
			( gate "R1U54"
				( objectStatus "@baseboard_fab2_lib.baseboard_fab2(sch_1):page152_i93" )
			)
			( gate "R2U46"
				( objectStatus "@baseboard_fab2_lib.baseboard_fab2(sch_1):page152_i94" )
			)
			( gate "R3N30"
				( objectStatus "@baseboard_fab2_lib.baseboard_fab2(sch_1):page152_i95" )
			)
			( gate "R9G30"
				( objectStatus "@baseboard_fab2_lib.baseboard_fab2(sch_1):page152_i98" )
			)
			( gate "R3P63"
				( objectStatus "@baseboard_fab2_lib.baseboard_fab2(sch_1):page152_i100" )
			)
			( gate "R2U45"
				( objectStatus "@baseboard_fab2_lib.baseboard_fab2(sch_1):page152_i102" )
			)
			( gate "R7F6"
				( objectStatus "@baseboard_fab2_lib.baseboard_fab2(sch_1):page153_i90" )
			)
			( gate "R7F5"
				( objectStatus "@baseboard_fab2_lib.baseboard_fab2(sch_1):page153_i94" )
			)
			( gate "R7F4"
				( objectStatus "@baseboard_fab2_lib.baseboard_fab2(sch_1):page153_i98" )
			)
			( gate "R7F37"
				( objectStatus "@baseboard_fab2_lib.baseboard_fab2(sch_1):page153_i108" )
			)
			( gate "R7F3"
				( objectStatus "@baseboard_fab2_lib.baseboard_fab2(sch_1):page153_i109" )
			)
			( gate "C7F2"
				( objectStatus "@baseboard_fab2_lib.baseboard_fab2(sch_1):page153_i130" )
			)
			( gate "C7F1"
				( objectStatus "@baseboard_fab2_lib.baseboard_fab2(sch_1):page153_i131" )
			)
			( gate "C3T5"
				( objectStatus "@baseboard_fab2_lib.baseboard_fab2(sch_1):page153_i136" )
			)
			( gate "C3T4"
				( objectStatus "@baseboard_fab2_lib.baseboard_fab2(sch_1):page153_i138" )
			)
			( gate "R7F32"
				( objectStatus "@baseboard_fab2_lib.baseboard_fab2(sch_1):page153_i140" )
			)
			( gate "U7F1"
				( objectStatus "@baseboard_fab2_lib.baseboard_fab2(sch_1):page153_i146" )
			)
			( gate "R3T3"
				( objectStatus "@baseboard_fab2_lib.baseboard_fab2(sch_1):page153_i150" )
			)
			( gate "R3T5"
				( objectStatus "@baseboard_fab2_lib.baseboard_fab2(sch_1):page153_i152" )
			)
			( gate "R3T2"
				( objectStatus "@baseboard_fab2_lib.baseboard_fab2(sch_1):page153_i155" )
			)
			( gate "R3U1"
				( objectStatus "@baseboard_fab2_lib.baseboard_fab2(sch_1):page153_i156" )
			)
			( gate "R3T1"
				( objectStatus "@baseboard_fab2_lib.baseboard_fab2(sch_1):page153_i157" )
			)
			( gate "R8F8"
				( objectStatus "@baseboard_fab2_lib.baseboard_fab2(sch_1):page153_i166" )
			)
			( gate "R8F7"
				( objectStatus "@baseboard_fab2_lib.baseboard_fab2(sch_1):page153_i167" )
			)
			( gate "R7F28"
				( objectStatus "@baseboard_fab2_lib.baseboard_fab2(sch_1):page153_i168" )
			)
			( gate "R7F30"
				( objectStatus "@baseboard_fab2_lib.baseboard_fab2(sch_1):page153_i170" )
			)
			( gate "R3T4"
				( objectStatus "@baseboard_fab2_lib.baseboard_fab2(sch_1):page153_i174" )
			)
			( gate "R3T12"
				( objectStatus "@baseboard_fab2_lib.baseboard_fab2(sch_1):page153_i178" )
			)
			( gate "R3T9"
				( objectStatus "@baseboard_fab2_lib.baseboard_fab2(sch_1):page153_i179" )
			)
			( gate "R7F29"
				( objectStatus "@baseboard_fab2_lib.baseboard_fab2(sch_1):page153_i181" )
			)
			( gate "R3T10"
				( objectStatus "@baseboard_fab2_lib.baseboard_fab2(sch_1):page153_i184" )
			)
			( gate "C8E18"
				( objectStatus "@baseboard_fab2_lib.baseboard_fab2(sch_1):page154_i14" )
			)
			( gate "R2T9"
				( objectStatus "@baseboard_fab2_lib.baseboard_fab2(sch_1):page154_i62" )
			)
			( gate "U8F1"
				( objectStatus "@baseboard_fab2_lib.baseboard_fab2(sch_1):page154_i74" )
			)
			( gate "U2T1"
				( objectStatus "@baseboard_fab2_lib.baseboard_fab2(sch_1):page154_i75" )
			)
			( gate "R2T2"
				( objectStatus "@baseboard_fab2_lib.baseboard_fab2(sch_1):page154_i92" )
			)
			( gate "R2R12"
				( objectStatus "@baseboard_fab2_lib.baseboard_fab2(sch_1):page154_i93" )
			)
			( gate "C2T1"
				( objectStatus "@baseboard_fab2_lib.baseboard_fab2(sch_1):page154_i94" )
			)
			( gate "U2T3"
				( objectStatus "@baseboard_fab2_lib.baseboard_fab2(sch_1):page154_i99" )
			)
			( gate "U2T2"
				( objectStatus "@baseboard_fab2_lib.baseboard_fab2(sch_1):page154_i100" )
			)
			( gate "R2T13"
				( objectStatus "@baseboard_fab2_lib.baseboard_fab2(sch_1):page154_i101" )
			)
			( gate "R2T11"
				( objectStatus "@baseboard_fab2_lib.baseboard_fab2(sch_1):page154_i105" )
			)
			( gate "R2T8"
				( objectStatus "@baseboard_fab2_lib.baseboard_fab2(sch_1):page154_i106" )
			)
			( gate "R8F6"
				( objectStatus "@baseboard_fab2_lib.baseboard_fab2(sch_1):page154_i119" )
			)
			( gate "Q8F1"
				( objectStatus "@baseboard_fab2_lib.baseboard_fab2(sch_1):page154_i126" )
			)
			( gate "R2T6"
				( objectStatus "@baseboard_fab2_lib.baseboard_fab2(sch_1):page154_i127" )
			)
			( gate "R1U6"
				( objectStatus "@baseboard_fab2_lib.baseboard_fab2(sch_1):page154_i128" )
			)
			( gate "C2T12"
				( objectStatus "@baseboard_fab2_lib.baseboard_fab2(sch_1):page154_i132" )
			)
			( gate "C2T8"
				( objectStatus "@baseboard_fab2_lib.baseboard_fab2(sch_1):page154_i135" )
			)
			( gate "R9A8"
				( objectStatus "@baseboard_fab2_lib.baseboard_fab2(sch_1):page155_i53" )
			)
			( gate "R1L32"
				( objectStatus "@baseboard_fab2_lib.baseboard_fab2(sch_1):page155_i65" )
			)
			( gate "R1L30"
				( objectStatus "@baseboard_fab2_lib.baseboard_fab2(sch_1):page155_i66" )
			)
			( gate "R1L25"
				( objectStatus "@baseboard_fab2_lib.baseboard_fab2(sch_1):page155_i67" )
			)
			( gate "R1L24"
				( objectStatus "@baseboard_fab2_lib.baseboard_fab2(sch_1):page155_i68" )
			)
			( gate "R1L20"
				( objectStatus "@baseboard_fab2_lib.baseboard_fab2(sch_1):page155_i73" )
			)
			( gate "R1L18"
				( objectStatus "@baseboard_fab2_lib.baseboard_fab2(sch_1):page155_i74" )
			)
			( gate "R1L14"
				( objectStatus "@baseboard_fab2_lib.baseboard_fab2(sch_1):page155_i75" )
			)
			( gate "R1L11"
				( objectStatus "@baseboard_fab2_lib.baseboard_fab2(sch_1):page155_i76" )
			)
			( gate "R9A7"
				( objectStatus "@baseboard_fab2_lib.baseboard_fab2(sch_1):page155_i80" )
			)
			( gate "C9A1"
				( objectStatus "@baseboard_fab2_lib.baseboard_fab2(sch_1):page155_i127" )
			)
			( gate "F1L1"
				( objectStatus "@baseboard_fab2_lib.baseboard_fab2(sch_1):page155_i129" )
			)
			( gate "R1L9"
				( objectStatus "@baseboard_fab2_lib.baseboard_fab2(sch_1):page155_i130" )
			)
			( gate "J9A2"
				( objectStatus "@baseboard_fab2_lib.baseboard_fab2(sch_1):page155_i171" )
			)
			( gate "U9A1"
				( objectStatus "@baseboard_fab2_lib.baseboard_fab2(sch_1):page155_i178" )
			)
			( gate "C1T56"
				( objectStatus "@baseboard_fab2_lib.baseboard_fab2(sch_1):page155_i184" )
			)
			( gate "R1L2"
				( objectStatus "@baseboard_fab2_lib.baseboard_fab2(sch_1):page155_i186" )
			)
			( gate "Q1L2"
				( objectStatus "@baseboard_fab2_lib.baseboard_fab2(sch_1):page155_i187" )
			)
			( gate "Q1L2"
				( objectStatus "@baseboard_fab2_lib.baseboard_fab2(sch_1):page155_i188" )
			)
			( gate "R2T34"
				( objectStatus "@baseboard_fab2_lib.baseboard_fab2(sch_1):page156_i206" )
			)
			( gate "R2T35"
				( objectStatus "@baseboard_fab2_lib.baseboard_fab2(sch_1):page156_i207" )
			)
			( gate "R2T22"
				( objectStatus "@baseboard_fab2_lib.baseboard_fab2(sch_1):page156_i210" )
			)
			( gate "R8F26"
				( objectStatus "@baseboard_fab2_lib.baseboard_fab2(sch_1):page156_i211" )
			)
			( gate "R8E24"
				( objectStatus "@baseboard_fab2_lib.baseboard_fab2(sch_1):page156_i214" )
			)
			( gate "R8E22"
				( objectStatus "@baseboard_fab2_lib.baseboard_fab2(sch_1):page156_i215" )
			)
			( gate "R2U2"
				( objectStatus "@baseboard_fab2_lib.baseboard_fab2(sch_1):page156_i265" )
			)
			( gate "R8G2"
				( objectStatus "@baseboard_fab2_lib.baseboard_fab2(sch_1):page156_i267" )
			)
			( gate "C2T35"
				( objectStatus "@baseboard_fab2_lib.baseboard_fab2(sch_1):page156_i273" )
			)
			( gate "C8F16"
				( objectStatus "@baseboard_fab2_lib.baseboard_fab2(sch_1):page156_i275" )
			)
			( gate "R8E11"
				( objectStatus "@baseboard_fab2_lib.baseboard_fab2(sch_1):page156_i279" )
			)
			( gate "J9B2"
				( objectStatus "@baseboard_fab2_lib.baseboard_fab2(sch_1):page156_i281" )
			)
			( gate "J8C1"
				( objectStatus "@baseboard_fab2_lib.baseboard_fab2(sch_1):page156_i285" )
			)
			( gate "R2T18"
				( objectStatus "@baseboard_fab2_lib.baseboard_fab2(sch_1):page156_i288" )
			)
			( gate "R2T28"
				( objectStatus "@baseboard_fab2_lib.baseboard_fab2(sch_1):page156_i289" )
			)
			( gate "R6D16"
				( objectStatus "@baseboard_fab2_lib.baseboard_fab2(sch_1):page156_i299" )
			)
			( gate "R3D31"
				( objectStatus "@baseboard_fab2_lib.baseboard_fab2(sch_1):page156_i300" )
			)
			( gate "R6N14"
				( objectStatus "@baseboard_fab2_lib.baseboard_fab2(sch_1):page156_i302" )
			)
			( gate "R6N13"
				( objectStatus "@baseboard_fab2_lib.baseboard_fab2(sch_1):page156_i303" )
			)
			( gate "R6N15"
				( objectStatus "@baseboard_fab2_lib.baseboard_fab2(sch_1):page156_i304" )
			)
			( gate "R1C32"
				( objectStatus "@baseboard_fab2_lib.baseboard_fab2(sch_1):page156_i312" )
			)
			( gate "R1C33"
				( objectStatus "@baseboard_fab2_lib.baseboard_fab2(sch_1):page156_i313" )
			)
			( gate "R1C34"
				( objectStatus "@baseboard_fab2_lib.baseboard_fab2(sch_1):page156_i320" )
			)
			( gate "R9M21"
				( objectStatus "@baseboard_fab2_lib.baseboard_fab2(sch_1):page156_i321" )
			)
			( gate "R4A8"
				( objectStatus "@baseboard_fab2_lib.baseboard_fab2(sch_1):page156_i322" )
			)
			( gate "R9M20"
				( objectStatus "@baseboard_fab2_lib.baseboard_fab2(sch_1):page156_i323" )
			)
			( gate "R4A9"
				( objectStatus "@baseboard_fab2_lib.baseboard_fab2(sch_1):page156_i324" )
			)
			( gate "R3P54"
				( objectStatus "@baseboard_fab2_lib.baseboard_fab2(sch_1):page156_i331" )
			)
			( gate "R3P56"
				( objectStatus "@baseboard_fab2_lib.baseboard_fab2(sch_1):page156_i333" )
			)
			( gate "R1C35"
				( objectStatus "@baseboard_fab2_lib.baseboard_fab2(sch_1):page156_i336" )
			)
			( gate "R1C36"
				( objectStatus "@baseboard_fab2_lib.baseboard_fab2(sch_1):page156_i337" )
			)
			( gate "R2N27"
				( objectStatus "@baseboard_fab2_lib.baseboard_fab2(sch_1):page157_i97" )
			)
			( gate "R8F23"
				( objectStatus "@baseboard_fab2_lib.baseboard_fab2(sch_1):page157_i296" )
			)
			( gate "R2T29"
				( objectStatus "@baseboard_fab2_lib.baseboard_fab2(sch_1):page157_i298" )
			)
			( gate "R2N25"
				( objectStatus "@baseboard_fab2_lib.baseboard_fab2(sch_1):page157_i302" )
			)
			( gate "R8F24"
				( objectStatus "@baseboard_fab2_lib.baseboard_fab2(sch_1):page157_i316" )
			)
			( gate "R2T5"
				( objectStatus "@baseboard_fab2_lib.baseboard_fab2(sch_1):page157_i326" )
			)
			( gate "R2T7"
				( objectStatus "@baseboard_fab2_lib.baseboard_fab2(sch_1):page157_i327" )
			)
			( gate "Q2T1"
				( objectStatus "@baseboard_fab2_lib.baseboard_fab2(sch_1):page157_i330" )
			)
			( gate "R8D25"
				( objectStatus "@baseboard_fab2_lib.baseboard_fab2(sch_1):page157_i335" )
			)
			( gate "Q2T2"
				( objectStatus "@baseboard_fab2_lib.baseboard_fab2(sch_1):page157_i340" )
			)
			( gate "R3N12"
				( objectStatus "@baseboard_fab2_lib.baseboard_fab2(sch_1):page157_i342" )
			)
			( gate "R3N11"
				( objectStatus "@baseboard_fab2_lib.baseboard_fab2(sch_1):page157_i344" )
			)
			( gate "R2M2"
				( objectStatus "@baseboard_fab2_lib.baseboard_fab2(sch_1):page157_i346" )
			)
			( gate "R2M5"
				( objectStatus "@baseboard_fab2_lib.baseboard_fab2(sch_1):page157_i348" )
			)
			( gate "S8E1"
				( objectStatus "@baseboard_fab2_lib.baseboard_fab2(sch_1):page157_i351" )
			)
			( gate "R2R9"
				( objectStatus "@baseboard_fab2_lib.baseboard_fab2(sch_1):page157_i352" )
			)
			( gate "C2R12"
				( objectStatus "@baseboard_fab2_lib.baseboard_fab2(sch_1):page157_i353" )
			)
			( gate "U9A3"
				( objectStatus "@baseboard_fab2_lib.baseboard_fab2(sch_1):page175_i93" )
			)
			( gate "R8E19"
				( objectStatus "@baseboard_fab2_lib.baseboard_fab2(sch_1):page157_i361" )
			)
			( gate "R2U4"
				( objectStatus "@baseboard_fab2_lib.baseboard_fab2(sch_1):page157_i367" )
			)
			( gate "R4R1"
				( objectStatus "@baseboard_fab2_lib.baseboard_fab2(sch_1):page157_i368" )
			)
			( gate "C2T3"
				( objectStatus "@baseboard_fab2_lib.baseboard_fab2(sch_1):page157_i370" )
			)
			( gate "U8D2"
				( objectStatus "@baseboard_fab2_lib.baseboard_fab2(sch_1):page157_i374" )
			)
			( gate "C8D1"
				( objectStatus "@baseboard_fab2_lib.baseboard_fab2(sch_1):page157_i376" )
			)
			( gate "R1L7"
				( objectStatus "@baseboard_fab2_lib.baseboard_fab2(sch_1):page157_i382" )
			)
			( gate "R8E32"
				( objectStatus "@baseboard_fab2_lib.baseboard_fab2(sch_1):page157_i385" )
			)
			( gate "R8D22"
				( objectStatus "@baseboard_fab2_lib.baseboard_fab2(sch_1):page157_i386" )
			)
			( gate "R8D36"
				( objectStatus "@baseboard_fab2_lib.baseboard_fab2(sch_1):page157_i388" )
			)
			( gate "C1T10"
				( objectStatus "@baseboard_fab2_lib.baseboard_fab2(sch_1):page158_i70" )
			)
			( gate "U9F2"
				( objectStatus "@baseboard_fab2_lib.baseboard_fab2(sch_1):page158_i74" )
			)
			( gate "U9F1"
				( objectStatus "@baseboard_fab2_lib.baseboard_fab2(sch_1):page158_i75" )
			)
			( gate "R9F25"
				( objectStatus "@baseboard_fab2_lib.baseboard_fab2(sch_1):page158_i86" )
			)
			( gate "R9F27"
				( objectStatus "@baseboard_fab2_lib.baseboard_fab2(sch_1):page158_i91" )
			)
			( gate "C1T11"
				( objectStatus "@baseboard_fab2_lib.baseboard_fab2(sch_1):page158_i97" )
			)
			( gate "R9F26"
				( objectStatus "@baseboard_fab2_lib.baseboard_fab2(sch_1):page158_i99" )
			)
			( gate "R9F24"
				( objectStatus "@baseboard_fab2_lib.baseboard_fab2(sch_1):page158_i100" )
			)
			( gate "DS9A4"
				( objectStatus "@baseboard_fab2_lib.baseboard_fab2(sch_1):page158_i130" )
			)
			( gate "R1L43"
				( objectStatus "@baseboard_fab2_lib.baseboard_fab2(sch_1):page158_i131" )
			)
			( gate "DS9A7"
				( objectStatus "@baseboard_fab2_lib.baseboard_fab2(sch_1):page158_i134" )
			)
			( gate "R1L44"
				( objectStatus "@baseboard_fab2_lib.baseboard_fab2(sch_1):page158_i136" )
			)
			( gate "R9F31"
				( objectStatus "@baseboard_fab2_lib.baseboard_fab2(sch_1):page239_i98" )
			)
			( gate "R8G3"
				( objectStatus "@baseboard_fab2_lib.baseboard_fab2(sch_1):page159_i210" )
			)
			( gate "R8G6"
				( objectStatus "@baseboard_fab2_lib.baseboard_fab2(sch_1):page159_i212" )
			)
			( gate "R2U5"
				( objectStatus "@baseboard_fab2_lib.baseboard_fab2(sch_1):page159_i214" )
			)
			( gate "R2U13"
				( objectStatus "@baseboard_fab2_lib.baseboard_fab2(sch_1):page159_i216" )
			)
			( gate "R2U1"
				( objectStatus "@baseboard_fab2_lib.baseboard_fab2(sch_1):page159_i218" )
			)
			( gate "R2T49"
				( objectStatus "@baseboard_fab2_lib.baseboard_fab2(sch_1):page159_i219" )
			)
			( gate "R2U7"
				( objectStatus "@baseboard_fab2_lib.baseboard_fab2(sch_1):page159_i220" )
			)
			( gate "R2U10"
				( objectStatus "@baseboard_fab2_lib.baseboard_fab2(sch_1):page159_i221" )
			)
			( gate "R1U11"
				( objectStatus "@baseboard_fab2_lib.baseboard_fab2(sch_1):page159_i222" )
			)
			( gate "R1U8"
				( objectStatus "@baseboard_fab2_lib.baseboard_fab2(sch_1):page159_i223" )
			)
			( gate "R9G12"
				( objectStatus "@baseboard_fab2_lib.baseboard_fab2(sch_1):page159_i224" )
			)
			( gate "R1U20"
				( objectStatus "@baseboard_fab2_lib.baseboard_fab2(sch_1):page159_i225" )
			)
			( gate "R1U19"
				( objectStatus "@baseboard_fab2_lib.baseboard_fab2(sch_1):page159_i226" )
			)
			( gate "R9G13"
				( objectStatus "@baseboard_fab2_lib.baseboard_fab2(sch_1):page159_i227" )
			)
			( gate "R8G5"
				( objectStatus "@baseboard_fab2_lib.baseboard_fab2(sch_1):page159_i228" )
			)
			( gate "R8G4"
				( objectStatus "@baseboard_fab2_lib.baseboard_fab2(sch_1):page159_i229" )
			)
			( gate "R2U34"
				( objectStatus "@baseboard_fab2_lib.baseboard_fab2(sch_1):page159_i230" )
			)
			( gate "R2U33"
				( objectStatus "@baseboard_fab2_lib.baseboard_fab2(sch_1):page159_i231" )
			)
			( gate "R1U9"
				( objectStatus "@baseboard_fab2_lib.baseboard_fab2(sch_1):page159_i232" )
			)
			( gate "R1U10"
				( objectStatus "@baseboard_fab2_lib.baseboard_fab2(sch_1):page159_i233" )
			)
			( gate "R1T8"
				( objectStatus "@baseboard_fab2_lib.baseboard_fab2(sch_1):page160_i4" )
			)
			( gate "R1T3"
				( objectStatus "@baseboard_fab2_lib.baseboard_fab2(sch_1):page160_i46" )
			)
			( gate "R1T2"
				( objectStatus "@baseboard_fab2_lib.baseboard_fab2(sch_1):page160_i49" )
			)
			( gate "R1T7"
				( objectStatus "@baseboard_fab2_lib.baseboard_fab2(sch_1):page160_i50" )
			)
			( gate "R9F23"
				( objectStatus "@baseboard_fab2_lib.baseboard_fab2(sch_1):page160_i51" )
			)
			( gate "R9F22"
				( objectStatus "@baseboard_fab2_lib.baseboard_fab2(sch_1):page160_i52" )
			)
			( gate "J10W1"
				( objectStatus "@baseboard_fab2_lib.baseboard_fab2(sch_1):page161_i140" )
			)
			( gate "C1E21"
				( objectStatus "@baseboard_fab2_lib.baseboard_fab2(sch_1):page161_i3" )
			)
			( gate "C1E20"
				( objectStatus "@baseboard_fab2_lib.baseboard_fab2(sch_1):page161_i4" )
			)
			( gate "C9M5"
				( objectStatus "@baseboard_fab2_lib.baseboard_fab2(sch_1):page161_i26" )
			)
			( gate "C9M4"
				( objectStatus "@baseboard_fab2_lib.baseboard_fab2(sch_1):page161_i27" )
			)
			( gate "CR1F1"
				( objectStatus "@baseboard_fab2_lib.baseboard_fab2(sch_1):page161_i42" )
			)
			( gate "R1F2"
				( objectStatus "@baseboard_fab2_lib.baseboard_fab2(sch_1):page161_i43" )
			)
			( gate "R1F1"
				( objectStatus "@baseboard_fab2_lib.baseboard_fab2(sch_1):page161_i45" )
			)
			( gate "C1F9"
				( objectStatus "@baseboard_fab2_lib.baseboard_fab2(sch_1):page161_i46" )
			)
			( gate "CR1E1"
				( objectStatus "@baseboard_fab2_lib.baseboard_fab2(sch_1):page161_i50" )
			)
			( gate "R1E12"
				( objectStatus "@baseboard_fab2_lib.baseboard_fab2(sch_1):page161_i51" )
			)
			( gate "CR1B2"
				( objectStatus "@baseboard_fab2_lib.baseboard_fab2(sch_1):page161_i62" )
			)
			( gate "CR1B1"
				( objectStatus "@baseboard_fab2_lib.baseboard_fab2(sch_1):page161_i64" )
			)
			( gate "R7F33"
				( objectStatus "@baseboard_fab2_lib.baseboard_fab2(sch_1):page161_i65" )
			)
			( gate "R1B22"
				( objectStatus "@baseboard_fab2_lib.baseboard_fab2(sch_1):page161_i67" )
			)
			( gate "C1B15"
				( objectStatus "@baseboard_fab2_lib.baseboard_fab2(sch_1):page161_i68" )
			)
			( gate "R1B21"
				( objectStatus "@baseboard_fab2_lib.baseboard_fab2(sch_1):page161_i70" )
			)
			( gate "U8G2"
				( objectStatus "@baseboard_fab2_lib.baseboard_fab2(sch_1):page161_i88" )
			)
			( gate "C2U27"
				( objectStatus "@baseboard_fab2_lib.baseboard_fab2(sch_1):page161_i90" )
			)
			( gate "U8G3"
				( objectStatus "@baseboard_fab2_lib.baseboard_fab2(sch_1):page161_i92" )
			)
			( gate "C2U28"
				( objectStatus "@baseboard_fab2_lib.baseboard_fab2(sch_1):page161_i93" )
			)
			( gate "R2U42"
				( objectStatus "@baseboard_fab2_lib.baseboard_fab2(sch_1):page161_i99" )
			)
			( gate "R2U44"
				( objectStatus "@baseboard_fab2_lib.baseboard_fab2(sch_1):page161_i102" )
			)
			( gate "C1E22"
				( objectStatus "@baseboard_fab2_lib.baseboard_fab2(sch_1):page161_i113" )
			)
			( gate "R1E11"
				( objectStatus "@baseboard_fab2_lib.baseboard_fab2(sch_1):page161_i120" )
			)
			( gate "U1E2"
				( objectStatus "@baseboard_fab2_lib.baseboard_fab2(sch_1):page161_i121" )
			)
			( gate "R8F16"
				( objectStatus "@baseboard_fab2_lib.baseboard_fab2(sch_1):page162_i8" )
			)
			( gate "R8F14"
				( objectStatus "@baseboard_fab2_lib.baseboard_fab2(sch_1):page162_i9" )
			)
			( gate "R8F12"
				( objectStatus "@baseboard_fab2_lib.baseboard_fab2(sch_1):page162_i13" )
			)
			( gate "R8F34"
				( objectStatus "@baseboard_fab2_lib.baseboard_fab2(sch_1):page162_i22" )
			)
			( gate "RN8F2"
				( objectStatus "@baseboard_fab2_lib.baseboard_fab2(sch_1):page246_i20" )
			)
			( gate "R8F35"
				( objectStatus "@baseboard_fab2_lib.baseboard_fab2(sch_1):page162_i24" )
			)
			( gate "C8F5"
				( objectStatus "@baseboard_fab2_lib.baseboard_fab2(sch_1):page162_i28" )
			)
			( gate "C8F4"
				( objectStatus "@baseboard_fab2_lib.baseboard_fab2(sch_1):page162_i30" )
			)
			( gate "U8F2"
				( objectStatus "@baseboard_fab2_lib.baseboard_fab2(sch_1):page162_i32" )
			)
			( gate "R6N8"
				( objectStatus "@baseboard_fab2_lib.baseboard_fab2(sch_1):page163_i2" )
			)
			( gate "R6N9"
				( objectStatus "@baseboard_fab2_lib.baseboard_fab2(sch_1):page163_i3" )
			)
			( gate "R9M18"
				( objectStatus "@baseboard_fab2_lib.baseboard_fab2(sch_1):page163_i6" )
			)
			( gate "R9M19"
				( objectStatus "@baseboard_fab2_lib.baseboard_fab2(sch_1):page163_i7" )
			)
			( gate "C9M8"
				( objectStatus "@baseboard_fab2_lib.baseboard_fab2(sch_1):page163_i10" )
			)
			( gate "C9M7"
				( objectStatus "@baseboard_fab2_lib.baseboard_fab2(sch_1):page163_i12" )
			)
			( gate "R9M17"
				( objectStatus "@baseboard_fab2_lib.baseboard_fab2(sch_1):page163_i15" )
			)
			( gate "R9M16"
				( objectStatus "@baseboard_fab2_lib.baseboard_fab2(sch_1):page163_i16" )
			)
			( gate "R9M14"
				( objectStatus "@baseboard_fab2_lib.baseboard_fab2(sch_1):page163_i20" )
			)
			( gate "R9M13"
				( objectStatus "@baseboard_fab2_lib.baseboard_fab2(sch_1):page163_i21" )
			)
			( gate "RN8F6"
				( objectStatus "@baseboard_fab2_lib.baseboard_fab2(sch_1):page246_i19" )
			)
			( gate "R1U24"
				( objectStatus "@baseboard_fab2_lib.baseboard_fab2(sch_1):page164_i47" )
			)
			( gate "R1T11"
				( objectStatus "@baseboard_fab2_lib.baseboard_fab2(sch_1):page164_i7" )
			)
			( gate "R1T5"
				( objectStatus "@baseboard_fab2_lib.baseboard_fab2(sch_1):page164_i11" )
			)
			( gate "R2N17"
				( objectStatus "@baseboard_fab2_lib.baseboard_fab2(sch_1):page164_i46" )
			)
			( gate "R1U17"
				( objectStatus "@baseboard_fab2_lib.baseboard_fab2(sch_1):page164_i21" )
			)
			( gate "R2N18"
				( objectStatus "@baseboard_fab2_lib.baseboard_fab2(sch_1):page164_i32" )
			)
			( gate "R7W3"
				( objectStatus "@baseboard_fab2_lib.baseboard_fab2(sch_1):page166_i46" )
			)
			( gate "R7W2"
				( objectStatus "@baseboard_fab2_lib.baseboard_fab2(sch_1):page166_i42" )
			)
			( gate "R7C17"
				( objectStatus "@baseboard_fab2_lib.baseboard_fab2(sch_1):page166_i28" )
			)
			( gate "R7D15"
				( objectStatus "@baseboard_fab2_lib.baseboard_fab2(sch_1):page166_i32" )
			)
			( gate "U9B4"
				( objectStatus "@baseboard_fab2_lib.baseboard_fab2(sch_1):page167_i1" )
			)
			( gate "R9B5"
				( objectStatus "@baseboard_fab2_lib.baseboard_fab2(sch_1):page167_i5" )
			)
			( gate "R9B4"
				( objectStatus "@baseboard_fab2_lib.baseboard_fab2(sch_1):page167_i6" )
			)
			( gate "C1M4"
				( objectStatus "@baseboard_fab2_lib.baseboard_fab2(sch_1):page167_i7" )
			)
			( gate "R1M9"
				( objectStatus "@baseboard_fab2_lib.baseboard_fab2(sch_1):page167_i8" )
			)
			( gate "R9B8"
				( objectStatus "@baseboard_fab2_lib.baseboard_fab2(sch_1):page167_i10" )
			)
			( gate "C1E19"
				( objectStatus "@baseboard_fab2_lib.baseboard_fab2(sch_1):page167_i24" )
			)
			( gate "R9R5"
				( objectStatus "@baseboard_fab2_lib.baseboard_fab2(sch_1):page167_i25" )
			)
			( gate "R9R6"
				( objectStatus "@baseboard_fab2_lib.baseboard_fab2(sch_1):page167_i26" )
			)
			( gate "U1E1"
				( objectStatus "@baseboard_fab2_lib.baseboard_fab2(sch_1):page167_i30" )
			)
			( gate "R1E9"
				( objectStatus "@baseboard_fab2_lib.baseboard_fab2(sch_1):page167_i34" )
			)
			( gate "R9B6"
				( objectStatus "@baseboard_fab2_lib.baseboard_fab2(sch_1):page167_i35" )
			)
			( gate "R1E10"
				( objectStatus "@baseboard_fab2_lib.baseboard_fab2(sch_1):page167_i38" )
			)
			( gate "C9B7"
				( objectStatus "@baseboard_fab2_lib.baseboard_fab2(sch_1):page167_i39" )
			)
			( gate "C9R14"
				( objectStatus "@baseboard_fab2_lib.baseboard_fab2(sch_1):page167_i41" )
			)
			( gate "C9R13"
				( objectStatus "@baseboard_fab2_lib.baseboard_fab2(sch_1):page167_i42" )
			)
			( gate "U8D4"
				( objectStatus "@baseboard_fab2_lib.baseboard_fab2(sch_1):page167_i49" )
			)
			( gate "R8D27"
				( objectStatus "@baseboard_fab2_lib.baseboard_fab2(sch_1):page167_i50" )
			)
			( gate "R9G15"
				( objectStatus "@baseboard_fab2_lib.baseboard_fab2(sch_1):page167_i58" )
			)
			( gate "R8D28"
				( objectStatus "@baseboard_fab2_lib.baseboard_fab2(sch_1):page167_i70" )
			)
			( gate "R1M8"
				( objectStatus "@baseboard_fab2_lib.baseboard_fab2(sch_1):page167_i74" )
			)
			( gate "R9R7"
				( objectStatus "@baseboard_fab2_lib.baseboard_fab2(sch_1):page167_i75" )
			)
			( gate "R9R8"
				( objectStatus "@baseboard_fab2_lib.baseboard_fab2(sch_1):page167_i76" )
			)
			( gate "R9G14"
				( objectStatus "@baseboard_fab2_lib.baseboard_fab2(sch_1):page167_i77" )
			)
			( gate "R2U38"
				( objectStatus "@baseboard_fab2_lib.baseboard_fab2(sch_1):page167_i80" )
			)
			( gate "R2U39"
				( objectStatus "@baseboard_fab2_lib.baseboard_fab2(sch_1):page167_i83" )
			)
			( gate "R8D24"
				( objectStatus "@baseboard_fab2_lib.baseboard_fab2(sch_1):page167_i84" )
			)
			( gate "R8D23"
				( objectStatus "@baseboard_fab2_lib.baseboard_fab2(sch_1):page167_i85" )
			)
			( gate "CR1L1"
				( objectStatus "@baseboard_fab2_lib.baseboard_fab2(sch_1):page168_i2" )
			)
			( gate "CR1L2"
				( objectStatus "@baseboard_fab2_lib.baseboard_fab2(sch_1):page168_i3" )
			)
			( gate "CR1L3"
				( objectStatus "@baseboard_fab2_lib.baseboard_fab2(sch_1):page168_i4" )
			)
			( gate "CR1L4"
				( objectStatus "@baseboard_fab2_lib.baseboard_fab2(sch_1):page168_i5" )
			)
			( gate "R1L6"
				( objectStatus "@baseboard_fab2_lib.baseboard_fab2(sch_1):page168_i6" )
			)
			( gate "Q1L3"
				( objectStatus "@baseboard_fab2_lib.baseboard_fab2(sch_1):page168_i8" )
			)
			( gate "R1L36"
				( objectStatus "@baseboard_fab2_lib.baseboard_fab2(sch_1):page168_i11" )
			)
			( gate "Q1L4"
				( objectStatus "@baseboard_fab2_lib.baseboard_fab2(sch_1):page168_i18" )
			)
			( gate "Q1L4"
				( objectStatus "@baseboard_fab2_lib.baseboard_fab2(sch_1):page168_i19" )
			)
			( gate "R1L38"
				( objectStatus "@baseboard_fab2_lib.baseboard_fab2(sch_1):page168_i22" )
			)
			( gate "C1U21"
				( objectStatus "@baseboard_fab2_lib.baseboard_fab2(sch_1):page169_i56" )
			)
			( gate "FB1U3"
				( objectStatus "@baseboard_fab2_lib.baseboard_fab2(sch_1):page169_i57" )
			)
			( gate "C9G21"
				( objectStatus "@baseboard_fab2_lib.baseboard_fab2(sch_1):page169_i68" )
			)
			( gate "C9G17"
				( objectStatus "@baseboard_fab2_lib.baseboard_fab2(sch_1):page169_i80" )
			)
			( gate "R1U32"
				( objectStatus "@baseboard_fab2_lib.baseboard_fab2(sch_1):page169_i82" )
			)
			( gate "C9G20"
				( objectStatus "@baseboard_fab2_lib.baseboard_fab2(sch_1):page169_i86" )
			)
			( gate "R1U39"
				( objectStatus "@baseboard_fab2_lib.baseboard_fab2(sch_1):page169_i88" )
			)
			( gate "R9G26"
				( objectStatus "@baseboard_fab2_lib.baseboard_fab2(sch_1):page169_i106" )
			)
			( gate "C9G22"
				( objectStatus "@baseboard_fab2_lib.baseboard_fab2(sch_1):page169_i108" )
			)
			( gate "R1U44"
				( objectStatus "@baseboard_fab2_lib.baseboard_fab2(sch_1):page169_i170" )
			)
			( gate "R1U47"
				( objectStatus "@baseboard_fab2_lib.baseboard_fab2(sch_1):page169_i115" )
			)
			( gate "R1U50"
				( objectStatus "@baseboard_fab2_lib.baseboard_fab2(sch_1):page169_i126" )
			)
			( gate "C9G15"
				( objectStatus "@baseboard_fab2_lib.baseboard_fab2(sch_1):page169_i139" )
			)
			( gate "R1U29"
				( objectStatus "@baseboard_fab2_lib.baseboard_fab2(sch_1):page169_i141" )
			)
			( gate "C9G14"
				( objectStatus "@baseboard_fab2_lib.baseboard_fab2(sch_1):page169_i146" )
			)
			( gate "R1U26"
				( objectStatus "@baseboard_fab2_lib.baseboard_fab2(sch_1):page169_i148" )
			)
			( gate "R1U28"
				( objectStatus "@baseboard_fab2_lib.baseboard_fab2(sch_1):page169_i169" )
			)
			( gate "C9G18"
				( objectStatus "@baseboard_fab2_lib.baseboard_fab2(sch_1):page169_i153" )
			)
			( gate "FB1U4"
				( objectStatus "@baseboard_fab2_lib.baseboard_fab2(sch_1):page169_i155" )
			)
			( gate "Q9G1"
				( objectStatus "@baseboard_fab2_lib.baseboard_fab2(sch_1):page169_i157" )
			)
			( gate "Q9G1"
				( objectStatus "@baseboard_fab2_lib.baseboard_fab2(sch_1):page169_i162" )
			)
			( gate "R1U49"
				( objectStatus "@baseboard_fab2_lib.baseboard_fab2(sch_1):page169_i163" )
			)
			( gate "R9G35"
				( objectStatus "@baseboard_fab2_lib.baseboard_fab2(sch_1):page169_i164" )
			)
			( gate "R2P3"
				( objectStatus "@baseboard_fab2_lib.baseboard_fab2(sch_1):page170_i2" )
			)
			( gate "U8D3"
				( objectStatus "@baseboard_fab2_lib.baseboard_fab2(sch_1):page170_i4" )
			)
			( gate "C2P1"
				( objectStatus "@baseboard_fab2_lib.baseboard_fab2(sch_1):page170_i8" )
			)
			( gate "U8E1"
				( objectStatus "@baseboard_fab2_lib.baseboard_fab2(sch_1):page170_i10" )
			)
			( gate "U8E1"
				( objectStatus "@baseboard_fab2_lib.baseboard_fab2(sch_1):page170_i11" )
			)
			( gate "U8E1"
				( objectStatus "@baseboard_fab2_lib.baseboard_fab2(sch_1):page170_i12" )
			)
			( gate "U1R2"
				( objectStatus "@baseboard_fab2_lib.baseboard_fab2(sch_1):page170_i20" )
			)
			( gate "C1R27"
				( objectStatus "@baseboard_fab2_lib.baseboard_fab2(sch_1):page170_i30" )
			)
			( gate "C8D2"
				( objectStatus "@baseboard_fab2_lib.baseboard_fab2(sch_1):page170_i33" )
			)
			( gate "U8D5"
				( objectStatus "@baseboard_fab2_lib.baseboard_fab2(sch_1):page170_i38" )
			)
			( gate "C8E2"
				( objectStatus "@baseboard_fab2_lib.baseboard_fab2(sch_1):page170_i40" )
			)
			( gate "C8D3"
				( objectStatus "@baseboard_fab2_lib.baseboard_fab2(sch_1):page170_i42" )
			)
			( gate "U1R1"
				( objectStatus "@baseboard_fab2_lib.baseboard_fab2(sch_1):page170_i46" )
			)
			( gate "C1R28"
				( objectStatus "@baseboard_fab2_lib.baseboard_fab2(sch_1):page170_i49" )
			)
			( gate "R1R8"
				( objectStatus "@baseboard_fab2_lib.baseboard_fab2(sch_1):page170_i51" )
			)
			( gate "R2T3"
				( objectStatus "@baseboard_fab2_lib.baseboard_fab2(sch_1):page170_i54" )
			)
			( gate "R2P5"
				( objectStatus "@baseboard_fab2_lib.baseboard_fab2(sch_1):page170_i56" )
			)
			( gate "Q2P1"
				( objectStatus "@baseboard_fab2_lib.baseboard_fab2(sch_1):page170_i58" )
			)
			( gate "R2P13"
				( objectStatus "@baseboard_fab2_lib.baseboard_fab2(sch_1):page170_i61" )
			)
			( gate "R2P11"
				( objectStatus "@baseboard_fab2_lib.baseboard_fab2(sch_1):page170_i63" )
			)
			( gate "R9F3"
				( objectStatus "@baseboard_fab2_lib.baseboard_fab2(sch_1):page170_i65" )
			)
			( gate "Q8F2"
				( objectStatus "@baseboard_fab2_lib.baseboard_fab2(sch_1):page170_i67" )
			)
			( gate "R8D26"
				( objectStatus "@baseboard_fab2_lib.baseboard_fab2(sch_1):page170_i71" )
			)
			( gate "R1R5"
				( objectStatus "@baseboard_fab2_lib.baseboard_fab2(sch_1):page170_i73" )
			)
			( gate "R2P4"
				( objectStatus "@baseboard_fab2_lib.baseboard_fab2(sch_1):page170_i74" )
			)
			( gate "C2L49"
				( objectStatus "@baseboard_fab2_lib.baseboard_fab2(sch_1):page172_i5" )
			)
			( gate "C2L52"
				( objectStatus "@baseboard_fab2_lib.baseboard_fab2(sch_1):page172_i6" )
			)
			( gate "C2L50"
				( objectStatus "@baseboard_fab2_lib.baseboard_fab2(sch_1):page172_i7" )
			)
			( gate "C2L51"
				( objectStatus "@baseboard_fab2_lib.baseboard_fab2(sch_1):page172_i8" )
			)
			( gate "C9B2"
				( objectStatus "@baseboard_fab2_lib.baseboard_fab2(sch_1):page172_i36" )
			)
			( gate "C9B1"
				( objectStatus "@baseboard_fab2_lib.baseboard_fab2(sch_1):page172_i39" )
			)
			( gate "R25W108"
				( objectStatus "@baseboard_fab2_lib.baseboard_fab2(sch_1):page150_i191" )
			)
			( gate "R25W116"
				( objectStatus "@baseboard_fab2_lib.baseboard_fab2(sch_1):page150_i189" )
			)
			( gate "J8A1"
				( objectStatus "@baseboard_fab2_lib.baseboard_fab2(sch_1):page173_i163" )
			)
			( gate "C2L13"
				( objectStatus "@baseboard_fab2_lib.baseboard_fab2(sch_1):page173_i165" )
			)
			( gate "C2L6"
				( objectStatus "@baseboard_fab2_lib.baseboard_fab2(sch_1):page173_i166" )
			)
			( gate "C2L19"
				( objectStatus "@baseboard_fab2_lib.baseboard_fab2(sch_1):page173_i172" )
			)
			( gate "C2L10"
				( objectStatus "@baseboard_fab2_lib.baseboard_fab2(sch_1):page173_i173" )
			)
			( gate "C2L17"
				( objectStatus "@baseboard_fab2_lib.baseboard_fab2(sch_1):page173_i174" )
			)
			( gate "C2L15"
				( objectStatus "@baseboard_fab2_lib.baseboard_fab2(sch_1):page173_i191" )
			)
			( gate "C2L4"
				( objectStatus "@baseboard_fab2_lib.baseboard_fab2(sch_1):page173_i192" )
			)
			( gate "C2L3"
				( objectStatus "@baseboard_fab2_lib.baseboard_fab2(sch_1):page173_i194" )
			)
			( gate "C2L20"
				( objectStatus "@baseboard_fab2_lib.baseboard_fab2(sch_1):page173_i195" )
			)
			( gate "C2L12"
				( objectStatus "@baseboard_fab2_lib.baseboard_fab2(sch_1):page173_i196" )
			)
			( gate "C2L18"
				( objectStatus "@baseboard_fab2_lib.baseboard_fab2(sch_1):page173_i197" )
			)
			( gate "C2L16"
				( objectStatus "@baseboard_fab2_lib.baseboard_fab2(sch_1):page173_i205" )
			)
			( gate "C2L7"
				( objectStatus "@baseboard_fab2_lib.baseboard_fab2(sch_1):page173_i206" )
			)
			( gate "C2L9"
				( objectStatus "@baseboard_fab2_lib.baseboard_fab2(sch_1):page173_i207" )
			)
			( gate "C2L14"
				( objectStatus "@baseboard_fab2_lib.baseboard_fab2(sch_1):page173_i208" )
			)
			( gate "C2L5"
				( objectStatus "@baseboard_fab2_lib.baseboard_fab2(sch_1):page173_i209" )
			)
			( gate "C2L40"
				( objectStatus "@baseboard_fab2_lib.baseboard_fab2(sch_1):page173_i220" )
			)
			( gate "C2L39"
				( objectStatus "@baseboard_fab2_lib.baseboard_fab2(sch_1):page173_i221" )
			)
			( gate "C2L43"
				( objectStatus "@baseboard_fab2_lib.baseboard_fab2(sch_1):page173_i222" )
			)
			( gate "C2L44"
				( objectStatus "@baseboard_fab2_lib.baseboard_fab2(sch_1):page173_i228" )
			)
			( gate "C2L42"
				( objectStatus "@baseboard_fab2_lib.baseboard_fab2(sch_1):page173_i233" )
			)
			( gate "C2L22"
				( objectStatus "@baseboard_fab2_lib.baseboard_fab2(sch_1):page173_i234" )
			)
			( gate "C2L37"
				( objectStatus "@baseboard_fab2_lib.baseboard_fab2(sch_1):page173_i238" )
			)
			( gate "C2L47"
				( objectStatus "@baseboard_fab2_lib.baseboard_fab2(sch_1):page173_i239" )
			)
			( gate "C2L27"
				( objectStatus "@baseboard_fab2_lib.baseboard_fab2(sch_1):page173_i240" )
			)
			( gate "C2L23"
				( objectStatus "@baseboard_fab2_lib.baseboard_fab2(sch_1):page173_i241" )
			)
			( gate "C2L41"
				( objectStatus "@baseboard_fab2_lib.baseboard_fab2(sch_1):page173_i242" )
			)
			( gate "C2L26"
				( objectStatus "@baseboard_fab2_lib.baseboard_fab2(sch_1):page173_i255" )
			)
			( gate "C2L38"
				( objectStatus "@baseboard_fab2_lib.baseboard_fab2(sch_1):page173_i256" )
			)
			( gate "C2L48"
				( objectStatus "@baseboard_fab2_lib.baseboard_fab2(sch_1):page173_i257" )
			)
			( gate "C2L24"
				( objectStatus "@baseboard_fab2_lib.baseboard_fab2(sch_1):page173_i258" )
			)
			( gate "C2L21"
				( objectStatus "@baseboard_fab2_lib.baseboard_fab2(sch_1):page173_i259" )
			)
			( gate "R2L23"
				( objectStatus "@baseboard_fab2_lib.baseboard_fab2(sch_1):page173_i261" )
			)
			( gate "R2L21"
				( objectStatus "@baseboard_fab2_lib.baseboard_fab2(sch_1):page173_i263" )
			)
			( gate "R2L22"
				( objectStatus "@baseboard_fab2_lib.baseboard_fab2(sch_1):page173_i264" )
			)
			( gate "R2L18"
				( objectStatus "@baseboard_fab2_lib.baseboard_fab2(sch_1):page173_i266" )
			)
			( gate "R6W41"
				( objectStatus "@baseboard_fab2_lib.baseboard_fab2(sch_1):page164_i87" )
			)
			( gate "C25W29"
				( objectStatus "@baseboard_fab2_lib.baseboard_fab2(sch_1):page149_i129" )
			)
			( gate "R6W44"
				( objectStatus "@baseboard_fab2_lib.baseboard_fab2(sch_1):page164_i78" )
			)
			( gate "R6W47"
				( objectStatus "@baseboard_fab2_lib.baseboard_fab2(sch_1):page164_i76" )
			)
			( gate "C6W14"
				( objectStatus "@baseboard_fab2_lib.baseboard_fab2(sch_1):page164_i66" )
			)
			( gate "R1L31"
				( objectStatus "@baseboard_fab2_lib.baseboard_fab2(sch_1):page175_i4" )
			)
			( gate "R1L27"
				( objectStatus "@baseboard_fab2_lib.baseboard_fab2(sch_1):page175_i5" )
			)
			( gate "C1L18"
				( objectStatus "@baseboard_fab2_lib.baseboard_fab2(sch_1):page175_i11" )
			)
			( gate "R1L26"
				( objectStatus "@baseboard_fab2_lib.baseboard_fab2(sch_1):page175_i13" )
			)
			( gate "C1L10"
				( objectStatus "@baseboard_fab2_lib.baseboard_fab2(sch_1):page175_i19" )
			)
			( gate "R1L22"
				( objectStatus "@baseboard_fab2_lib.baseboard_fab2(sch_1):page175_i22" )
			)
			( gate "R1L28"
				( objectStatus "@baseboard_fab2_lib.baseboard_fab2(sch_1):page111_i97" )
			)
			( gate "C1L17"
				( objectStatus "@baseboard_fab2_lib.baseboard_fab2(sch_1):page175_i37" )
			)
			( gate "C1L9"
				( objectStatus "@baseboard_fab2_lib.baseboard_fab2(sch_1):page175_i38" )
			)
			( gate "C9A3"
				( objectStatus "@baseboard_fab2_lib.baseboard_fab2(sch_1):page175_i40" )
			)
			( gate "R1L33"
				( objectStatus "@baseboard_fab2_lib.baseboard_fab2(sch_1):page175_i45" )
			)
			( gate "Q9A3"
				( objectStatus "@baseboard_fab2_lib.baseboard_fab2(sch_1):page175_i49" )
			)
			( gate "DS9A1"
				( objectStatus "@baseboard_fab2_lib.baseboard_fab2(sch_1):page175_i50" )
			)
			( gate "U1L2"
				( objectStatus "@baseboard_fab2_lib.baseboard_fab2(sch_1):page175_i57" )
			)
			( gate "R1L8"
				( objectStatus "@baseboard_fab2_lib.baseboard_fab2(sch_1):page175_i58" )
			)
			( gate "R1L12"
				( objectStatus "@baseboard_fab2_lib.baseboard_fab2(sch_1):page175_i63" )
			)
			( gate "C1L4"
				( objectStatus "@baseboard_fab2_lib.baseboard_fab2(sch_1):page175_i64" )
			)
			( gate "DS9A3"
				( objectStatus "@baseboard_fab2_lib.baseboard_fab2(sch_1):page175_i67" )
			)
			( gate "S9A1"
				( objectStatus "@baseboard_fab2_lib.baseboard_fab2(sch_1):page175_i78" )
			)
			( gate "U3T1"
				( objectStatus "@baseboard_fab2_lib.baseboard_fab2(sch_1):page153_i185" )
			)
			( gate "R1M5"
				( objectStatus "@baseboard_fab2_lib.baseboard_fab2(sch_1):page176_i16" )
			)
			( gate "R1M6"
				( objectStatus "@baseboard_fab2_lib.baseboard_fab2(sch_1):page176_i31" )
			)
			( gate "J9B1"
				( objectStatus "@baseboard_fab2_lib.baseboard_fab2(sch_1):page176_i69" )
			)
			( gate "CR1M2"
				( objectStatus "@baseboard_fab2_lib.baseboard_fab2(sch_1):page176_i98" )
			)
			( gate "U1M3"
				( objectStatus "@baseboard_fab2_lib.baseboard_fab2(sch_1):page176_i100" )
			)
			( gate "R1M24"
				( objectStatus "@baseboard_fab2_lib.baseboard_fab2(sch_1):page176_i105" )
			)
			( gate "C1M38"
				( objectStatus "@baseboard_fab2_lib.baseboard_fab2(sch_1):page176_i108" )
			)
			( gate "R1M25"
				( objectStatus "@baseboard_fab2_lib.baseboard_fab2(sch_1):page176_i111" )
			)
			( gate "C9B8"
				( objectStatus "@baseboard_fab2_lib.baseboard_fab2(sch_1):page176_i113" )
			)
			( gate "R1M13"
				( objectStatus "@baseboard_fab2_lib.baseboard_fab2(sch_1):page177_i3" )
			)
			( gate "R1M10"
				( objectStatus "@baseboard_fab2_lib.baseboard_fab2(sch_1):page177_i6" )
			)
			( gate "R1M12"
				( objectStatus "@baseboard_fab2_lib.baseboard_fab2(sch_1):page177_i8" )
			)
			( gate "R1M11"
				( objectStatus "@baseboard_fab2_lib.baseboard_fab2(sch_1):page177_i9" )
			)
			( gate "C1M3"
				( objectStatus "@baseboard_fab2_lib.baseboard_fab2(sch_1):page177_i20" )
			)
			( gate "DS9A6"
				( objectStatus "@baseboard_fab2_lib.baseboard_fab2(sch_1):page177_i31" )
			)
			( gate "R1L37"
				( objectStatus "@baseboard_fab2_lib.baseboard_fab2(sch_1):page177_i33" )
			)
			( gate "DS9A2"
				( objectStatus "@baseboard_fab2_lib.baseboard_fab2(sch_1):page177_i42" )
			)
			( gate "R1L21"
				( objectStatus "@baseboard_fab2_lib.baseboard_fab2(sch_1):page177_i43" )
			)
			( gate "U1M1"
				( objectStatus "@baseboard_fab2_lib.baseboard_fab2(sch_1):page177_i70" )
			)
			( gate "DS9F1"
				( objectStatus "@baseboard_fab2_lib.baseboard_fab2(sch_1):page177_i71" )
			)
			( gate "R9F28"
				( objectStatus "@baseboard_fab2_lib.baseboard_fab2(sch_1):page177_i72" )
			)
			( gate "R9F30"
				( objectStatus "@baseboard_fab2_lib.baseboard_fab2(sch_1):page177_i76" )
			)
			( gate "Q9F1"
				( objectStatus "@baseboard_fab2_lib.baseboard_fab2(sch_1):page177_i79" )
			)
			( gate "Q9F1"
				( objectStatus "@baseboard_fab2_lib.baseboard_fab2(sch_1):page177_i80" )
			)
			( gate "R9F52"
				( objectStatus "@baseboard_fab2_lib.baseboard_fab2(sch_1):page177_i82" )
			)
			( gate "R8D20"
				( objectStatus "@baseboard_fab2_lib.baseboard_fab2(sch_1):page178_i1" )
			)
			( gate "R2L12"
				( objectStatus "@baseboard_fab2_lib.baseboard_fab2(sch_1):page178_i2" )
			)
			( gate "R8D19"
				( objectStatus "@baseboard_fab2_lib.baseboard_fab2(sch_1):page178_i8" )
			)
			( gate "R2N31"
				( objectStatus "@baseboard_fab2_lib.baseboard_fab2(sch_1):page178_i11" )
			)
			( gate "R2L15"
				( objectStatus "@baseboard_fab2_lib.baseboard_fab2(sch_1):page178_i12" )
			)
			( gate "R2L11"
				( objectStatus "@baseboard_fab2_lib.baseboard_fab2(sch_1):page178_i13" )
			)
			( gate "R2L6"
				( objectStatus "@baseboard_fab2_lib.baseboard_fab2(sch_1):page178_i17" )
			)
			( gate "R2L4"
				( objectStatus "@baseboard_fab2_lib.baseboard_fab2(sch_1):page178_i18" )
			)
			( gate "R2L5"
				( objectStatus "@baseboard_fab2_lib.baseboard_fab2(sch_1):page178_i20" )
			)
			( gate "R8B29"
				( objectStatus "@baseboard_fab2_lib.baseboard_fab2(sch_1):page178_i21" )
			)
			( gate "R2N19"
				( objectStatus "@baseboard_fab2_lib.baseboard_fab2(sch_1):page178_i22" )
			)
			( gate "R2N22"
				( objectStatus "@baseboard_fab2_lib.baseboard_fab2(sch_1):page178_i23" )
			)
			( gate "C9N17"
				( objectStatus "@baseboard_fab2_lib.baseboard_fab2(sch_1):page182_i38" )
			)
			( gate "C9N18"
				( objectStatus "@baseboard_fab2_lib.baseboard_fab2(sch_1):page182_i39" )
			)
			( gate "C9N1"
				( objectStatus "@baseboard_fab2_lib.baseboard_fab2(sch_1):page182_i40" )
			)
			( gate "R9F69"
				( objectStatus "@baseboard_fab2_lib.baseboard_fab2(sch_1):page158_i150" )
			)
			( gate "R9F68"
				( objectStatus "@baseboard_fab2_lib.baseboard_fab2(sch_1):page158_i149" )
			)
			( gate "C9N15"
				( objectStatus "@baseboard_fab2_lib.baseboard_fab2(sch_1):page182_i41" )
			)
			( gate "C9N6"
				( objectStatus "@baseboard_fab2_lib.baseboard_fab2(sch_1):page182_i42" )
			)
			( gate "C9N14"
				( objectStatus "@baseboard_fab2_lib.baseboard_fab2(sch_1):page182_i43" )
			)
			( gate "C9N4"
				( objectStatus "@baseboard_fab2_lib.baseboard_fab2(sch_1):page182_i44" )
			)
			( gate "C9N5"
				( objectStatus "@baseboard_fab2_lib.baseboard_fab2(sch_1):page182_i45" )
			)
			( gate "C9N16"
				( objectStatus "@baseboard_fab2_lib.baseboard_fab2(sch_1):page182_i46" )
			)
			( gate "C9N3"
				( objectStatus "@baseboard_fab2_lib.baseboard_fab2(sch_1):page182_i47" )
			)
			( gate "C9N7"
				( objectStatus "@baseboard_fab2_lib.baseboard_fab2(sch_1):page182_i48" )
			)
			( gate "C9N10"
				( objectStatus "@baseboard_fab2_lib.baseboard_fab2(sch_1):page182_i49" )
			)
			( gate "C9N9"
				( objectStatus "@baseboard_fab2_lib.baseboard_fab2(sch_1):page182_i52" )
			)
			( gate "C9N8"
				( objectStatus "@baseboard_fab2_lib.baseboard_fab2(sch_1):page182_i53" )
			)
			( gate "J8E1"
				( objectStatus "@baseboard_fab2_lib.baseboard_fab2(sch_1):page184_i87" )
			)
			( gate "R8E9"
				( objectStatus "@baseboard_fab2_lib.baseboard_fab2(sch_1):page184_i88" )
			)
			( gate "R8D35"
				( objectStatus "@baseboard_fab2_lib.baseboard_fab2(sch_1):page184_i92" )
			)
			( gate "R8E13"
				( objectStatus "@baseboard_fab2_lib.baseboard_fab2(sch_1):page184_i93" )
			)
			( gate "R8E10"
				( objectStatus "@baseboard_fab2_lib.baseboard_fab2(sch_1):page184_i95" )
			)
			( gate "R8E1"
				( objectStatus "@baseboard_fab2_lib.baseboard_fab2(sch_1):page184_i99" )
			)
			( gate "RM8D1"
				( objectStatus "@baseboard_fab2_lib.baseboard_fab2(sch_1):page184_i104" )
			)
			( gate "C2T13"
				( objectStatus "@baseboard_fab2_lib.baseboard_fab2(sch_1):page185_i172" )
			)
			( gate "C2T14"
				( objectStatus "@baseboard_fab2_lib.baseboard_fab2(sch_1):page185_i171" )
			)
			( gate "C2T23"
				( objectStatus "@baseboard_fab2_lib.baseboard_fab2(sch_1):page185_i180" )
			)
			( gate "C2T20"
				( objectStatus "@baseboard_fab2_lib.baseboard_fab2(sch_1):page185_i179" )
			)
			( gate "C3P33"
				( objectStatus "@baseboard_fab2_lib.baseboard_fab2(sch_1):page107_i477" )
			)
			( gate "C8F11"
				( objectStatus "@baseboard_fab2_lib.baseboard_fab2(sch_1):page185_i139" )
			)
			( gate "C8F7"
				( objectStatus "@baseboard_fab2_lib.baseboard_fab2(sch_1):page185_i96" )
			)
			( gate "C3P16"
				( objectStatus "@baseboard_fab2_lib.baseboard_fab2(sch_1):page107_i476" )
			)
			( gate "C3P36"
				( objectStatus "@baseboard_fab2_lib.baseboard_fab2(sch_1):page107_i475" )
			)
			( gate "C3P41"
				( objectStatus "@baseboard_fab2_lib.baseboard_fab2(sch_1):page107_i474" )
			)
			( gate "R8F18"
				( objectStatus "@baseboard_fab2_lib.baseboard_fab2(sch_1):page185_i105" )
			)
			( gate "R8F21"
				( objectStatus "@baseboard_fab2_lib.baseboard_fab2(sch_1):page185_i106" )
			)
			( gate "U2P1"
				( objectStatus "@baseboard_fab2_lib.baseboard_fab2(sch_1):page185_i110" )
			)
			( gate "R2P15"
				( objectStatus "@baseboard_fab2_lib.baseboard_fab2(sch_1):page185_i111" )
			)
			( gate "R2P16"
				( objectStatus "@baseboard_fab2_lib.baseboard_fab2(sch_1):page185_i113" )
			)
			( gate "R2P14"
				( objectStatus "@baseboard_fab2_lib.baseboard_fab2(sch_1):page185_i115" )
			)
			( gate "C2P9"
				( objectStatus "@baseboard_fab2_lib.baseboard_fab2(sch_1):page185_i117" )
			)
			( gate "C2T29"
				( objectStatus "@baseboard_fab2_lib.baseboard_fab2(sch_1):page185_i120" )
			)
			( gate "C2T26"
				( objectStatus "@baseboard_fab2_lib.baseboard_fab2(sch_1):page185_i123" )
			)
			( gate "C2T21"
				( objectStatus "@baseboard_fab2_lib.baseboard_fab2(sch_1):page185_i124" )
			)
			( gate "C2T16"
				( objectStatus "@baseboard_fab2_lib.baseboard_fab2(sch_1):page185_i126" )
			)
			( gate "C2T15"
				( objectStatus "@baseboard_fab2_lib.baseboard_fab2(sch_1):page185_i127" )
			)
			( gate "C2T24"
				( objectStatus "@baseboard_fab2_lib.baseboard_fab2(sch_1):page185_i129" )
			)
			( gate "C2T2"
				( objectStatus "@baseboard_fab2_lib.baseboard_fab2(sch_1):page185_i131" )
			)
			( gate "C2T4"
				( objectStatus "@baseboard_fab2_lib.baseboard_fab2(sch_1):page185_i132" )
			)
			( gate "C2T5"
				( objectStatus "@baseboard_fab2_lib.baseboard_fab2(sch_1):page185_i135" )
			)
			( gate "R8F36"
				( objectStatus "@baseboard_fab2_lib.baseboard_fab2(sch_1):page185_i136" )
			)
			( gate "C1M27"
				( objectStatus "@baseboard_fab2_lib.baseboard_fab2(sch_1):page186_i3" )
			)
			( gate "C1M26"
				( objectStatus "@baseboard_fab2_lib.baseboard_fab2(sch_1):page186_i6" )
			)
			( gate "C1M23"
				( objectStatus "@baseboard_fab2_lib.baseboard_fab2(sch_1):page186_i7" )
			)
			( gate "C1M22"
				( objectStatus "@baseboard_fab2_lib.baseboard_fab2(sch_1):page186_i8" )
			)
			( gate "C1M24"
				( objectStatus "@baseboard_fab2_lib.baseboard_fab2(sch_1):page186_i10" )
			)
			( gate "R1M14"
				( objectStatus "@baseboard_fab2_lib.baseboard_fab2(sch_1):page186_i220" )
			)
			( gate "RT2"
				( objectStatus "@baseboard_fab2_lib.baseboard_fab2(sch_1):page202_i114" )
			)
			( gate "C1M20"
				( objectStatus "@baseboard_fab2_lib.baseboard_fab2(sch_1):page186_i270" )
			)
			( gate "C1M21"
				( objectStatus "@baseboard_fab2_lib.baseboard_fab2(sch_1):page186_i334" )
			)
			( gate "C1M25"
				( objectStatus "@baseboard_fab2_lib.baseboard_fab2(sch_1):page186_i335" )
			)
			( gate "J9B3"
				( objectStatus "@baseboard_fab2_lib.baseboard_fab2(sch_1):page186_i336" )
			)
			( gate "R1M16"
				( objectStatus "@baseboard_fab2_lib.baseboard_fab2(sch_1):page186_i337" )
			)
			( gate "R1M17"
				( objectStatus "@baseboard_fab2_lib.baseboard_fab2(sch_1):page186_i338" )
			)
			( gate "R1M15"
				( objectStatus "@baseboard_fab2_lib.baseboard_fab2(sch_1):page186_i339" )
			)
			( gate "R1M18"
				( objectStatus "@baseboard_fab2_lib.baseboard_fab2(sch_1):page186_i340" )
			)
			( gate "C9B10"
				( objectStatus "@baseboard_fab2_lib.baseboard_fab2(sch_1):page186_i345" )
			)
			( gate "C1C18"
				( objectStatus "@baseboard_fab2_lib.baseboard_fab2(sch_1):page209_i89" )
			)
			( gate "J8E3"
				( objectStatus "@baseboard_fab2_lib.baseboard_fab2(sch_1):page187_i119" )
			)
			( gate "R9E10"
				( objectStatus "@baseboard_fab2_lib.baseboard_fab2(sch_1):page187_i145" )
			)
			( gate "R9E11"
				( objectStatus "@baseboard_fab2_lib.baseboard_fab2(sch_1):page187_i150" )
			)
			( gate "R9E12"
				( objectStatus "@baseboard_fab2_lib.baseboard_fab2(sch_1):page187_i153" )
			)
			( gate "C2R15"
				( objectStatus "@baseboard_fab2_lib.baseboard_fab2(sch_1):page188_i2" )
			)
			( gate "C2R18"
				( objectStatus "@baseboard_fab2_lib.baseboard_fab2(sch_1):page188_i3" )
			)
			( gate "C2P11"
				( objectStatus "@baseboard_fab2_lib.baseboard_fab2(sch_1):page188_i21" )
			)
			( gate "C2P12"
				( objectStatus "@baseboard_fab2_lib.baseboard_fab2(sch_1):page188_i23" )
			)
			( gate "C2R17"
				( objectStatus "@baseboard_fab2_lib.baseboard_fab2(sch_1):page188_i25" )
			)
			( gate "J8E4"
				( objectStatus "@baseboard_fab2_lib.baseboard_fab2(sch_1):page188_i27" )
			)
			( gate "C2R16"
				( objectStatus "@baseboard_fab2_lib.baseboard_fab2(sch_1):page188_i40" )
			)
			( gate "C2P10"
				( objectStatus "@baseboard_fab2_lib.baseboard_fab2(sch_1):page188_i41" )
			)
			( gate "C2P16"
				( objectStatus "@baseboard_fab2_lib.baseboard_fab2(sch_1):page188_i53" )
			)
			( gate "C2P15"
				( objectStatus "@baseboard_fab2_lib.baseboard_fab2(sch_1):page188_i55" )
			)
			( gate "C2P14"
				( objectStatus "@baseboard_fab2_lib.baseboard_fab2(sch_1):page188_i56" )
			)
			( gate "C2P13"
				( objectStatus "@baseboard_fab2_lib.baseboard_fab2(sch_1):page188_i57" )
			)
			( gate "C8C15"
				( objectStatus "@baseboard_fab2_lib.baseboard_fab2(sch_1):page188_i82" )
			)
			( gate "C8C14"
				( objectStatus "@baseboard_fab2_lib.baseboard_fab2(sch_1):page188_i86" )
			)
			( gate "R1R18"
				( objectStatus "@baseboard_fab2_lib.baseboard_fab2(sch_1):page188_i88" )
			)
			( gate "R1R19"
				( objectStatus "@baseboard_fab2_lib.baseboard_fab2(sch_1):page188_i89" )
			)
			( gate "R1R21"
				( objectStatus "@baseboard_fab2_lib.baseboard_fab2(sch_1):page188_i90" )
			)
			( gate "R1R20"
				( objectStatus "@baseboard_fab2_lib.baseboard_fab2(sch_1):page188_i91" )
			)
			( gate "R1R22"
				( objectStatus "@baseboard_fab2_lib.baseboard_fab2(sch_1):page188_i92" )
			)
			( gate "R1R16"
				( objectStatus "@baseboard_fab2_lib.baseboard_fab2(sch_1):page188_i93" )
			)
			( gate "R1R17"
				( objectStatus "@baseboard_fab2_lib.baseboard_fab2(sch_1):page188_i94" )
			)
			( gate "R1R23"
				( objectStatus "@baseboard_fab2_lib.baseboard_fab2(sch_1):page188_i95" )
			)
			( gate "R8G10"
				( objectStatus "@baseboard_fab2_lib.baseboard_fab2(sch_1):page189_i7" )
			)
			( gate "R7G19"
				( objectStatus "@baseboard_fab2_lib.baseboard_fab2(sch_1):page189_i8" )
			)
			( gate "R8G9"
				( objectStatus "@baseboard_fab2_lib.baseboard_fab2(sch_1):page189_i9" )
			)
			( gate "R7G18"
				( objectStatus "@baseboard_fab2_lib.baseboard_fab2(sch_1):page189_i13" )
			)
			( gate "R8G8"
				( objectStatus "@baseboard_fab2_lib.baseboard_fab2(sch_1):page189_i17" )
			)
			( gate "R8G7"
				( objectStatus "@baseboard_fab2_lib.baseboard_fab2(sch_1):page189_i18" )
			)
			( gate "R8G11"
				( objectStatus "@baseboard_fab2_lib.baseboard_fab2(sch_1):page189_i19" )
			)
			( gate "R8G14"
				( objectStatus "@baseboard_fab2_lib.baseboard_fab2(sch_1):page189_i20" )
			)
			( gate "R8G12"
				( objectStatus "@baseboard_fab2_lib.baseboard_fab2(sch_1):page189_i21" )
			)
			( gate "R8G16"
				( objectStatus "@baseboard_fab2_lib.baseboard_fab2(sch_1):page189_i22" )
			)
			( gate "R8G13"
				( objectStatus "@baseboard_fab2_lib.baseboard_fab2(sch_1):page189_i23" )
			)
			( gate "R8G15"
				( objectStatus "@baseboard_fab2_lib.baseboard_fab2(sch_1):page189_i24" )
			)
			( gate "R8G17"
				( objectStatus "@baseboard_fab2_lib.baseboard_fab2(sch_1):page189_i25" )
			)
			( gate "R8G18"
				( objectStatus "@baseboard_fab2_lib.baseboard_fab2(sch_1):page189_i26" )
			)
			( gate "R7G16"
				( objectStatus "@baseboard_fab2_lib.baseboard_fab2(sch_1):page189_i27" )
			)
			( gate "R7G15"
				( objectStatus "@baseboard_fab2_lib.baseboard_fab2(sch_1):page189_i36" )
			)
			( gate "R7G17"
				( objectStatus "@baseboard_fab2_lib.baseboard_fab2(sch_1):page189_i37" )
			)
			( gate "R7G14"
				( objectStatus "@baseboard_fab2_lib.baseboard_fab2(sch_1):page189_i38" )
			)
			( gate "R3R15"
				( objectStatus "@baseboard_fab2_lib.baseboard_fab2(sch_1):page189_i44" )
			)
			( gate "R3R11"
				( objectStatus "@baseboard_fab2_lib.baseboard_fab2(sch_1):page189_i45" )
			)
			( gate "J7G2"
				( objectStatus "@baseboard_fab2_lib.baseboard_fab2(sch_1):page189_i47" )
			)
			( gate "CR3U1"
				( objectStatus "@baseboard_fab2_lib.baseboard_fab2(sch_1):page189_i49" )
			)
			( gate "R8G20"
				( objectStatus "@baseboard_fab2_lib.baseboard_fab2(sch_1):page189_i50" )
			)
			( gate "R7G23"
				( objectStatus "@baseboard_fab2_lib.baseboard_fab2(sch_1):page189_i51" )
			)
			( gate "R7G22"
				( objectStatus "@baseboard_fab2_lib.baseboard_fab2(sch_1):page189_i53" )
			)
			( gate "R8G23"
				( objectStatus "@baseboard_fab2_lib.baseboard_fab2(sch_1):page189_i56" )
			)
			( gate "R7G21"
				( objectStatus "@baseboard_fab2_lib.baseboard_fab2(sch_1):page189_i63" )
			)
			( gate "R8G19"
				( objectStatus "@baseboard_fab2_lib.baseboard_fab2(sch_1):page189_i64" )
			)
			( gate "R8G21"
				( objectStatus "@baseboard_fab2_lib.baseboard_fab2(sch_1):page189_i65" )
			)
			( gate "R8G22"
				( objectStatus "@baseboard_fab2_lib.baseboard_fab2(sch_1):page189_i66" )
			)
			( gate "R3P34"
				( objectStatus "@baseboard_fab2_lib.baseboard_fab2(sch_1):page190_i116" )
			)
			( gate "R3P35"
				( objectStatus "@baseboard_fab2_lib.baseboard_fab2(sch_1):page190_i117" )
			)
			( gate "U8D7"
				( objectStatus "@baseboard_fab2_lib.baseboard_fab2(sch_1):page190_i179" )
			)
			( gate "R2R2"
				( objectStatus "@baseboard_fab2_lib.baseboard_fab2(sch_1):page190_i338" )
			)
			( gate "U8D7"
				( objectStatus "@baseboard_fab2_lib.baseboard_fab2(sch_1):page191_i59" )
			)
			( gate "R2R6"
				( objectStatus "@baseboard_fab2_lib.baseboard_fab2(sch_1):page191_i166" )
			)
			( gate "R2R7"
				( objectStatus "@baseboard_fab2_lib.baseboard_fab2(sch_1):page191_i172" )
			)
			( gate "R2R4"
				( objectStatus "@baseboard_fab2_lib.baseboard_fab2(sch_1):page191_i184" )
			)
			( gate "R7D42"
				( objectStatus "@baseboard_fab2_lib.baseboard_fab2(sch_1):page191_i193" )
			)
			( gate "C2P8"
				( objectStatus "@baseboard_fab2_lib.baseboard_fab2(sch_1):page192_i1" )
			)
			( gate "C2P5"
				( objectStatus "@baseboard_fab2_lib.baseboard_fab2(sch_1):page192_i3" )
			)
			( gate "C3R1"
				( objectStatus "@baseboard_fab2_lib.baseboard_fab2(sch_1):page192_i4" )
			)
			( gate "C3P43"
				( objectStatus "@baseboard_fab2_lib.baseboard_fab2(sch_1):page192_i6" )
			)
			( gate "C3R3"
				( objectStatus "@baseboard_fab2_lib.baseboard_fab2(sch_1):page192_i7" )
			)
			( gate "C2R1"
				( objectStatus "@baseboard_fab2_lib.baseboard_fab2(sch_1):page192_i8" )
			)
			( gate "C2P2"
				( objectStatus "@baseboard_fab2_lib.baseboard_fab2(sch_1):page192_i9" )
			)
			( gate "C3R2"
				( objectStatus "@baseboard_fab2_lib.baseboard_fab2(sch_1):page192_i10" )
			)
			( gate "C3P51"
				( objectStatus "@baseboard_fab2_lib.baseboard_fab2(sch_1):page192_i11" )
			)
			( gate "C3P47"
				( objectStatus "@baseboard_fab2_lib.baseboard_fab2(sch_1):page192_i12" )
			)
			( gate "U8D7"
				( objectStatus "@baseboard_fab2_lib.baseboard_fab2(sch_1):page192_i14" )
			)
			( gate "C2R5"
				( objectStatus "@baseboard_fab2_lib.baseboard_fab2(sch_1):page192_i15" )
			)
			( gate "C2P4"
				( objectStatus "@baseboard_fab2_lib.baseboard_fab2(sch_1):page192_i16" )
			)
			( gate "C3P52"
				( objectStatus "@baseboard_fab2_lib.baseboard_fab2(sch_1):page192_i17" )
			)
			( gate "C2P6"
				( objectStatus "@baseboard_fab2_lib.baseboard_fab2(sch_1):page192_i18" )
			)
			( gate "C2R3"
				( objectStatus "@baseboard_fab2_lib.baseboard_fab2(sch_1):page192_i19" )
			)
			( gate "C2P7"
				( objectStatus "@baseboard_fab2_lib.baseboard_fab2(sch_1):page192_i20" )
			)
			( gate "C2R4"
				( objectStatus "@baseboard_fab2_lib.baseboard_fab2(sch_1):page192_i21" )
			)
			( gate "C2P3"
				( objectStatus "@baseboard_fab2_lib.baseboard_fab2(sch_1):page192_i22" )
			)
			( gate "C3P44"
				( objectStatus "@baseboard_fab2_lib.baseboard_fab2(sch_1):page192_i23" )
			)
			( gate "C3P48"
				( objectStatus "@baseboard_fab2_lib.baseboard_fab2(sch_1):page192_i25" )
			)
			( gate "C2R2"
				( objectStatus "@baseboard_fab2_lib.baseboard_fab2(sch_1):page192_i28" )
			)
			( gate "R7E6"
				( objectStatus "@baseboard_fab2_lib.baseboard_fab2(sch_1):page192_i33" )
			)
			( gate "R2R1"
				( objectStatus "@baseboard_fab2_lib.baseboard_fab2(sch_1):page192_i34" )
			)
			( gate "R7E5"
				( objectStatus "@baseboard_fab2_lib.baseboard_fab2(sch_1):page192_i38" )
			)
			( gate "R2R3"
				( objectStatus "@baseboard_fab2_lib.baseboard_fab2(sch_1):page192_i41" )
			)
			( gate "R3R16"
				( objectStatus "@baseboard_fab2_lib.baseboard_fab2(sch_1):page192_i48" )
			)
			( gate "R6M9"
				( objectStatus "@baseboard_fab2_lib.baseboard_fab2(sch_1):page192_i49" )
			)
			( gate "R7E18"
				( objectStatus "@baseboard_fab2_lib.baseboard_fab2(sch_1):page192_i55" )
			)
			( gate "R7E19"
				( objectStatus "@baseboard_fab2_lib.baseboard_fab2(sch_1):page192_i57" )
			)
			( gate "R7E20"
				( objectStatus "@baseboard_fab2_lib.baseboard_fab2(sch_1):page192_i59" )
			)
			( gate "C4C1"
				( objectStatus "@baseboard_fab2_lib.baseboard_fab2(sch_1):page193_i29" )
			)
			( gate "C3C2"
				( objectStatus "@baseboard_fab2_lib.baseboard_fab2(sch_1):page193_i31" )
			)
			( gate "C3C1"
				( objectStatus "@baseboard_fab2_lib.baseboard_fab2(sch_1):page193_i38" )
			)
			( gate "J4E1"
				( objectStatus "@baseboard_fab2_lib.baseboard_fab2(sch_1):page193_i45" )
			)
			( gate "J4B2"
				( objectStatus "@baseboard_fab2_lib.baseboard_fab2(sch_1):page193_i46" )
			)
			( gate "C4E24"
				( objectStatus "@baseboard_fab2_lib.baseboard_fab2(sch_1):page193_i61" )
			)
			( gate "C6R16"
				( objectStatus "@baseboard_fab2_lib.baseboard_fab2(sch_1):page193_i62" )
			)
			( gate "C4F1"
				( objectStatus "@baseboard_fab2_lib.baseboard_fab2(sch_1):page193_i68" )
			)
			( gate "C4F3"
				( objectStatus "@baseboard_fab2_lib.baseboard_fab2(sch_1):page193_i70" )
			)
			( gate "C3F1"
				( objectStatus "@baseboard_fab2_lib.baseboard_fab2(sch_1):page193_i140" )
			)
			( gate "C4F2"
				( objectStatus "@baseboard_fab2_lib.baseboard_fab2(sch_1):page193_i141" )
			)
			( gate "R4C12"
				( objectStatus "@baseboard_fab2_lib.baseboard_fab2(sch_1):page193_i169" )
			)
			( gate "R4C11"
				( objectStatus "@baseboard_fab2_lib.baseboard_fab2(sch_1):page193_i170" )
			)
			( gate "C4T2"
				( objectStatus "@baseboard_fab2_lib.baseboard_fab2(sch_1):page194_i9" )
			)
			( gate "C4T1"
				( objectStatus "@baseboard_fab2_lib.baseboard_fab2(sch_1):page194_i16" )
			)
			( gate "C4R1"
				( objectStatus "@baseboard_fab2_lib.baseboard_fab2(sch_1):page194_i29" )
			)
			( gate "C3R4"
				( objectStatus "@baseboard_fab2_lib.baseboard_fab2(sch_1):page194_i31" )
			)
			( gate "J6E1"
				( objectStatus "@baseboard_fab2_lib.baseboard_fab2(sch_1):page194_i55" )
			)
			( gate "J6B1"
				( objectStatus "@baseboard_fab2_lib.baseboard_fab2(sch_1):page194_i56" )
			)
			( gate "C3N40"
				( objectStatus "@baseboard_fab2_lib.baseboard_fab2(sch_1):page194_i86" )
			)
			( gate "C3M46"
				( objectStatus "@baseboard_fab2_lib.baseboard_fab2(sch_1):page194_i99" )
			)
			( gate "C3N14"
				( objectStatus "@baseboard_fab2_lib.baseboard_fab2(sch_1):page194_i101" )
			)
			( gate "C3T1"
				( objectStatus "@baseboard_fab2_lib.baseboard_fab2(sch_1):page194_i149" )
			)
			( gate "C3T2"
				( objectStatus "@baseboard_fab2_lib.baseboard_fab2(sch_1):page194_i150" )
			)
			( gate "R7C24"
				( objectStatus "@baseboard_fab2_lib.baseboard_fab2(sch_1):page194_i155" )
			)
			( gate "R3N29"
				( objectStatus "@baseboard_fab2_lib.baseboard_fab2(sch_1):page194_i156" )
			)
			( gate "RM1E1"
				( objectStatus "@baseboard_fab2_lib.baseboard_fab2(sch_1):page195_i26" )
			)
			( gate "C9R5"
				( objectStatus "@baseboard_fab2_lib.baseboard_fab2(sch_1):page195_i31" )
			)
			( gate "C1E12"
				( objectStatus "@baseboard_fab2_lib.baseboard_fab2(sch_1):page195_i32" )
			)
			( gate "C1E15"
				( objectStatus "@baseboard_fab2_lib.baseboard_fab2(sch_1):page195_i35" )
			)
			( gate "C9R12"
				( objectStatus "@baseboard_fab2_lib.baseboard_fab2(sch_1):page195_i36" )
			)
			( gate "C9R6"
				( objectStatus "@baseboard_fab2_lib.baseboard_fab2(sch_1):page195_i37" )
			)
			( gate "C1E17"
				( objectStatus "@baseboard_fab2_lib.baseboard_fab2(sch_1):page195_i38" )
			)
			( gate "C1E16"
				( objectStatus "@baseboard_fab2_lib.baseboard_fab2(sch_1):page195_i39" )
			)
			( gate "TH4G1"
				( objectStatus "@baseboard_fab2_lib.baseboard_fab2(sch_1):page195_i49" )
			)
			( gate "TH9G1"
				( objectStatus "@baseboard_fab2_lib.baseboard_fab2(sch_1):page195_i52" )
			)
			( gate "TH9A1"
				( objectStatus "@baseboard_fab2_lib.baseboard_fab2(sch_1):page195_i54" )
			)
			( gate "TH1A1"
				( objectStatus "@baseboard_fab2_lib.baseboard_fab2(sch_1):page195_i56" )
			)
			( gate "TH4A1"
				( objectStatus "@baseboard_fab2_lib.baseboard_fab2(sch_1):page195_i62" )
			)
			( gate "TH7A1"
				( objectStatus "@baseboard_fab2_lib.baseboard_fab2(sch_1):page195_i65" )
			)
			( gate "TH7G1"
				( objectStatus "@baseboard_fab2_lib.baseboard_fab2(sch_1):page195_i67" )
			)
			( gate "C4F6"
				( objectStatus "@baseboard_fab2_lib.baseboard_fab2(sch_1):page195_i82" )
			)
			( gate "C4B13"
				( objectStatus "@baseboard_fab2_lib.baseboard_fab2(sch_1):page195_i83" )
			)
			( gate "C1B14"
				( objectStatus "@baseboard_fab2_lib.baseboard_fab2(sch_1):page195_i84" )
			)
			( gate "C1F7"
				( objectStatus "@baseboard_fab2_lib.baseboard_fab2(sch_1):page195_i85" )
			)
			( gate "C4F5"
				( objectStatus "@baseboard_fab2_lib.baseboard_fab2(sch_1):page195_i96" )
			)
			( gate "C4B14"
				( objectStatus "@baseboard_fab2_lib.baseboard_fab2(sch_1):page195_i97" )
			)
			( gate "C3T6"
				( objectStatus "@baseboard_fab2_lib.baseboard_fab2(sch_1):page195_i98" )
			)
			( gate "C9M3"
				( objectStatus "@baseboard_fab2_lib.baseboard_fab2(sch_1):page195_i99" )
			)
			( gate "C3B6"
				( objectStatus "@baseboard_fab2_lib.baseboard_fab2(sch_1):page195_i100" )
			)
			( gate "C1R23"
				( objectStatus "@baseboard_fab2_lib.baseboard_fab2(sch_1):page195_i101" )
			)
			( gate "C4M6"
				( objectStatus "@baseboard_fab2_lib.baseboard_fab2(sch_1):page195_i102" )
			)
			( gate "C1M5"
				( objectStatus "@baseboard_fab2_lib.baseboard_fab2(sch_1):page195_i103" )
			)
			( gate "C3T13"
				( objectStatus "@baseboard_fab2_lib.baseboard_fab2(sch_1):page195_i104" )
			)
			( gate "C4M7"
				( objectStatus "@baseboard_fab2_lib.baseboard_fab2(sch_1):page195_i105" )
			)
			( gate "C3T15"
				( objectStatus "@baseboard_fab2_lib.baseboard_fab2(sch_1):page195_i106" )
			)
			( gate "C7M6"
				( objectStatus "@baseboard_fab2_lib.baseboard_fab2(sch_1):page195_i108" )
			)
			( gate "C6N5"
				( objectStatus "@baseboard_fab2_lib.baseboard_fab2(sch_1):page195_i109" )
			)
			( gate "C9T3"
				( objectStatus "@baseboard_fab2_lib.baseboard_fab2(sch_1):page195_i111" )
			)
			( gate "C4F4"
				( objectStatus "@baseboard_fab2_lib.baseboard_fab2(sch_1):page195_i112" )
			)
			( gate "C3T3"
				( objectStatus "@baseboard_fab2_lib.baseboard_fab2(sch_1):page195_i113" )
			)
			( gate "R2U43"
				( objectStatus "@baseboard_fab2_lib.baseboard_fab2(sch_1):page196_i46" )
			)
			( gate "BT8G1"
				( objectStatus "@baseboard_fab2_lib.baseboard_fab2(sch_1):page196_i47" )
			)
			( gate "XBT8G1"
				( objectStatus "@baseboard_fab2_lib.baseboard_fab2(sch_1):page196_i51" )
			)
			( gate "CR2U1"
				( objectStatus "@baseboard_fab2_lib.baseboard_fab2(sch_1):page196_i53" )
			)
			( gate "R3P44"
				( objectStatus "@baseboard_fab2_lib.baseboard_fab2(sch_1):page196_i59" )
			)
			( gate "C3P45"
				( objectStatus "@baseboard_fab2_lib.baseboard_fab2(sch_1):page196_i60" )
			)
			( gate "R2P20"
				( objectStatus "@baseboard_fab2_lib.baseboard_fab2(sch_1):page196_i65" )
			)
			( gate "R1L16"
				( objectStatus "@baseboard_fab2_lib.baseboard_fab2(sch_1):page196_i68" )
			)
			( gate "U7D3"
				( objectStatus "@baseboard_fab2_lib.baseboard_fab2(sch_1):page196_i70" )
			)
			( gate "R3P50"
				( objectStatus "@baseboard_fab2_lib.baseboard_fab2(sch_1):page196_i71" )
			)
			( gate "C3P46"
				( objectStatus "@baseboard_fab2_lib.baseboard_fab2(sch_1):page196_i72" )
			)
			( gate "R3P48"
				( objectStatus "@baseboard_fab2_lib.baseboard_fab2(sch_1):page196_i74" )
			)
			( gate "R3P51"
				( objectStatus "@baseboard_fab2_lib.baseboard_fab2(sch_1):page196_i75" )
			)
			( gate "U1L3"
				( objectStatus "@baseboard_fab2_lib.baseboard_fab2(sch_1):page196_i80" )
			)
			( gate "C1L16"
				( objectStatus "@baseboard_fab2_lib.baseboard_fab2(sch_1):page196_i81" )
			)
			( gate "U8E2"
				( objectStatus "@baseboard_fab2_lib.baseboard_fab2(sch_1):page196_i89" )
			)
			( gate "R8E7"
				( objectStatus "@baseboard_fab2_lib.baseboard_fab2(sch_1):page196_i90" )
			)
			( gate "C8E3"
				( objectStatus "@baseboard_fab2_lib.baseboard_fab2(sch_1):page196_i94" )
			)
			( gate "C2U26"
				( objectStatus "@baseboard_fab2_lib.baseboard_fab2(sch_1):page196_i102" )
			)
			( gate "CR7E1"
				( objectStatus "@baseboard_fab2_lib.baseboard_fab2(sch_1):page196_i103" )
			)
			( gate "U8D8"
				( objectStatus "@baseboard_fab2_lib.baseboard_fab2(sch_1):page196_i104" )
			)
			( gate "C8D4"
				( objectStatus "@baseboard_fab2_lib.baseboard_fab2(sch_1):page196_i105" )
			)
			( gate "R8D42"
				( objectStatus "@baseboard_fab2_lib.baseboard_fab2(sch_1):page196_i106" )
			)
			( gate "R8D38"
				( objectStatus "@baseboard_fab2_lib.baseboard_fab2(sch_1):page196_i112" )
			)
			( gate "R9P9"
				( objectStatus "@baseboard_fab2_lib.baseboard_fab2(sch_1):page200_i251" )
			)
			( gate "R8D39"
				( objectStatus "@baseboard_fab2_lib.baseboard_fab2(sch_1):page196_i114" )
			)
			( gate "R8D37"
				( objectStatus "@baseboard_fab2_lib.baseboard_fab2(sch_1):page196_i115" )
			)
			( gate "R8D41"
				( objectStatus "@baseboard_fab2_lib.baseboard_fab2(sch_1):page196_i120" )
			)
			( gate "R2P18"
				( objectStatus "@baseboard_fab2_lib.baseboard_fab2(sch_1):page196_i121" )
			)
			( gate "R2P21"
				( objectStatus "@baseboard_fab2_lib.baseboard_fab2(sch_1):page196_i122" )
			)
			( gate "Q7D1"
				( objectStatus "@baseboard_fab2_lib.baseboard_fab2(sch_1):page134_i14" )
			)
			( gate "CR8E1"
				( objectStatus "@baseboard_fab2_lib.baseboard_fab2(sch_1):page196_i128" )
			)
			( gate "EU2T1"
				( objectStatus "@baseboard_fab2_lib.baseboard_fab2(sch_1):page198_i1" )
			)
			( gate "EU8B1"
				( objectStatus "@baseboard_fab2_lib.baseboard_fab2(sch_1):page198_i13" )
			)
			( gate "EU7E1"
				( objectStatus "@baseboard_fab2_lib.baseboard_fab2(sch_1):page198_i19" )
			)
			( gate "C8F17"
				( objectStatus "@baseboard_fab2_lib.baseboard_fab2(sch_1):page198_i24" )
			)
			( gate "C8B8"
				( objectStatus "@baseboard_fab2_lib.baseboard_fab2(sch_1):page198_i26" )
			)
			( gate "C8E19"
				( objectStatus "@baseboard_fab2_lib.baseboard_fab2(sch_1):page198_i28" )
			)
			( gate "C8B5"
				( objectStatus "@baseboard_fab2_lib.baseboard_fab2(sch_1):page198_i37" )
			)
			( gate "C8B12"
				( objectStatus "@baseboard_fab2_lib.baseboard_fab2(sch_1):page198_i38" )
			)
			( gate "C8B6"
				( objectStatus "@baseboard_fab2_lib.baseboard_fab2(sch_1):page198_i40" )
			)
			( gate "C8B7"
				( objectStatus "@baseboard_fab2_lib.baseboard_fab2(sch_1):page198_i41" )
			)
			( gate "C2T36"
				( objectStatus "@baseboard_fab2_lib.baseboard_fab2(sch_1):page198_i43" )
			)
			( gate "C2U1"
				( objectStatus "@baseboard_fab2_lib.baseboard_fab2(sch_1):page198_i44" )
			)
			( gate "C2U19"
				( objectStatus "@baseboard_fab2_lib.baseboard_fab2(sch_1):page198_i46" )
			)
			( gate "C2U2"
				( objectStatus "@baseboard_fab2_lib.baseboard_fab2(sch_1):page198_i47" )
			)
			( gate "C7E9"
				( objectStatus "@baseboard_fab2_lib.baseboard_fab2(sch_1):page198_i49" )
			)
			( gate "C7E8"
				( objectStatus "@baseboard_fab2_lib.baseboard_fab2(sch_1):page198_i50" )
			)
			( gate "C7E5"
				( objectStatus "@baseboard_fab2_lib.baseboard_fab2(sch_1):page198_i52" )
			)
			( gate "C7E6"
				( objectStatus "@baseboard_fab2_lib.baseboard_fab2(sch_1):page198_i53" )
			)
			( gate "C1B18"
				( objectStatus "@baseboard_fab2_lib.baseboard_fab2(sch_1):page198_i61" )
			)
			( gate "C1B19"
				( objectStatus "@baseboard_fab2_lib.baseboard_fab2(sch_1):page198_i64" )
			)
			( gate "C9M6"
				( objectStatus "@baseboard_fab2_lib.baseboard_fab2(sch_1):page198_i67" )
			)
			( gate "EU9M1"
				( objectStatus "@baseboard_fab2_lib.baseboard_fab2(sch_1):page198_i69" )
			)
			( gate "C9M10"
				( objectStatus "@baseboard_fab2_lib.baseboard_fab2(sch_1):page198_i74" )
			)
			( gate "C9M9"
				( objectStatus "@baseboard_fab2_lib.baseboard_fab2(sch_1):page198_i76" )
			)
			( gate "R8E12"
				( objectStatus "@baseboard_fab2_lib.baseboard_fab2(sch_1):page198_i78" )
			)
			( gate "R8B4"
				( objectStatus "@baseboard_fab2_lib.baseboard_fab2(sch_1):page198_i83" )
			)
			( gate "Q8G1"
				( objectStatus "@baseboard_fab2_lib.baseboard_fab2(sch_1):page198_i85" )
			)
			( gate "Q1B1"
				( objectStatus "@baseboard_fab2_lib.baseboard_fab2(sch_1):page198_i86" )
			)
			( gate "Q8B1"
				( objectStatus "@baseboard_fab2_lib.baseboard_fab2(sch_1):page198_i87" )
			)
			( gate "Q7E7"
				( objectStatus "@baseboard_fab2_lib.baseboard_fab2(sch_1):page198_i88" )
			)
			( gate "R9P30"
				( objectStatus "@baseboard_fab2_lib.baseboard_fab2(sch_1):page199_i2" )
			)
			( gate "C1D25"
				( objectStatus "@baseboard_fab2_lib.baseboard_fab2(sch_1):page199_i3" )
			)
			( gate "C1D27"
				( objectStatus "@baseboard_fab2_lib.baseboard_fab2(sch_1):page199_i7" )
			)
			( gate "R1D43"
				( objectStatus "@baseboard_fab2_lib.baseboard_fab2(sch_1):page199_i9" )
			)
			( gate "EU1D2"
				( objectStatus "@baseboard_fab2_lib.baseboard_fab2(sch_1):page199_i10" )
			)
			( gate "R9P29"
				( objectStatus "@baseboard_fab2_lib.baseboard_fab2(sch_1):page199_i12" )
			)
			( gate "R1D42"
				( objectStatus "@baseboard_fab2_lib.baseboard_fab2(sch_1):page199_i13" )
			)
			( gate "R1D37"
				( objectStatus "@baseboard_fab2_lib.baseboard_fab2(sch_1):page199_i15" )
			)
			( gate "R1D39"
				( objectStatus "@baseboard_fab2_lib.baseboard_fab2(sch_1):page199_i16" )
			)
			( gate "R1D32"
				( objectStatus "@baseboard_fab2_lib.baseboard_fab2(sch_1):page199_i17" )
			)
			( gate "R1D41"
				( objectStatus "@baseboard_fab2_lib.baseboard_fab2(sch_1):page199_i19" )
			)
			( gate "C9P14"
				( objectStatus "@baseboard_fab2_lib.baseboard_fab2(sch_1):page199_i24" )
			)
			( gate "R1D28"
				( objectStatus "@baseboard_fab2_lib.baseboard_fab2(sch_1):page199_i26" )
			)
			( gate "R1D24"
				( objectStatus "@baseboard_fab2_lib.baseboard_fab2(sch_1):page199_i27" )
			)
			( gate "R1D25"
				( objectStatus "@baseboard_fab2_lib.baseboard_fab2(sch_1):page199_i28" )
			)
			( gate "R9P17"
				( objectStatus "@baseboard_fab2_lib.baseboard_fab2(sch_1):page199_i33" )
			)
			( gate "R9P16"
				( objectStatus "@baseboard_fab2_lib.baseboard_fab2(sch_1):page199_i36" )
			)
			( gate "R1D27"
				( objectStatus "@baseboard_fab2_lib.baseboard_fab2(sch_1):page199_i38" )
			)
			( gate "R9P18"
				( objectStatus "@baseboard_fab2_lib.baseboard_fab2(sch_1):page199_i41" )
			)
			( gate "R1D31"
				( objectStatus "@baseboard_fab2_lib.baseboard_fab2(sch_1):page199_i43" )
			)
			( gate "C1D11"
				( objectStatus "@baseboard_fab2_lib.baseboard_fab2(sch_1):page199_i53" )
			)
			( gate "R9P23"
				( objectStatus "@baseboard_fab2_lib.baseboard_fab2(sch_1):page199_i54" )
			)
			( gate "R9P24"
				( objectStatus "@baseboard_fab2_lib.baseboard_fab2(sch_1):page199_i55" )
			)
			( gate "Q1D3"
				( objectStatus "@baseboard_fab2_lib.baseboard_fab2(sch_1):page199_i58" )
			)
			( gate "R1D36"
				( objectStatus "@baseboard_fab2_lib.baseboard_fab2(sch_1):page199_i65" )
			)
			( gate "C9P12"
				( objectStatus "@baseboard_fab2_lib.baseboard_fab2(sch_1):page199_i67" )
			)
			( gate "Q1D1"
				( objectStatus "@baseboard_fab2_lib.baseboard_fab2(sch_1):page199_i82" )
			)
			( gate "R1D13"
				( objectStatus "@baseboard_fab2_lib.baseboard_fab2(sch_1):page199_i84" )
			)
			( gate "R1D16"
				( objectStatus "@baseboard_fab2_lib.baseboard_fab2(sch_1):page199_i85" )
			)
			( gate "Q1D1"
				( objectStatus "@baseboard_fab2_lib.baseboard_fab2(sch_1):page199_i86" )
			)
			( gate "R1D11"
				( objectStatus "@baseboard_fab2_lib.baseboard_fab2(sch_1):page199_i88" )
			)
			( gate "R1D15"
				( objectStatus "@baseboard_fab2_lib.baseboard_fab2(sch_1):page199_i92" )
			)
			( gate "VR1D1"
				( objectStatus "@baseboard_fab2_lib.baseboard_fab2(sch_1):page199_i99" )
			)
			( gate "R1D40"
				( objectStatus "@baseboard_fab2_lib.baseboard_fab2(sch_1):page199_i100" )
			)
			( gate "R1D34"
				( objectStatus "@baseboard_fab2_lib.baseboard_fab2(sch_1):page199_i102" )
			)
			( gate "C9P15"
				( objectStatus "@baseboard_fab2_lib.baseboard_fab2(sch_1):page199_i105" )
			)
			( gate "C1D26"
				( objectStatus "@baseboard_fab2_lib.baseboard_fab2(sch_1):page199_i107" )
			)
			( gate "R1D33"
				( objectStatus "@baseboard_fab2_lib.baseboard_fab2(sch_1):page199_i108" )
			)
			( gate "R1D26"
				( objectStatus "@baseboard_fab2_lib.baseboard_fab2(sch_1):page199_i109" )
			)
			( gate "R1D30"
				( objectStatus "@baseboard_fab2_lib.baseboard_fab2(sch_1):page199_i110" )
			)
			( gate "C1D19"
				( objectStatus "@baseboard_fab2_lib.baseboard_fab2(sch_1):page199_i119" )
			)
			( gate "C1D21"
				( objectStatus "@baseboard_fab2_lib.baseboard_fab2(sch_1):page199_i121" )
			)
			( gate "C9P17"
				( objectStatus "@baseboard_fab2_lib.baseboard_fab2(sch_1):page200_i36" )
			)
			( gate "C9P16"
				( objectStatus "@baseboard_fab2_lib.baseboard_fab2(sch_1):page200_i40" )
			)
			( gate "C1D22"
				( objectStatus "@baseboard_fab2_lib.baseboard_fab2(sch_1):page200_i42" )
			)
			( gate "R1D45"
				( objectStatus "@baseboard_fab2_lib.baseboard_fab2(sch_1):page200_i43" )
			)
			( gate "R1D44"
				( objectStatus "@baseboard_fab2_lib.baseboard_fab2(sch_1):page200_i44" )
			)
			( gate "R9P27"
				( objectStatus "@baseboard_fab2_lib.baseboard_fab2(sch_1):page200_i47" )
			)
			( gate "R1D46"
				( objectStatus "@baseboard_fab2_lib.baseboard_fab2(sch_1):page200_i48" )
			)
			( gate "R9R1"
				( objectStatus "@baseboard_fab2_lib.baseboard_fab2(sch_1):page200_i49" )
			)
			( gate "R1D49"
				( objectStatus "@baseboard_fab2_lib.baseboard_fab2(sch_1):page200_i50" )
			)
			( gate "R9P26"
				( objectStatus "@baseboard_fab2_lib.baseboard_fab2(sch_1):page200_i51" )
			)
			( gate "R1D47"
				( objectStatus "@baseboard_fab2_lib.baseboard_fab2(sch_1):page200_i52" )
			)
			( gate "EU1E3"
				( objectStatus "@baseboard_fab2_lib.baseboard_fab2(sch_1):page200_i54" )
			)
			( gate "R1E1"
				( objectStatus "@baseboard_fab2_lib.baseboard_fab2(sch_1):page200_i56" )
			)
			( gate "EU9R1"
				( objectStatus "@baseboard_fab2_lib.baseboard_fab2(sch_1):page200_i57" )
			)
			( gate "R9R4"
				( objectStatus "@baseboard_fab2_lib.baseboard_fab2(sch_1):page200_i58" )
			)
			( gate "EU1E1"
				( objectStatus "@baseboard_fab2_lib.baseboard_fab2(sch_1):page200_i59" )
			)
			( gate "R1D48"
				( objectStatus "@baseboard_fab2_lib.baseboard_fab2(sch_1):page200_i60" )
			)
			( gate "R9P19"
				( objectStatus "@baseboard_fab2_lib.baseboard_fab2(sch_1):page200_i70" )
			)
			( gate "R9P21"
				( objectStatus "@baseboard_fab2_lib.baseboard_fab2(sch_1):page200_i71" )
			)
			( gate "R9P20"
				( objectStatus "@baseboard_fab2_lib.baseboard_fab2(sch_1):page200_i86" )
			)
			( gate "U1D1"
				( objectStatus "@baseboard_fab2_lib.baseboard_fab2(sch_1):page200_i103" )
			)
			( gate "R9P11"
				( objectStatus "@baseboard_fab2_lib.baseboard_fab2(sch_1):page200_i108" )
			)
			( gate "R9P6"
				( objectStatus "@baseboard_fab2_lib.baseboard_fab2(sch_1):page200_i149" )
			)
			( gate "R1D51"
				( objectStatus "@baseboard_fab2_lib.baseboard_fab2(sch_1):page200_i154" )
			)
			( gate "C1E2"
				( objectStatus "@baseboard_fab2_lib.baseboard_fab2(sch_1):page200_i155" )
			)
			( gate "R1D22"
				( objectStatus "@baseboard_fab2_lib.baseboard_fab2(sch_1):page200_i158" )
			)
			( gate "U9P1"
				( objectStatus "@baseboard_fab2_lib.baseboard_fab2(sch_1):page200_i163" )
			)
			( gate "U1D2"
				( objectStatus "@baseboard_fab2_lib.baseboard_fab2(sch_1):page200_i170" )
			)
			( gate "R1D12"
				( objectStatus "@baseboard_fab2_lib.baseboard_fab2(sch_1):page200_i174" )
			)
			( gate "R1D19"
				( objectStatus "@baseboard_fab2_lib.baseboard_fab2(sch_1):page200_i175" )
			)
			( gate "C9P6"
				( objectStatus "@baseboard_fab2_lib.baseboard_fab2(sch_1):page200_i185" )
			)
			( gate "C1D9"
				( objectStatus "@baseboard_fab2_lib.baseboard_fab2(sch_1):page200_i187" )
			)
			( gate "R1D18"
				( objectStatus "@baseboard_fab2_lib.baseboard_fab2(sch_1):page199_i87" )
			)
			( gate "R1D23"
				( objectStatus "@baseboard_fab2_lib.baseboard_fab2(sch_1):page200_i191" )
			)
			( gate "R9P10"
				( objectStatus "@baseboard_fab2_lib.baseboard_fab2(sch_1):page200_i192" )
			)
			( gate "Q9P1"
				( objectStatus "@baseboard_fab2_lib.baseboard_fab2(sch_1):page200_i196" )
			)
			( gate "Q9P1"
				( objectStatus "@baseboard_fab2_lib.baseboard_fab2(sch_1):page200_i199" )
			)
			( gate "U9P2"
				( objectStatus "@baseboard_fab2_lib.baseboard_fab2(sch_1):page200_i200" )
			)
			( gate "C9P11"
				( objectStatus "@baseboard_fab2_lib.baseboard_fab2(sch_1):page200_i201" )
			)
			( gate "Q1D2"
				( objectStatus "@baseboard_fab2_lib.baseboard_fab2(sch_1):page200_i203" )
			)
			( gate "R1D21"
				( objectStatus "@baseboard_fab2_lib.baseboard_fab2(sch_1):page200_i204" )
			)
			( gate "R9P4"
				( objectStatus "@baseboard_fab2_lib.baseboard_fab2(sch_1):page200_i210" )
			)
			( gate "CR9P2"
				( objectStatus "@baseboard_fab2_lib.baseboard_fab2(sch_1):page200_i213" )
			)
			( gate "CR9P1"
				( objectStatus "@baseboard_fab2_lib.baseboard_fab2(sch_1):page200_i214" )
			)
			( gate "R9P5"
				( objectStatus "@baseboard_fab2_lib.baseboard_fab2(sch_1):page200_i215" )
			)
			( gate "R9P12"
				( objectStatus "@baseboard_fab2_lib.baseboard_fab2(sch_1):page200_i218" )
			)
			( gate "CR1F5"
				( objectStatus "@baseboard_fab2_lib.baseboard_fab2(sch_1):page200_i220" )
			)
			( gate "R9P33"
				( objectStatus "@baseboard_fab2_lib.baseboard_fab2(sch_1):page200_i222" )
			)
			( gate "R1D7"
				( objectStatus "@baseboard_fab2_lib.baseboard_fab2(sch_1):page206_i155" )
			)
			( gate "R3L13"
				( objectStatus "@baseboard_fab2_lib.baseboard_fab2(sch_1):page218_i70" )
			)
			( gate "R4D31"
				( objectStatus "@baseboard_fab2_lib.baseboard_fab2(sch_1):page201_i22" )
			)
			( gate "R4D58"
				( objectStatus "@baseboard_fab2_lib.baseboard_fab2(sch_1):page201_i25" )
			)
			( gate "R4D67"
				( objectStatus "@baseboard_fab2_lib.baseboard_fab2(sch_1):page201_i26" )
			)
			( gate "R4E5"
				( objectStatus "@baseboard_fab2_lib.baseboard_fab2(sch_1):page201_i27" )
			)
			( gate "C4D25"
				( objectStatus "@baseboard_fab2_lib.baseboard_fab2(sch_1):page201_i30" )
			)
			( gate "C4D26"
				( objectStatus "@baseboard_fab2_lib.baseboard_fab2(sch_1):page201_i32" )
			)
			( gate "C4D15"
				( objectStatus "@baseboard_fab2_lib.baseboard_fab2(sch_1):page201_i37" )
			)
			( gate "C4D19"
				( objectStatus "@baseboard_fab2_lib.baseboard_fab2(sch_1):page201_i39" )
			)
			( gate "R4D26"
				( objectStatus "@baseboard_fab2_lib.baseboard_fab2(sch_1):page201_i40" )
			)
			( gate "R3P17"
				( objectStatus "@baseboard_fab2_lib.baseboard_fab2(sch_1):page211_i99" )
			)
			( gate "R4D27"
				( objectStatus "@baseboard_fab2_lib.baseboard_fab2(sch_1):page201_i54" )
			)
			( gate "R4D32"
				( objectStatus "@baseboard_fab2_lib.baseboard_fab2(sch_1):page201_i55" )
			)
			( gate "R4E6"
				( objectStatus "@baseboard_fab2_lib.baseboard_fab2(sch_1):page201_i56" )
			)
			( gate "C1C8"
				( objectStatus "@baseboard_fab2_lib.baseboard_fab2(sch_1):page206_i156" )
			)
			( gate "C4D29"
				( objectStatus "@baseboard_fab2_lib.baseboard_fab2(sch_1):page201_i64" )
			)
			( gate "C4D17"
				( objectStatus "@baseboard_fab2_lib.baseboard_fab2(sch_1):page201_i66" )
			)
			( gate "C4D18"
				( objectStatus "@baseboard_fab2_lib.baseboard_fab2(sch_1):page201_i68" )
			)
			( gate "C4D45"
				( objectStatus "@baseboard_fab2_lib.baseboard_fab2(sch_1):page201_i70" )
			)
			( gate "R4D66"
				( objectStatus "@baseboard_fab2_lib.baseboard_fab2(sch_1):page201_i98" )
			)
			( gate "R6P32"
				( objectStatus "@baseboard_fab2_lib.baseboard_fab2(sch_1):page201_i102" )
			)
			( gate "R6P37"
				( objectStatus "@baseboard_fab2_lib.baseboard_fab2(sch_1):page201_i103" )
			)
			( gate "R4E8"
				( objectStatus "@baseboard_fab2_lib.baseboard_fab2(sch_1):page201_i109" )
			)
			( gate "R4D39"
				( objectStatus "@baseboard_fab2_lib.baseboard_fab2(sch_1):page201_i110" )
			)
			( gate "R4E3"
				( objectStatus "@baseboard_fab2_lib.baseboard_fab2(sch_1):page201_i111" )
			)
			( gate "R4E20"
				( objectStatus "@baseboard_fab2_lib.baseboard_fab2(sch_1):page201_i116" )
			)
			( gate "R6P27"
				( objectStatus "@baseboard_fab2_lib.baseboard_fab2(sch_1):page201_i120" )
			)
			( gate "R6P28"
				( objectStatus "@baseboard_fab2_lib.baseboard_fab2(sch_1):page201_i121" )
			)
			( gate "R4D63"
				( objectStatus "@baseboard_fab2_lib.baseboard_fab2(sch_1):page201_i124" )
			)
			( gate "C4D42"
				( objectStatus "@baseboard_fab2_lib.baseboard_fab2(sch_1):page201_i125" )
			)
			( gate "R4D65"
				( objectStatus "@baseboard_fab2_lib.baseboard_fab2(sch_1):page201_i127" )
			)
			( gate "R6P45"
				( objectStatus "@baseboard_fab2_lib.baseboard_fab2(sch_1):page201_i128" )
			)
			( gate "R6P18"
				( objectStatus "@baseboard_fab2_lib.baseboard_fab2(sch_1):page201_i131" )
			)
			( gate "R6P16"
				( objectStatus "@baseboard_fab2_lib.baseboard_fab2(sch_1):page201_i132" )
			)
			( gate "EU4D4"
				( objectStatus "@baseboard_fab2_lib.baseboard_fab2(sch_1):page201_i155" )
			)
			( gate "L4D3"
				( objectStatus "@baseboard_fab2_lib.baseboard_fab2(sch_1):page202_i110" )
			)
			( gate "C6R7"
				( objectStatus "@baseboard_fab2_lib.baseboard_fab2(sch_1):page202_i9" )
			)
			( gate "C4E5"
				( objectStatus "@baseboard_fab2_lib.baseboard_fab2(sch_1):page202_i18" )
			)
			( gate "C7A26"
				( objectStatus "@baseboard_fab2_lib.baseboard_fab2(sch_1):page219_i152" )
			)
			( gate "C4E17"
				( objectStatus "@baseboard_fab2_lib.baseboard_fab2(sch_1):page202_i22" )
			)
			( gate "C4E27"
				( objectStatus "@baseboard_fab2_lib.baseboard_fab2(sch_1):page202_i24" )
			)
			( gate "C4E28"
				( objectStatus "@baseboard_fab2_lib.baseboard_fab2(sch_1):page214_i175" )
			)
			( gate "C4E11"
				( objectStatus "@baseboard_fab2_lib.baseboard_fab2(sch_1):page202_i27" )
			)
			( gate "L4D2"
				( objectStatus "@baseboard_fab2_lib.baseboard_fab2(sch_1):page203_i130" )
			)
			( gate "C4D50"
				( objectStatus "@baseboard_fab2_lib.baseboard_fab2(sch_1):page202_i32" )
			)
			( gate "R9R2"
				( objectStatus "@baseboard_fab2_lib.baseboard_fab2(sch_1):page207_i106" )
			)
			( gate "C4E10"
				( objectStatus "@baseboard_fab2_lib.baseboard_fab2(sch_1):page202_i34" )
			)
			( gate "C4E20"
				( objectStatus "@baseboard_fab2_lib.baseboard_fab2(sch_1):page202_i35" )
			)
			( gate "C4E19"
				( objectStatus "@baseboard_fab2_lib.baseboard_fab2(sch_1):page202_i36" )
			)
			( gate "C6R11"
				( objectStatus "@baseboard_fab2_lib.baseboard_fab2(sch_1):page202_i37" )
			)
			( gate "C6P13"
				( objectStatus "@baseboard_fab2_lib.baseboard_fab2(sch_1):page202_i38" )
			)
			( gate "R6N3"
				( objectStatus "@baseboard_fab2_lib.baseboard_fab2(sch_1):page205_i81" )
			)
			( gate "C6R13"
				( objectStatus "@baseboard_fab2_lib.baseboard_fab2(sch_1):page202_i42" )
			)
			( gate "C4E26"
				( objectStatus "@baseboard_fab2_lib.baseboard_fab2(sch_1):page202_i45" )
			)
			( gate "C4D49"
				( objectStatus "@baseboard_fab2_lib.baseboard_fab2(sch_1):page202_i46" )
			)
			( gate "C4D48"
				( objectStatus "@baseboard_fab2_lib.baseboard_fab2(sch_1):page202_i47" )
			)
			( gate "C6R4"
				( objectStatus "@baseboard_fab2_lib.baseboard_fab2(sch_1):page202_i48" )
			)
			( gate "C6P22"
				( objectStatus "@baseboard_fab2_lib.baseboard_fab2(sch_1):page202_i49" )
			)
			( gate "C6N8"
				( objectStatus "@baseboard_fab2_lib.baseboard_fab2(sch_1):page202_i51" )
			)
			( gate "C4E3"
				( objectStatus "@baseboard_fab2_lib.baseboard_fab2(sch_1):page202_i61" )
			)
			( gate "C6P16"
				( objectStatus "@baseboard_fab2_lib.baseboard_fab2(sch_1):page202_i62" )
			)
			( gate "EU4E1"
				( objectStatus "@baseboard_fab2_lib.baseboard_fab2(sch_1):page202_i63" )
			)
			( gate "EU4D6"
				( objectStatus "@baseboard_fab2_lib.baseboard_fab2(sch_1):page202_i64" )
			)
			( gate "R4E22"
				( objectStatus "@baseboard_fab2_lib.baseboard_fab2(sch_1):page202_i65" )
			)
			( gate "R4E19"
				( objectStatus "@baseboard_fab2_lib.baseboard_fab2(sch_1):page202_i67" )
			)
			( gate "C6P24"
				( objectStatus "@baseboard_fab2_lib.baseboard_fab2(sch_1):page203_i1" )
			)
			( gate "C6R6"
				( objectStatus "@baseboard_fab2_lib.baseboard_fab2(sch_1):page203_i2" )
			)
			( gate "C4D9"
				( objectStatus "@baseboard_fab2_lib.baseboard_fab2(sch_1):page203_i3" )
			)
			( gate "L1D3"
				( objectStatus "@baseboard_fab2_lib.baseboard_fab2(sch_1):page207_i108" )
			)
			( gate "C6R3"
				( objectStatus "@baseboard_fab2_lib.baseboard_fab2(sch_1):page203_i16" )
			)
			( gate "C6R9"
				( objectStatus "@baseboard_fab2_lib.baseboard_fab2(sch_1):page203_i18" )
			)
			( gate "L4C3"
				( objectStatus "@baseboard_fab2_lib.baseboard_fab2(sch_1):page204_i104" )
			)
			( gate "C6P3"
				( objectStatus "@baseboard_fab2_lib.baseboard_fab2(sch_1):page203_i25" )
			)
			( gate "C6P23"
				( objectStatus "@baseboard_fab2_lib.baseboard_fab2(sch_1):page203_i28" )
			)
			( gate "C6P14"
				( objectStatus "@baseboard_fab2_lib.baseboard_fab2(sch_1):page203_i29" )
			)
			( gate "C6P18"
				( objectStatus "@baseboard_fab2_lib.baseboard_fab2(sch_1):page203_i30" )
			)
			( gate "C6P8"
				( objectStatus "@baseboard_fab2_lib.baseboard_fab2(sch_1):page203_i32" )
			)
			( gate "C6N9"
				( objectStatus "@baseboard_fab2_lib.baseboard_fab2(sch_1):page203_i34" )
			)
			( gate "R6R6"
				( objectStatus "@baseboard_fab2_lib.baseboard_fab2(sch_1):page202_i108" )
			)
			( gate "C4D13"
				( objectStatus "@baseboard_fab2_lib.baseboard_fab2(sch_1):page203_i40" )
			)
			( gate "C4E6"
				( objectStatus "@baseboard_fab2_lib.baseboard_fab2(sch_1):page202_i112" )
			)
			( gate "C4D28"
				( objectStatus "@baseboard_fab2_lib.baseboard_fab2(sch_1):page203_i42" )
			)
			( gate "C4D16"
				( objectStatus "@baseboard_fab2_lib.baseboard_fab2(sch_1):page203_i45" )
			)
			( gate "C4D35"
				( objectStatus "@baseboard_fab2_lib.baseboard_fab2(sch_1):page203_i46" )
			)
			( gate "C4D30"
				( objectStatus "@baseboard_fab2_lib.baseboard_fab2(sch_1):page203_i47" )
			)
			( gate "C4D5"
				( objectStatus "@baseboard_fab2_lib.baseboard_fab2(sch_1):page203_i48" )
			)
			( gate "C4E25"
				( objectStatus "@baseboard_fab2_lib.baseboard_fab2(sch_1):page202_i111" )
			)
			( gate "R6R2"
				( objectStatus "@baseboard_fab2_lib.baseboard_fab2(sch_1):page202_i107" )
			)
			( gate "C4D7"
				( objectStatus "@baseboard_fab2_lib.baseboard_fab2(sch_1):page203_i51" )
			)
			( gate "C4D11"
				( objectStatus "@baseboard_fab2_lib.baseboard_fab2(sch_1):page203_i52" )
			)
			( gate "C4D10"
				( objectStatus "@baseboard_fab2_lib.baseboard_fab2(sch_1):page203_i53" )
			)
			( gate "C6P19"
				( objectStatus "@baseboard_fab2_lib.baseboard_fab2(sch_1):page203_i54" )
			)
			( gate "C6P20"
				( objectStatus "@baseboard_fab2_lib.baseboard_fab2(sch_1):page203_i57" )
			)
			( gate "C6P15"
				( objectStatus "@baseboard_fab2_lib.baseboard_fab2(sch_1):page203_i58" )
			)
			( gate "C6P7"
				( objectStatus "@baseboard_fab2_lib.baseboard_fab2(sch_1):page203_i59" )
			)
			( gate "C6P21"
				( objectStatus "@baseboard_fab2_lib.baseboard_fab2(sch_1):page203_i66" )
			)
			( gate "R4E13"
				( objectStatus "@baseboard_fab2_lib.baseboard_fab2(sch_1):page203_i67" )
			)
			( gate "C4D34"
				( objectStatus "@baseboard_fab2_lib.baseboard_fab2(sch_1):page203_i68" )
			)
			( gate "C4D4"
				( objectStatus "@baseboard_fab2_lib.baseboard_fab2(sch_1):page203_i69" )
			)
			( gate "EU4D3"
				( objectStatus "@baseboard_fab2_lib.baseboard_fab2(sch_1):page203_i70" )
			)
			( gate "EU4D1"
				( objectStatus "@baseboard_fab2_lib.baseboard_fab2(sch_1):page203_i71" )
			)
			( gate "R4D72"
				( objectStatus "@baseboard_fab2_lib.baseboard_fab2(sch_1):page203_i89" )
			)
			( gate "R4D71"
				( objectStatus "@baseboard_fab2_lib.baseboard_fab2(sch_1):page203_i91" )
			)
			( gate "L1E1"
				( objectStatus "@baseboard_fab2_lib.baseboard_fab2(sch_1):page207_i107" )
			)
			( gate "C4D12"
				( objectStatus "@baseboard_fab2_lib.baseboard_fab2(sch_1):page204_i9" )
			)
			( gate "C4D47"
				( objectStatus "@baseboard_fab2_lib.baseboard_fab2(sch_1):page204_i18" )
			)
			( gate "C4D14"
				( objectStatus "@baseboard_fab2_lib.baseboard_fab2(sch_1):page203_i132" )
			)
			( gate "C4C17"
				( objectStatus "@baseboard_fab2_lib.baseboard_fab2(sch_1):page204_i22" )
			)
			( gate "R9R11"
				( objectStatus "@baseboard_fab2_lib.baseboard_fab2(sch_1):page207_i105" )
			)
			( gate "C4D46"
				( objectStatus "@baseboard_fab2_lib.baseboard_fab2(sch_1):page204_i34" )
			)
			( gate "C4C19"
				( objectStatus "@baseboard_fab2_lib.baseboard_fab2(sch_1):page204_i35" )
			)
			( gate "C4C18"
				( objectStatus "@baseboard_fab2_lib.baseboard_fab2(sch_1):page204_i36" )
			)
			( gate "C6N10"
				( objectStatus "@baseboard_fab2_lib.baseboard_fab2(sch_1):page204_i37" )
			)
			( gate "C6P17"
				( objectStatus "@baseboard_fab2_lib.baseboard_fab2(sch_1):page204_i38" )
			)
			( gate "C6N11"
				( objectStatus "@baseboard_fab2_lib.baseboard_fab2(sch_1):page204_i42" )
			)
			( gate "L1B2"
				( objectStatus "@baseboard_fab2_lib.baseboard_fab2(sch_1):page209_i81" )
			)
			( gate "C4D2"
				( objectStatus "@baseboard_fab2_lib.baseboard_fab2(sch_1):page204_i48" )
			)
			( gate "C4E16"
				( objectStatus "@baseboard_fab2_lib.baseboard_fab2(sch_1):page204_i50" )
			)
			( gate "R8W5"
				( objectStatus "@baseboard_fab2_lib.baseboard_fab2(sch_1):page138_i194" )
			)
			( gate "R8W4"
				( objectStatus "@baseboard_fab2_lib.baseboard_fab2(sch_1):page138_i195" )
			)
			( gate "R4E14"
				( objectStatus "@baseboard_fab2_lib.baseboard_fab2(sch_1):page204_i60" )
			)
			( gate "R4E16"
				( objectStatus "@baseboard_fab2_lib.baseboard_fab2(sch_1):page204_i61" )
			)
			( gate "R4E17"
				( objectStatus "@baseboard_fab2_lib.baseboard_fab2(sch_1):page204_i62" )
			)
			( gate "R4E15"
				( objectStatus "@baseboard_fab2_lib.baseboard_fab2(sch_1):page204_i63" )
			)
			( gate "R4E18"
				( objectStatus "@baseboard_fab2_lib.baseboard_fab2(sch_1):page204_i64" )
			)
			( gate "C4C12"
				( objectStatus "@baseboard_fab2_lib.baseboard_fab2(sch_1):page204_i67" )
			)
			( gate "C6R2"
				( objectStatus "@baseboard_fab2_lib.baseboard_fab2(sch_1):page204_i70" )
			)
			( gate "EU4C2"
				( objectStatus "@baseboard_fab2_lib.baseboard_fab2(sch_1):page204_i71" )
			)
			( gate "R4D68"
				( objectStatus "@baseboard_fab2_lib.baseboard_fab2(sch_1):page204_i83" )
			)
			( gate "C6N7"
				( objectStatus "@baseboard_fab2_lib.baseboard_fab2(sch_1):page205_i5" )
			)
			( gate "L1C1"
				( objectStatus "@baseboard_fab2_lib.baseboard_fab2(sch_1):page210_i72" )
			)
			( gate "C6N1"
				( objectStatus "@baseboard_fab2_lib.baseboard_fab2(sch_1):page205_i12" )
			)
			( gate "C6N4"
				( objectStatus "@baseboard_fab2_lib.baseboard_fab2(sch_1):page205_i14" )
			)
			( gate "C4C5"
				( objectStatus "@baseboard_fab2_lib.baseboard_fab2(sch_1):page205_i16" )
			)
			( gate "C4C14"
				( objectStatus "@baseboard_fab2_lib.baseboard_fab2(sch_1):page204_i113" )
			)
			( gate "R6P47"
				( objectStatus "@baseboard_fab2_lib.baseboard_fab2(sch_1):page204_i103" )
			)
			( gate "C4C6"
				( objectStatus "@baseboard_fab2_lib.baseboard_fab2(sch_1):page205_i20" )
			)
			( gate "R4C5"
				( objectStatus "@baseboard_fab2_lib.baseboard_fab2(sch_1):page205_i24" )
			)
			( gate "C4C8"
				( objectStatus "@baseboard_fab2_lib.baseboard_fab2(sch_1):page205_i25" )
			)
			( gate "R4C4"
				( objectStatus "@baseboard_fab2_lib.baseboard_fab2(sch_1):page205_i26" )
			)
			( gate "R4C1"
				( objectStatus "@baseboard_fab2_lib.baseboard_fab2(sch_1):page205_i29" )
			)
			( gate "R4C2"
				( objectStatus "@baseboard_fab2_lib.baseboard_fab2(sch_1):page205_i30" )
			)
			( gate "C4C10"
				( objectStatus "@baseboard_fab2_lib.baseboard_fab2(sch_1):page205_i31" )
			)
			( gate "C4C9"
				( objectStatus "@baseboard_fab2_lib.baseboard_fab2(sch_1):page205_i32" )
			)
			( gate "C6N2"
				( objectStatus "@baseboard_fab2_lib.baseboard_fab2(sch_1):page205_i33" )
			)
			( gate "C6N3"
				( objectStatus "@baseboard_fab2_lib.baseboard_fab2(sch_1):page205_i34" )
			)
			( gate "C6N6"
				( objectStatus "@baseboard_fab2_lib.baseboard_fab2(sch_1):page205_i35" )
			)
			( gate "R4C3"
				( objectStatus "@baseboard_fab2_lib.baseboard_fab2(sch_1):page205_i37" )
			)
			( gate "C4C11"
				( objectStatus "@baseboard_fab2_lib.baseboard_fab2(sch_1):page205_i43" )
			)
			( gate "R6N4"
				( objectStatus "@baseboard_fab2_lib.baseboard_fab2(sch_1):page205_i45" )
			)
			( gate "EU4C1"
				( objectStatus "@baseboard_fab2_lib.baseboard_fab2(sch_1):page205_i46" )
			)
			( gate "R4C13"
				( objectStatus "@baseboard_fab2_lib.baseboard_fab2(sch_1):page205_i62" )
			)
			( gate "R9P1"
				( objectStatus "@baseboard_fab2_lib.baseboard_fab2(sch_1):page206_i4" )
			)
			( gate "R1D6"
				( objectStatus "@baseboard_fab2_lib.baseboard_fab2(sch_1):page206_i6" )
			)
			( gate "C4W4"
				( objectStatus "@baseboard_fab2_lib.baseboard_fab2(sch_1):page235_i246" )
			)
			( gate "C1C13"
				( objectStatus "@baseboard_fab2_lib.baseboard_fab2(sch_1):page206_i29" )
			)
			( gate "C1C14"
				( objectStatus "@baseboard_fab2_lib.baseboard_fab2(sch_1):page206_i31" )
			)
			( gate "R1D53"
				( objectStatus "@baseboard_fab2_lib.baseboard_fab2(sch_1):page206_i33" )
			)
			( gate "R1C18"
				( objectStatus "@baseboard_fab2_lib.baseboard_fab2(sch_1):page206_i34" )
			)
			( gate "R1C28"
				( objectStatus "@baseboard_fab2_lib.baseboard_fab2(sch_1):page206_i35" )
			)
			( gate "R1D8"
				( objectStatus "@baseboard_fab2_lib.baseboard_fab2(sch_1):page206_i36" )
			)
			( gate "R1D3"
				( objectStatus "@baseboard_fab2_lib.baseboard_fab2(sch_1):page206_i37" )
			)
			( gate "R1D2"
				( objectStatus "@baseboard_fab2_lib.baseboard_fab2(sch_1):page206_i38" )
			)
			( gate "C1C7"
				( objectStatus "@baseboard_fab2_lib.baseboard_fab2(sch_1):page206_i41" )
			)
			( gate "C1C9"
				( objectStatus "@baseboard_fab2_lib.baseboard_fab2(sch_1):page206_i42" )
			)
			( gate "R1C14"
				( objectStatus "@baseboard_fab2_lib.baseboard_fab2(sch_1):page206_i46" )
			)
			( gate "R1C13"
				( objectStatus "@baseboard_fab2_lib.baseboard_fab2(sch_1):page206_i49" )
			)
			( gate "R9P2"
				( objectStatus "@baseboard_fab2_lib.baseboard_fab2(sch_1):page206_i53" )
			)
			( gate "R1D9"
				( objectStatus "@baseboard_fab2_lib.baseboard_fab2(sch_1):page206_i54" )
			)
			( gate "R1C16"
				( objectStatus "@baseboard_fab2_lib.baseboard_fab2(sch_1):page206_i56" )
			)
			( gate "C1C16"
				( objectStatus "@baseboard_fab2_lib.baseboard_fab2(sch_1):page206_i68" )
			)
			( gate "C1C10"
				( objectStatus "@baseboard_fab2_lib.baseboard_fab2(sch_1):page206_i69" )
			)
			( gate "C1C11"
				( objectStatus "@baseboard_fab2_lib.baseboard_fab2(sch_1):page206_i71" )
			)
			( gate "C3P2"
				( objectStatus "@baseboard_fab2_lib.baseboard_fab2(sch_1):page211_i103" )
			)
			( gate "R1C21"
				( objectStatus "@baseboard_fab2_lib.baseboard_fab2(sch_1):page206_i77" )
			)
			( gate "C1D1"
				( objectStatus "@baseboard_fab2_lib.baseboard_fab2(sch_1):page206_i78" )
			)
			( gate "R1D4"
				( objectStatus "@baseboard_fab2_lib.baseboard_fab2(sch_1):page206_i79" )
			)
			( gate "R9N7"
				( objectStatus "@baseboard_fab2_lib.baseboard_fab2(sch_1):page206_i111" )
			)
			( gate "R9N8"
				( objectStatus "@baseboard_fab2_lib.baseboard_fab2(sch_1):page206_i112" )
			)
			( gate "R1C30"
				( objectStatus "@baseboard_fab2_lib.baseboard_fab2(sch_1):page206_i113" )
			)
			( gate "C1C23"
				( objectStatus "@baseboard_fab2_lib.baseboard_fab2(sch_1):page206_i114" )
			)
			( gate "R1D1"
				( objectStatus "@baseboard_fab2_lib.baseboard_fab2(sch_1):page206_i116" )
			)
			( gate "R9P3"
				( objectStatus "@baseboard_fab2_lib.baseboard_fab2(sch_1):page206_i117" )
			)
			( gate "R9N16"
				( objectStatus "@baseboard_fab2_lib.baseboard_fab2(sch_1):page206_i119" )
			)
			( gate "R9N14"
				( objectStatus "@baseboard_fab2_lib.baseboard_fab2(sch_1):page206_i120" )
			)
			( gate "EU1C2"
				( objectStatus "@baseboard_fab2_lib.baseboard_fab2(sch_1):page206_i130" )
			)
			( gate "C9R8"
				( objectStatus "@baseboard_fab2_lib.baseboard_fab2(sch_1):page207_i8" )
			)
			( gate "C1E3"
				( objectStatus "@baseboard_fab2_lib.baseboard_fab2(sch_1):page207_i18" )
			)
			( gate "EU1E2"
				( objectStatus "@baseboard_fab2_lib.baseboard_fab2(sch_1):page207_i20" )
			)
			( gate "R9P8"
				( objectStatus "@baseboard_fab2_lib.baseboard_fab2(sch_1):page208_i115" )
			)
			( gate "C1E7"
				( objectStatus "@baseboard_fab2_lib.baseboard_fab2(sch_1):page207_i28" )
			)
			( gate "C1G4"
				( objectStatus "@baseboard_fab2_lib.baseboard_fab2(sch_1):page224_i155" )
			)
			( gate "C1E11"
				( objectStatus "@baseboard_fab2_lib.baseboard_fab2(sch_1):page207_i30" )
			)
			( gate "C1E8"
				( objectStatus "@baseboard_fab2_lib.baseboard_fab2(sch_1):page207_i32" )
			)
			( gate "C1E14"
				( objectStatus "@baseboard_fab2_lib.baseboard_fab2(sch_1):page207_i33" )
			)
			( gate "C1E13"
				( objectStatus "@baseboard_fab2_lib.baseboard_fab2(sch_1):page207_i34" )
			)
			( gate "C1E25"
				( objectStatus "@baseboard_fab2_lib.baseboard_fab2(sch_1):page207_i36" )
			)
			( gate "C1F21"
				( objectStatus "@baseboard_fab2_lib.baseboard_fab2(sch_1):page224_i154" )
			)
			( gate "C1D36"
				( objectStatus "@baseboard_fab2_lib.baseboard_fab2(sch_1):page207_i38" )
			)
			( gate "R9P22"
				( objectStatus "@baseboard_fab2_lib.baseboard_fab2(sch_1):page208_i114" )
			)
			( gate "C1E24"
				( objectStatus "@baseboard_fab2_lib.baseboard_fab2(sch_1):page207_i40" )
			)
			( gate "C1D34"
				( objectStatus "@baseboard_fab2_lib.baseboard_fab2(sch_1):page207_i41" )
			)
			( gate "C1D35"
				( objectStatus "@baseboard_fab2_lib.baseboard_fab2(sch_1):page207_i42" )
			)
			( gate "C9R7"
				( objectStatus "@baseboard_fab2_lib.baseboard_fab2(sch_1):page207_i43" )
			)
			( gate "C9R10"
				( objectStatus "@baseboard_fab2_lib.baseboard_fab2(sch_1):page207_i44" )
			)
			( gate "C9R11"
				( objectStatus "@baseboard_fab2_lib.baseboard_fab2(sch_1):page207_i48" )
			)
			( gate "C9P22"
				( objectStatus "@baseboard_fab2_lib.baseboard_fab2(sch_1):page207_i50" )
			)
			( gate "C9P25"
				( objectStatus "@baseboard_fab2_lib.baseboard_fab2(sch_1):page207_i51" )
			)
			( gate "C9P26"
				( objectStatus "@baseboard_fab2_lib.baseboard_fab2(sch_1):page207_i54" )
			)
			( gate "C1E9"
				( objectStatus "@baseboard_fab2_lib.baseboard_fab2(sch_1):page207_i58" )
			)
			( gate "C9P3"
				( objectStatus "@baseboard_fab2_lib.baseboard_fab2(sch_1):page207_i59" )
			)
			( gate "R1E13"
				( objectStatus "@baseboard_fab2_lib.baseboard_fab2(sch_1):page207_i67" )
			)
			( gate "R1E14"
				( objectStatus "@baseboard_fab2_lib.baseboard_fab2(sch_1):page207_i68" )
			)
			( gate "R1E3"
				( objectStatus "@baseboard_fab2_lib.baseboard_fab2(sch_1):page208_i7" )
			)
			( gate "C1D14"
				( objectStatus "@baseboard_fab2_lib.baseboard_fab2(sch_1):page208_i9" )
			)
			( gate "J1F2"
				( objectStatus "@baseboard_fab2_lib.baseboard_fab2(sch_1):page161_i139" )
			)
			( gate "C9P8"
				( objectStatus "@baseboard_fab2_lib.baseboard_fab2(sch_1):page208_i12" )
			)
			( gate "C9P5"
				( objectStatus "@baseboard_fab2_lib.baseboard_fab2(sch_1):page208_i14" )
			)
			( gate "L1C2"
				( objectStatus "@baseboard_fab2_lib.baseboard_fab2(sch_1):page209_i80" )
			)
			( gate "C1D3"
				( objectStatus "@baseboard_fab2_lib.baseboard_fab2(sch_1):page208_i22" )
			)
			( gate "C9N24"
				( objectStatus "@baseboard_fab2_lib.baseboard_fab2(sch_1):page208_i24" )
			)
			( gate "C9R9"
				( objectStatus "@baseboard_fab2_lib.baseboard_fab2(sch_1):page208_i25" )
			)
			( gate "C9R3"
				( objectStatus "@baseboard_fab2_lib.baseboard_fab2(sch_1):page208_i26" )
			)
			( gate "EU1D3"
				( objectStatus "@baseboard_fab2_lib.baseboard_fab2(sch_1):page208_i27" )
			)
			( gate "C9P23"
				( objectStatus "@baseboard_fab2_lib.baseboard_fab2(sch_1):page208_i28" )
			)
			( gate "C9P18"
				( objectStatus "@baseboard_fab2_lib.baseboard_fab2(sch_1):page208_i30" )
			)
			( gate "R3U9"
				( objectStatus "@baseboard_fab2_lib.baseboard_fab2(sch_1):page216_i146" )
			)
			( gate "C1D16"
				( objectStatus "@baseboard_fab2_lib.baseboard_fab2(sch_1):page208_i38" )
			)
			( gate "C1E6"
				( objectStatus "@baseboard_fab2_lib.baseboard_fab2(sch_1):page207_i110" )
			)
			( gate "C1D20"
				( objectStatus "@baseboard_fab2_lib.baseboard_fab2(sch_1):page208_i40" )
			)
			( gate "C1D17"
				( objectStatus "@baseboard_fab2_lib.baseboard_fab2(sch_1):page208_i43" )
			)
			( gate "C1D28"
				( objectStatus "@baseboard_fab2_lib.baseboard_fab2(sch_1):page208_i44" )
			)
			( gate "C1D23"
				( objectStatus "@baseboard_fab2_lib.baseboard_fab2(sch_1):page208_i45" )
			)
			( gate "C1D6"
				( objectStatus "@baseboard_fab2_lib.baseboard_fab2(sch_1):page208_i46" )
			)
			( gate "C1E23"
				( objectStatus "@baseboard_fab2_lib.baseboard_fab2(sch_1):page207_i109" )
			)
			( gate "C1D10"
				( objectStatus "@baseboard_fab2_lib.baseboard_fab2(sch_1):page208_i48" )
			)
			( gate "R9P32"
				( objectStatus "@baseboard_fab2_lib.baseboard_fab2(sch_1):page209_i79" )
			)
			( gate "C1D7"
				( objectStatus "@baseboard_fab2_lib.baseboard_fab2(sch_1):page208_i50" )
			)
			( gate "C1D13"
				( objectStatus "@baseboard_fab2_lib.baseboard_fab2(sch_1):page208_i51" )
			)
			( gate "C1D12"
				( objectStatus "@baseboard_fab2_lib.baseboard_fab2(sch_1):page208_i52" )
			)
			( gate "C9P4"
				( objectStatus "@baseboard_fab2_lib.baseboard_fab2(sch_1):page208_i53" )
			)
			( gate "C9P7"
				( objectStatus "@baseboard_fab2_lib.baseboard_fab2(sch_1):page208_i54" )
			)
			( gate "C9P9"
				( objectStatus "@baseboard_fab2_lib.baseboard_fab2(sch_1):page208_i55" )
			)
			( gate "C9P24"
				( objectStatus "@baseboard_fab2_lib.baseboard_fab2(sch_1):page208_i58" )
			)
			( gate "C9P1"
				( objectStatus "@baseboard_fab2_lib.baseboard_fab2(sch_1):page208_i59" )
			)
			( gate "C9P2"
				( objectStatus "@baseboard_fab2_lib.baseboard_fab2(sch_1):page208_i60" )
			)
			( gate "C9P10"
				( objectStatus "@baseboard_fab2_lib.baseboard_fab2(sch_1):page208_i66" )
			)
			( gate "C9R2"
				( objectStatus "@baseboard_fab2_lib.baseboard_fab2(sch_1):page208_i67" )
			)
			( gate "EU1D1"
				( objectStatus "@baseboard_fab2_lib.baseboard_fab2(sch_1):page208_i71" )
			)
			( gate "R1D54"
				( objectStatus "@baseboard_fab2_lib.baseboard_fab2(sch_1):page208_i75" )
			)
			( gate "R1D55"
				( objectStatus "@baseboard_fab2_lib.baseboard_fab2(sch_1):page208_i76" )
			)
			( gate "R1E5"
				( objectStatus "@baseboard_fab2_lib.baseboard_fab2(sch_1):page209_i3" )
			)
			( gate "C9N27"
				( objectStatus "@baseboard_fab2_lib.baseboard_fab2(sch_1):page209_i5" )
			)
			( gate "C9N26"
				( objectStatus "@baseboard_fab2_lib.baseboard_fab2(sch_1):page209_i7" )
			)
			( gate "C9N25"
				( objectStatus "@baseboard_fab2_lib.baseboard_fab2(sch_1):page209_i8" )
			)
			( gate "R1E8"
				( objectStatus "@baseboard_fab2_lib.baseboard_fab2(sch_1):page209_i9" )
			)
			( gate "R1E7"
				( objectStatus "@baseboard_fab2_lib.baseboard_fab2(sch_1):page209_i10" )
			)
			( gate "R1E6"
				( objectStatus "@baseboard_fab2_lib.baseboard_fab2(sch_1):page209_i11" )
			)
			( gate "R1E4"
				( objectStatus "@baseboard_fab2_lib.baseboard_fab2(sch_1):page209_i15" )
			)
			( gate "C1C26"
				( objectStatus "@baseboard_fab2_lib.baseboard_fab2(sch_1):page209_i16" )
			)
			( gate "C1C25"
				( objectStatus "@baseboard_fab2_lib.baseboard_fab2(sch_1):page209_i17" )
			)
			( gate "C1D32"
				( objectStatus "@baseboard_fab2_lib.baseboard_fab2(sch_1):page209_i18" )
			)
			( gate "C1C24"
				( objectStatus "@baseboard_fab2_lib.baseboard_fab2(sch_1):page209_i20" )
			)
			( gate "C1A11"
				( objectStatus "@baseboard_fab2_lib.baseboard_fab2(sch_1):page227_i147" )
			)
			( gate "C1D33"
				( objectStatus "@baseboard_fab2_lib.baseboard_fab2(sch_1):page209_i22" )
			)
			( gate "R9N3"
				( objectStatus "@baseboard_fab2_lib.baseboard_fab2(sch_1):page210_i71" )
			)
			( gate "R3P7"
				( objectStatus "@baseboard_fab2_lib.baseboard_fab2(sch_1):page133_i370" )
			)
			( gate "L7F2"
				( objectStatus "@baseboard_fab2_lib.baseboard_fab2(sch_1):page217_i261" )
			)
			( gate "C1C1"
				( objectStatus "@baseboard_fab2_lib.baseboard_fab2(sch_1):page209_i35" )
			)
			( gate "C1E18"
				( objectStatus "@baseboard_fab2_lib.baseboard_fab2(sch_1):page209_i37" )
			)
			( gate "C1C2"
				( objectStatus "@baseboard_fab2_lib.baseboard_fab2(sch_1):page209_i38" )
			)
			( gate "L7A1"
				( objectStatus "@baseboard_fab2_lib.baseboard_fab2(sch_1):page219_i157" )
			)
			( gate "C1D24"
				( objectStatus "@baseboard_fab2_lib.baseboard_fab2(sch_1):page209_i42" )
			)
			( gate "C9P20"
				( objectStatus "@baseboard_fab2_lib.baseboard_fab2(sch_1):page209_i55" )
			)
			( gate "EU1C3"
				( objectStatus "@baseboard_fab2_lib.baseboard_fab2(sch_1):page209_i56" )
			)
			( gate "R1D52"
				( objectStatus "@baseboard_fab2_lib.baseboard_fab2(sch_1):page209_i59" )
			)
			( gate "C1C19"
				( objectStatus "@baseboard_fab2_lib.baseboard_fab2(sch_1):page210_i8" )
			)
			( gate "L7A2"
				( objectStatus "@baseboard_fab2_lib.baseboard_fab2(sch_1):page236_i178" )
			)
			( gate "C9N11"
				( objectStatus "@baseboard_fab2_lib.baseboard_fab2(sch_1):page210_i12" )
			)
			( gate "C9N20"
				( objectStatus "@baseboard_fab2_lib.baseboard_fab2(sch_1):page210_i14" )
			)
			( gate "R3N7"
				( objectStatus "@baseboard_fab2_lib.baseboard_fab2(sch_1):page212_i140" )
			)
			( gate "C1C4"
				( objectStatus "@baseboard_fab2_lib.baseboard_fab2(sch_1):page210_i22" )
			)
			( gate "C1D15"
				( objectStatus "@baseboard_fab2_lib.baseboard_fab2(sch_1):page208_i118" )
			)
			( gate "C1C12"
				( objectStatus "@baseboard_fab2_lib.baseboard_fab2(sch_1):page210_i24" )
			)
			( gate "C1C5"
				( objectStatus "@baseboard_fab2_lib.baseboard_fab2(sch_1):page210_i26" )
			)
			( gate "C1C17"
				( objectStatus "@baseboard_fab2_lib.baseboard_fab2(sch_1):page210_i27" )
			)
			( gate "C1C15"
				( objectStatus "@baseboard_fab2_lib.baseboard_fab2(sch_1):page210_i28" )
			)
			( gate "R1C12"
				( objectStatus "@baseboard_fab2_lib.baseboard_fab2(sch_1):page210_i29" )
			)
			( gate "R1C7"
				( objectStatus "@baseboard_fab2_lib.baseboard_fab2(sch_1):page210_i31" )
			)
			( gate "R1C5"
				( objectStatus "@baseboard_fab2_lib.baseboard_fab2(sch_1):page210_i32" )
			)
			( gate "R1C4"
				( objectStatus "@baseboard_fab2_lib.baseboard_fab2(sch_1):page210_i33" )
			)
			( gate "R1C6"
				( objectStatus "@baseboard_fab2_lib.baseboard_fab2(sch_1):page210_i34" )
			)
			( gate "C9N13"
				( objectStatus "@baseboard_fab2_lib.baseboard_fab2(sch_1):page210_i35" )
			)
			( gate "C9N19"
				( objectStatus "@baseboard_fab2_lib.baseboard_fab2(sch_1):page210_i36" )
			)
			( gate "C9N21"
				( objectStatus "@baseboard_fab2_lib.baseboard_fab2(sch_1):page210_i38" )
			)
			( gate "C9N22"
				( objectStatus "@baseboard_fab2_lib.baseboard_fab2(sch_1):page210_i44" )
			)
			( gate "R9N4"
				( objectStatus "@baseboard_fab2_lib.baseboard_fab2(sch_1):page210_i45" )
			)
			( gate "EU1C1"
				( objectStatus "@baseboard_fab2_lib.baseboard_fab2(sch_1):page210_i51" )
			)
			( gate "R1C37"
				( objectStatus "@baseboard_fab2_lib.baseboard_fab2(sch_1):page210_i52" )
			)
			( gate "C3P4"
				( objectStatus "@baseboard_fab2_lib.baseboard_fab2(sch_1):page211_i11" )
			)
			( gate "C3P5"
				( objectStatus "@baseboard_fab2_lib.baseboard_fab2(sch_1):page211_i13" )
			)
			( gate "R3P11"
				( objectStatus "@baseboard_fab2_lib.baseboard_fab2(sch_1):page211_i16" )
			)
			( gate "R3T11"
				( objectStatus "@baseboard_fab2_lib.baseboard_fab2(sch_1):page215_i70" )
			)
			( gate "C3P3"
				( objectStatus "@baseboard_fab2_lib.baseboard_fab2(sch_1):page211_i20" )
			)
			( gate "C3P7"
				( objectStatus "@baseboard_fab2_lib.baseboard_fab2(sch_1):page211_i22" )
			)
			( gate "R3P22"
				( objectStatus "@baseboard_fab2_lib.baseboard_fab2(sch_1):page211_i24" )
			)
			( gate "R3P13"
				( objectStatus "@baseboard_fab2_lib.baseboard_fab2(sch_1):page211_i100" )
			)
			( gate "R3P15"
				( objectStatus "@baseboard_fab2_lib.baseboard_fab2(sch_1):page211_i29" )
			)
			( gate "R3P12"
				( objectStatus "@baseboard_fab2_lib.baseboard_fab2(sch_1):page211_i31" )
			)
			( gate "R3P16"
				( objectStatus "@baseboard_fab2_lib.baseboard_fab2(sch_1):page211_i32" )
			)
			( gate "C4D40"
				( objectStatus "@baseboard_fab2_lib.baseboard_fab2(sch_1):page213_i105" )
			)
			( gate "R3N31"
				( objectStatus "@baseboard_fab2_lib.baseboard_fab2(sch_1):page211_i52" )
			)
			( gate "R3P25"
				( objectStatus "@baseboard_fab2_lib.baseboard_fab2(sch_1):page211_i56" )
			)
			( gate "R3P20"
				( objectStatus "@baseboard_fab2_lib.baseboard_fab2(sch_1):page211_i58" )
			)
			( gate "R3N23"
				( objectStatus "@baseboard_fab2_lib.baseboard_fab2(sch_1):page211_i60" )
			)
			( gate "R3P1"
				( objectStatus "@baseboard_fab2_lib.baseboard_fab2(sch_1):page211_i61" )
			)
			( gate "R3P18"
				( objectStatus "@baseboard_fab2_lib.baseboard_fab2(sch_1):page211_i64" )
			)
			( gate "R7G10"
				( objectStatus "@baseboard_fab2_lib.baseboard_fab2(sch_1):page215_i73" )
			)
			( gate "C3P6"
				( objectStatus "@baseboard_fab2_lib.baseboard_fab2(sch_1):page211_i71" )
			)
			( gate "R3N19"
				( objectStatus "@baseboard_fab2_lib.baseboard_fab2(sch_1):page211_i81" )
			)
			( gate "C3N39"
				( objectStatus "@baseboard_fab2_lib.baseboard_fab2(sch_1):page211_i83" )
			)
			( gate "R3P26"
				( objectStatus "@baseboard_fab2_lib.baseboard_fab2(sch_1):page211_i87" )
			)
			( gate "R3P21"
				( objectStatus "@baseboard_fab2_lib.baseboard_fab2(sch_1):page211_i88" )
			)
			( gate "EU3P1"
				( objectStatus "@baseboard_fab2_lib.baseboard_fab2(sch_1):page211_i93" )
			)
			( gate "C4E7"
				( objectStatus "@baseboard_fab2_lib.baseboard_fab2(sch_1):page214_i178" )
			)
			( gate "C6R12"
				( objectStatus "@baseboard_fab2_lib.baseboard_fab2(sch_1):page214_i177" )
			)
			( gate "C3N35"
				( objectStatus "@baseboard_fab2_lib.baseboard_fab2(sch_1):page212_i18" )
			)
			( gate "C7C6"
				( objectStatus "@baseboard_fab2_lib.baseboard_fab2(sch_1):page212_i23" )
			)
			( gate "L7A4"
				( objectStatus "@baseboard_fab2_lib.baseboard_fab2(sch_1):page236_i179" )
			)
			( gate "R6R5"
				( objectStatus "@baseboard_fab2_lib.baseboard_fab2(sch_1):page214_i173" )
			)
			( gate "C7C18"
				( objectStatus "@baseboard_fab2_lib.baseboard_fab2(sch_1):page212_i33" )
			)
			( gate "C7G35"
				( objectStatus "@baseboard_fab2_lib.baseboard_fab2(sch_1):page216_i149" )
			)
			( gate "C7C17"
				( objectStatus "@baseboard_fab2_lib.baseboard_fab2(sch_1):page212_i36" )
			)
			( gate "C7C14"
				( objectStatus "@baseboard_fab2_lib.baseboard_fab2(sch_1):page212_i37" )
			)
			( gate "C7C11"
				( objectStatus "@baseboard_fab2_lib.baseboard_fab2(sch_1):page212_i38" )
			)
			( gate "C7C12"
				( objectStatus "@baseboard_fab2_lib.baseboard_fab2(sch_1):page212_i39" )
			)
			( gate "C3N36"
				( objectStatus "@baseboard_fab2_lib.baseboard_fab2(sch_1):page212_i40" )
			)
			( gate "C3N33"
				( objectStatus "@baseboard_fab2_lib.baseboard_fab2(sch_1):page212_i41" )
			)
			( gate "C3N34"
				( objectStatus "@baseboard_fab2_lib.baseboard_fab2(sch_1):page212_i43" )
			)
			( gate "R6P10"
				( objectStatus "@baseboard_fab2_lib.baseboard_fab2(sch_1):page203_i129" )
			)
			( gate "R6P19"
				( objectStatus "@baseboard_fab2_lib.baseboard_fab2(sch_1):page203_i128" )
			)
			( gate "L4E2"
				( objectStatus "@baseboard_fab2_lib.baseboard_fab2(sch_1):page214_i174" )
			)
			( gate "C3P1"
				( objectStatus "@baseboard_fab2_lib.baseboard_fab2(sch_1):page212_i60" )
			)
			( gate "R3N20"
				( objectStatus "@baseboard_fab2_lib.baseboard_fab2(sch_1):page212_i68" )
			)
			( gate "R3N21"
				( objectStatus "@baseboard_fab2_lib.baseboard_fab2(sch_1):page212_i74" )
			)
			( gate "C7C10"
				( objectStatus "@baseboard_fab2_lib.baseboard_fab2(sch_1):page212_i77" )
			)
			( gate "R7C3"
				( objectStatus "@baseboard_fab2_lib.baseboard_fab2(sch_1):page212_i78" )
			)
			( gate "EU7C1"
				( objectStatus "@baseboard_fab2_lib.baseboard_fab2(sch_1):page212_i101" )
			)
			( gate "R7C25"
				( objectStatus "@baseboard_fab2_lib.baseboard_fab2(sch_1):page212_i103" )
			)
			( gate "SH3P1"
				( objectStatus "@baseboard_fab2_lib.baseboard_fab2(sch_1):page212_i104" )
			)
			( gate "SH3P2"
				( objectStatus "@baseboard_fab2_lib.baseboard_fab2(sch_1):page212_i105" )
			)
			( gate "C4D31"
				( objectStatus "@baseboard_fab2_lib.baseboard_fab2(sch_1):page213_i9" )
			)
			( gate "C4D32"
				( objectStatus "@baseboard_fab2_lib.baseboard_fab2(sch_1):page213_i11" )
			)
			( gate "R4D46"
				( objectStatus "@baseboard_fab2_lib.baseboard_fab2(sch_1):page213_i13" )
			)
			( gate "R6P49"
				( objectStatus "@baseboard_fab2_lib.baseboard_fab2(sch_1):page213_i14" )
			)
			( gate "R4D42"
				( objectStatus "@baseboard_fab2_lib.baseboard_fab2(sch_1):page213_i15" )
			)
			( gate "R4D56"
				( objectStatus "@baseboard_fab2_lib.baseboard_fab2(sch_1):page213_i16" )
			)
			( gate "C4D36"
				( objectStatus "@baseboard_fab2_lib.baseboard_fab2(sch_1):page213_i17" )
			)
			( gate "R4D47"
				( objectStatus "@baseboard_fab2_lib.baseboard_fab2(sch_1):page213_i25" )
			)
			( gate "R6P35"
				( objectStatus "@baseboard_fab2_lib.baseboard_fab2(sch_1):page213_i27" )
			)
			( gate "R6P33"
				( objectStatus "@baseboard_fab2_lib.baseboard_fab2(sch_1):page213_i30" )
			)
			( gate "R4D60"
				( objectStatus "@baseboard_fab2_lib.baseboard_fab2(sch_1):page213_i31" )
			)
			( gate "R4D57"
				( objectStatus "@baseboard_fab2_lib.baseboard_fab2(sch_1):page213_i32" )
			)
			( gate "C8A3"
				( objectStatus "@baseboard_fab2_lib.baseboard_fab2(sch_1):page235_i255" )
			)
			( gate "C4D38"
				( objectStatus "@baseboard_fab2_lib.baseboard_fab2(sch_1):page213_i35" )
			)
			( gate "R4D54"
				( objectStatus "@baseboard_fab2_lib.baseboard_fab2(sch_1):page213_i37" )
			)
			( gate "R1G23"
				( objectStatus "@baseboard_fab2_lib.baseboard_fab2(sch_1):page223_i73" )
			)
			( gate "R4D51"
				( objectStatus "@baseboard_fab2_lib.baseboard_fab2(sch_1):page213_i46" )
			)
			( gate "R4D49"
				( objectStatus "@baseboard_fab2_lib.baseboard_fab2(sch_1):page213_i63" )
			)
			( gate "R7A8"
				( objectStatus "@baseboard_fab2_lib.baseboard_fab2(sch_1):page218_i74" )
			)
			( gate "C4D33"
				( objectStatus "@baseboard_fab2_lib.baseboard_fab2(sch_1):page213_i73" )
			)
			( gate "C4D44"
				( objectStatus "@baseboard_fab2_lib.baseboard_fab2(sch_1):page213_i83" )
			)
			( gate "R4E7"
				( objectStatus "@baseboard_fab2_lib.baseboard_fab2(sch_1):page213_i84" )
			)
			( gate "R6P41"
				( objectStatus "@baseboard_fab2_lib.baseboard_fab2(sch_1):page213_i90" )
			)
			( gate "R6P40"
				( objectStatus "@baseboard_fab2_lib.baseboard_fab2(sch_1):page213_i91" )
			)
			( gate "EU4D5"
				( objectStatus "@baseboard_fab2_lib.baseboard_fab2(sch_1):page213_i96" )
			)
			( gate "C7A13"
				( objectStatus "@baseboard_fab2_lib.baseboard_fab2(sch_1):page236_i161" )
			)
			( gate "C6R5"
				( objectStatus "@baseboard_fab2_lib.baseboard_fab2(sch_1):page214_i24" )
			)
			( gate "C22W24"
				( objectStatus "@baseboard_fab2_lib.baseboard_fab2(sch_1):page236_i160" )
			)
			( gate "C22W23"
				( objectStatus "@baseboard_fab2_lib.baseboard_fab2(sch_1):page236_i159" )
			)
			( gate "C7R1"
				( objectStatus "@baseboard_fab2_lib.baseboard_fab2(sch_1):page214_i65" )
			)
			( gate "L4C2"
				( objectStatus "@baseboard_fab2_lib.baseboard_fab2(sch_1):page205_i82" )
			)
			( gate "R3U6"
				( objectStatus "@baseboard_fab2_lib.baseboard_fab2(sch_1):page216_i145" )
			)
			( gate "C4E23"
				( objectStatus "@baseboard_fab2_lib.baseboard_fab2(sch_1):page214_i73" )
			)
			( gate "C7A18"
				( objectStatus "@baseboard_fab2_lib.baseboard_fab2(sch_1):page219_i151" )
			)
			( gate "C4E22"
				( objectStatus "@baseboard_fab2_lib.baseboard_fab2(sch_1):page214_i76" )
			)
			( gate "C4E13"
				( objectStatus "@baseboard_fab2_lib.baseboard_fab2(sch_1):page214_i77" )
			)
			( gate "C4E18"
				( objectStatus "@baseboard_fab2_lib.baseboard_fab2(sch_1):page214_i78" )
			)
			( gate "C4E15"
				( objectStatus "@baseboard_fab2_lib.baseboard_fab2(sch_1):page214_i79" )
			)
			( gate "C6R14"
				( objectStatus "@baseboard_fab2_lib.baseboard_fab2(sch_1):page214_i80" )
			)
			( gate "C6R10"
				( objectStatus "@baseboard_fab2_lib.baseboard_fab2(sch_1):page214_i81" )
			)
			( gate "C6R8"
				( objectStatus "@baseboard_fab2_lib.baseboard_fab2(sch_1):page214_i83" )
			)
			( gate "C3D27"
				( objectStatus "@baseboard_fab2_lib.baseboard_fab2(sch_1):page214_i96" )
			)
			( gate "R3D28"
				( objectStatus "@baseboard_fab2_lib.baseboard_fab2(sch_1):page214_i101" )
			)
			( gate "R3E1"
				( objectStatus "@baseboard_fab2_lib.baseboard_fab2(sch_1):page214_i105" )
			)
			( gate "C3E1"
				( objectStatus "@baseboard_fab2_lib.baseboard_fab2(sch_1):page214_i108" )
			)
			( gate "R7R1"
				( objectStatus "@baseboard_fab2_lib.baseboard_fab2(sch_1):page214_i109" )
			)
			( gate "EU4E2"
				( objectStatus "@baseboard_fab2_lib.baseboard_fab2(sch_1):page214_i126" )
			)
			( gate "R4E21"
				( objectStatus "@baseboard_fab2_lib.baseboard_fab2(sch_1):page214_i127" )
			)
			( gate "SH3D2"
				( objectStatus "@baseboard_fab2_lib.baseboard_fab2(sch_1):page214_i129" )
			)
			( gate "SH3D1"
				( objectStatus "@baseboard_fab2_lib.baseboard_fab2(sch_1):page214_i130" )
			)
			( gate "Q12W4"
				( objectStatus "@baseboard_fab2_lib.baseboard_fab2(sch_1):page197_i35" )
			)
			( gate "R9M4"
				( objectStatus "@baseboard_fab2_lib.baseboard_fab2(sch_1):page197_i29" )
			)
			( gate "C8F19"
				( objectStatus "@baseboard_fab2_lib.baseboard_fab2(sch_1):page101_i146" )
			)
			( gate "EU1B1"
				( objectStatus "@baseboard_fab2_lib.baseboard_fab2(sch_1):page226_i69" )
			)
			( gate "R9M7"
				( objectStatus "@baseboard_fab2_lib.baseboard_fab2(sch_1):page226_i57" )
			)
			( gate "EU1G2"
				( objectStatus "@baseboard_fab2_lib.baseboard_fab2(sch_1):page223_i69" )
			)
			( gate "R9U3"
				( objectStatus "@baseboard_fab2_lib.baseboard_fab2(sch_1):page223_i57" )
			)
			( gate "R1B13"
				( objectStatus "@baseboard_fab2_lib.baseboard_fab2(sch_1):page226_i75" )
			)
			( gate "R1G8"
				( objectStatus "@baseboard_fab2_lib.baseboard_fab2(sch_1):page223_i55" )
			)
			( gate "EU7A5"
				( objectStatus "@baseboard_fab2_lib.baseboard_fab2(sch_1):page218_i69" )
			)
			( gate "R3L11"
				( objectStatus "@baseboard_fab2_lib.baseboard_fab2(sch_1):page218_i67" )
			)
			( gate "R1G6"
				( objectStatus "@baseboard_fab2_lib.baseboard_fab2(sch_1):page223_i76" )
			)
			( gate "R7B5"
				( objectStatus "@baseboard_fab2_lib.baseboard_fab2(sch_1):page218_i58" )
			)
			( gate "R4G19"
				( objectStatus "@baseboard_fab2_lib.baseboard_fab2(sch_1):page221_i33" )
			)
			( gate "C4G14"
				( objectStatus "@baseboard_fab2_lib.baseboard_fab2(sch_1):page221_i30" )
			)
			( gate "C4W5"
				( objectStatus "@baseboard_fab2_lib.baseboard_fab2(sch_1):page222_i46" )
			)
			( gate "R4G18"
				( objectStatus "@baseboard_fab2_lib.baseboard_fab2(sch_1):page221_i25" )
			)
			( gate "C6U16"
				( objectStatus "@baseboard_fab2_lib.baseboard_fab2(sch_1):page221_i19" )
			)
			( gate "C6U15"
				( objectStatus "@baseboard_fab2_lib.baseboard_fab2(sch_1):page221_i18" )
			)
			( gate "R6U4"
				( objectStatus "@baseboard_fab2_lib.baseboard_fab2(sch_1):page221_i14" )
			)
			( gate "C4G15"
				( objectStatus "@baseboard_fab2_lib.baseboard_fab2(sch_1):page221_i13" )
			)
			( gate "C6U12"
				( objectStatus "@baseboard_fab2_lib.baseboard_fab2(sch_1):page221_i11" )
			)
			( gate "SH5U1"
				( objectStatus "@baseboard_fab2_lib.baseboard_fab2(sch_1):page221_i9" )
			)
			( gate "C4W3"
				( objectStatus "@baseboard_fab2_lib.baseboard_fab2(sch_1):page235_i244" )
			)
			( gate "C6G3"
				( objectStatus "@baseboard_fab2_lib.baseboard_fab2(sch_1):page216_i6" )
			)
			( gate "C7G31"
				( objectStatus "@baseboard_fab2_lib.baseboard_fab2(sch_1):page216_i44" )
			)
			( gate "C3U2"
				( objectStatus "@baseboard_fab2_lib.baseboard_fab2(sch_1):page216_i45" )
			)
			( gate "C3U3"
				( objectStatus "@baseboard_fab2_lib.baseboard_fab2(sch_1):page216_i46" )
			)
			( gate "C3U4"
				( objectStatus "@baseboard_fab2_lib.baseboard_fab2(sch_1):page216_i47" )
			)
			( gate "C7G37"
				( objectStatus "@baseboard_fab2_lib.baseboard_fab2(sch_1):page216_i48" )
			)
			( gate "C7G33"
				( objectStatus "@baseboard_fab2_lib.baseboard_fab2(sch_1):page216_i50" )
			)
			( gate "C7G29"
				( objectStatus "@baseboard_fab2_lib.baseboard_fab2(sch_1):page216_i51" )
			)
			( gate "R3L8"
				( objectStatus "@baseboard_fab2_lib.baseboard_fab2(sch_1):page219_i148" )
			)
			( gate "C7G34"
				( objectStatus "@baseboard_fab2_lib.baseboard_fab2(sch_1):page216_i54" )
			)
			( gate "CT57"
				( objectStatus "@baseboard_fab2_lib.baseboard_fab2(sch_1):page210_i55" )
			)
			( gate "L1F2"
				( objectStatus "@baseboard_fab2_lib.baseboard_fab2(sch_1):page224_i161" )
			)
			( gate "C7G27"
				( objectStatus "@baseboard_fab2_lib.baseboard_fab2(sch_1):page216_i68" )
			)
			( gate "C7G41"
				( objectStatus "@baseboard_fab2_lib.baseboard_fab2(sch_1):page216_i72" )
			)
			( gate "CT14"
				( objectStatus "@baseboard_fab2_lib.baseboard_fab2(sch_1):page209_i73" )
			)
			( gate "R3L6"
				( objectStatus "@baseboard_fab2_lib.baseboard_fab2(sch_1):page219_i147" )
			)
			( gate "C7G40"
				( objectStatus "@baseboard_fab2_lib.baseboard_fab2(sch_1):page216_i77" )
			)
			( gate "C7G36"
				( objectStatus "@baseboard_fab2_lib.baseboard_fab2(sch_1):page216_i78" )
			)
			( gate "C7G30"
				( objectStatus "@baseboard_fab2_lib.baseboard_fab2(sch_1):page216_i79" )
			)
			( gate "C3U9"
				( objectStatus "@baseboard_fab2_lib.baseboard_fab2(sch_1):page216_i80" )
			)
			( gate "C3U7"
				( objectStatus "@baseboard_fab2_lib.baseboard_fab2(sch_1):page216_i81" )
			)
			( gate "C3U6"
				( objectStatus "@baseboard_fab2_lib.baseboard_fab2(sch_1):page216_i84" )
			)
			( gate "EU7G2"
				( objectStatus "@baseboard_fab2_lib.baseboard_fab2(sch_1):page216_i102" )
			)
			( gate "EU7G3"
				( objectStatus "@baseboard_fab2_lib.baseboard_fab2(sch_1):page216_i103" )
			)
			( gate "R7G25"
				( objectStatus "@baseboard_fab2_lib.baseboard_fab2(sch_1):page216_i104" )
			)
			( gate "R7G30"
				( objectStatus "@baseboard_fab2_lib.baseboard_fab2(sch_1):page216_i106" )
			)
			( gate "R3U4"
				( objectStatus "@baseboard_fab2_lib.baseboard_fab2(sch_1):page217_i58" )
			)
			( gate "R4U6"
				( objectStatus "@baseboard_fab2_lib.baseboard_fab2(sch_1):page217_i74" )
			)
			( gate "C7G28"
				( objectStatus "@baseboard_fab2_lib.baseboard_fab2(sch_1):page217_i75" )
			)
			( gate "C3U1"
				( objectStatus "@baseboard_fab2_lib.baseboard_fab2(sch_1):page217_i76" )
			)
			( gate "C3U5"
				( objectStatus "@baseboard_fab2_lib.baseboard_fab2(sch_1):page217_i77" )
			)
			( gate "C3U8"
				( objectStatus "@baseboard_fab2_lib.baseboard_fab2(sch_1):page217_i78" )
			)
			( gate "C5U14"
				( objectStatus "@baseboard_fab2_lib.baseboard_fab2(sch_1):page217_i322" )
			)
			( gate "C4T4"
				( objectStatus "@baseboard_fab2_lib.baseboard_fab2(sch_1):page217_i319" )
			)
			( gate "C5G9"
				( objectStatus "@baseboard_fab2_lib.baseboard_fab2(sch_1):page217_i318" )
			)
			( gate "C5P41"
				( objectStatus "@baseboard_fab2_lib.baseboard_fab2(sch_1):page217_i323" )
			)
			( gate "C5P43"
				( objectStatus "@baseboard_fab2_lib.baseboard_fab2(sch_1):page217_i326" )
			)
			( gate "C5P42"
				( objectStatus "@baseboard_fab2_lib.baseboard_fab2(sch_1):page217_i325" )
			)
			( gate "C5U13"
				( objectStatus "@baseboard_fab2_lib.baseboard_fab2(sch_1):page217_i321" )
			)
			( gate "C5A20"
				( objectStatus "@baseboard_fab2_lib.baseboard_fab2(sch_1):page220_i308" )
			)
			( gate "L7A5"
				( objectStatus "@baseboard_fab2_lib.baseboard_fab2(sch_1):page220_i241" )
			)
			( gate "C7G2"
				( objectStatus "@baseboard_fab2_lib.baseboard_fab2(sch_1):page217_i175" )
			)
			( gate "C5A10"
				( objectStatus "@baseboard_fab2_lib.baseboard_fab2(sch_1):page220_i321" )
			)
			( gate "C5U5"
				( objectStatus "@baseboard_fab2_lib.baseboard_fab2(sch_1):page217_i286" )
			)
			( gate "C5U4"
				( objectStatus "@baseboard_fab2_lib.baseboard_fab2(sch_1):page217_i285" )
			)
			( gate "C5U3"
				( objectStatus "@baseboard_fab2_lib.baseboard_fab2(sch_1):page217_i284" )
			)
			( gate "C5U2"
				( objectStatus "@baseboard_fab2_lib.baseboard_fab2(sch_1):page217_i283" )
			)
			( gate "C5U16"
				( objectStatus "@baseboard_fab2_lib.baseboard_fab2(sch_1):page221_i46" )
			)
			( gate "C5F2"
				( objectStatus "@baseboard_fab2_lib.baseboard_fab2(sch_1):page217_i205" )
			)
			( gate "C5F1"
				( objectStatus "@baseboard_fab2_lib.baseboard_fab2(sch_1):page217_i206" )
			)
			( gate "C5G10"
				( objectStatus "@baseboard_fab2_lib.baseboard_fab2(sch_1):page217_i207" )
			)
			( gate "C5T2"
				( objectStatus "@baseboard_fab2_lib.baseboard_fab2(sch_1):page217_i208" )
			)
			( gate "C5U11"
				( objectStatus "@baseboard_fab2_lib.baseboard_fab2(sch_1):page217_i209" )
			)
			( gate "C5T13"
				( objectStatus "@baseboard_fab2_lib.baseboard_fab2(sch_1):page217_i210" )
			)
			( gate "C5T4"
				( objectStatus "@baseboard_fab2_lib.baseboard_fab2(sch_1):page217_i211" )
			)
			( gate "C5T1"
				( objectStatus "@baseboard_fab2_lib.baseboard_fab2(sch_1):page217_i212" )
			)
			( gate "C5G19"
				( objectStatus "@baseboard_fab2_lib.baseboard_fab2(sch_1):page217_i213" )
			)
			( gate "C5G3"
				( objectStatus "@baseboard_fab2_lib.baseboard_fab2(sch_1):page217_i314" )
			)
			( gate "C5A19"
				( objectStatus "@baseboard_fab2_lib.baseboard_fab2(sch_1):page220_i277" )
			)
			( gate "C5G15"
				( objectStatus "@baseboard_fab2_lib.baseboard_fab2(sch_1):page217_i313" )
			)
			( gate "C5G16"
				( objectStatus "@baseboard_fab2_lib.baseboard_fab2(sch_1):page217_i312" )
			)
			( gate "C5A18"
				( objectStatus "@baseboard_fab2_lib.baseboard_fab2(sch_1):page220_i276" )
			)
			( gate "C5A17"
				( objectStatus "@baseboard_fab2_lib.baseboard_fab2(sch_1):page220_i275" )
			)
			( gate "C5G14"
				( objectStatus "@baseboard_fab2_lib.baseboard_fab2(sch_1):page217_i311" )
			)
			( gate "C5A4"
				( objectStatus "@baseboard_fab2_lib.baseboard_fab2(sch_1):page220_i274" )
			)
			( gate "C5G17"
				( objectStatus "@baseboard_fab2_lib.baseboard_fab2(sch_1):page217_i310" )
			)
			( gate "C5G18"
				( objectStatus "@baseboard_fab2_lib.baseboard_fab2(sch_1):page217_i309" )
			)
			( gate "C5A16"
				( objectStatus "@baseboard_fab2_lib.baseboard_fab2(sch_1):page220_i273" )
			)
			( gate "C5A9"
				( objectStatus "@baseboard_fab2_lib.baseboard_fab2(sch_1):page220_i272" )
			)
			( gate "C5G8"
				( objectStatus "@baseboard_fab2_lib.baseboard_fab2(sch_1):page217_i308" )
			)
			( gate "C5G1"
				( objectStatus "@baseboard_fab2_lib.baseboard_fab2(sch_1):page217_i307" )
			)
			( gate "C5A8"
				( objectStatus "@baseboard_fab2_lib.baseboard_fab2(sch_1):page220_i271" )
			)
			( gate "C5A3"
				( objectStatus "@baseboard_fab2_lib.baseboard_fab2(sch_1):page220_i270" )
			)
			( gate "C5G7"
				( objectStatus "@baseboard_fab2_lib.baseboard_fab2(sch_1):page217_i306" )
			)
			( gate "C5G5"
				( objectStatus "@baseboard_fab2_lib.baseboard_fab2(sch_1):page217_i305" )
			)
			( gate "C5A7"
				( objectStatus "@baseboard_fab2_lib.baseboard_fab2(sch_1):page220_i269" )
			)
			( gate "C5A6"
				( objectStatus "@baseboard_fab2_lib.baseboard_fab2(sch_1):page220_i268" )
			)
			( gate "C5G6"
				( objectStatus "@baseboard_fab2_lib.baseboard_fab2(sch_1):page217_i304" )
			)
			( gate "C5A14"
				( objectStatus "@baseboard_fab2_lib.baseboard_fab2(sch_1):page220_i267" )
			)
			( gate "C5G13"
				( objectStatus "@baseboard_fab2_lib.baseboard_fab2(sch_1):page217_i303" )
			)
			( gate "C5G4"
				( objectStatus "@baseboard_fab2_lib.baseboard_fab2(sch_1):page217_i302" )
			)
			( gate "C5A2"
				( objectStatus "@baseboard_fab2_lib.baseboard_fab2(sch_1):page220_i266" )
			)
			( gate "C5D8"
				( objectStatus "@baseboard_fab2_lib.baseboard_fab2(sch_1):page220_i261" )
			)
			( gate "C5G2"
				( objectStatus "@baseboard_fab2_lib.baseboard_fab2(sch_1):page217_i301" )
			)
			( gate "C5G12"
				( objectStatus "@baseboard_fab2_lib.baseboard_fab2(sch_1):page217_i300" )
			)
			( gate "C5D7"
				( objectStatus "@baseboard_fab2_lib.baseboard_fab2(sch_1):page220_i260" )
			)
			( gate "C5D6"
				( objectStatus "@baseboard_fab2_lib.baseboard_fab2(sch_1):page220_i259" )
			)
			( gate "C5G11"
				( objectStatus "@baseboard_fab2_lib.baseboard_fab2(sch_1):page217_i299" )
			)
			( gate "C5D9"
				( objectStatus "@baseboard_fab2_lib.baseboard_fab2(sch_1):page220_i258" )
			)
			( gate "SH4U1"
				( objectStatus "@baseboard_fab2_lib.baseboard_fab2(sch_1):page217_i259" )
			)
			( gate "SH4U2"
				( objectStatus "@baseboard_fab2_lib.baseboard_fab2(sch_1):page217_i260" )
			)
			( gate "R1G12"
				( objectStatus "@baseboard_fab2_lib.baseboard_fab2(sch_1):page223_i54" )
			)
			( gate "R1G11"
				( objectStatus "@baseboard_fab2_lib.baseboard_fab2(sch_1):page223_i49" )
			)
			( gate "C5T3"
				( objectStatus "@baseboard_fab2_lib.baseboard_fab2(sch_1):page221_i40" )
			)
			( gate "C7A28"
				( objectStatus "@baseboard_fab2_lib.baseboard_fab2(sch_1):page218_i14" )
			)
			( gate "R3M6"
				( objectStatus "@baseboard_fab2_lib.baseboard_fab2(sch_1):page218_i15" )
			)
			( gate "C7A29"
				( objectStatus "@baseboard_fab2_lib.baseboard_fab2(sch_1):page218_i16" )
			)
			( gate "CF17"
				( objectStatus "@baseboard_fab2_lib.baseboard_fab2(sch_1):page218_i17" )
			)
			( gate "R7A17"
				( objectStatus "@baseboard_fab2_lib.baseboard_fab2(sch_1):page218_i21" )
			)
			( gate "C8L3"
				( objectStatus "@baseboard_fab2_lib.baseboard_fab2(sch_1):page230_i41" )
			)
			( gate "C5L4"
				( objectStatus "@baseboard_fab2_lib.baseboard_fab2(sch_1):page222_i45" )
			)
			( gate "R6L9"
				( objectStatus "@baseboard_fab2_lib.baseboard_fab2(sch_1):page222_i23" )
			)
			( gate "C4A12"
				( objectStatus "@baseboard_fab2_lib.baseboard_fab2(sch_1):page222_i22" )
			)
			( gate "C4A9"
				( objectStatus "@baseboard_fab2_lib.baseboard_fab2(sch_1):page222_i20" )
			)
			( gate "R1B12"
				( objectStatus "@baseboard_fab2_lib.baseboard_fab2(sch_1):page226_i72" )
			)
			( gate "R3M5"
				( objectStatus "@baseboard_fab2_lib.baseboard_fab2(sch_1):page218_i34" )
			)
			( gate "R3M1"
				( objectStatus "@baseboard_fab2_lib.baseboard_fab2(sch_1):page218_i35" )
			)
			( gate "C6L3"
				( objectStatus "@baseboard_fab2_lib.baseboard_fab2(sch_1):page222_i17" )
			)
			( gate "C6L4"
				( objectStatus "@baseboard_fab2_lib.baseboard_fab2(sch_1):page222_i15" )
			)
			( gate "C7A37"
				( objectStatus "@baseboard_fab2_lib.baseboard_fab2(sch_1):page218_i40" )
			)
			( gate "R12W31"
				( objectStatus "@baseboard_fab2_lib.baseboard_fab2(sch_1):page223_i75" )
			)
			( gate "EU4A1"
				( objectStatus "@baseboard_fab2_lib.baseboard_fab2(sch_1):page222_i13" )
			)
			( gate "R7B1"
				( objectStatus "@baseboard_fab2_lib.baseboard_fab2(sch_1):page218_i59" )
			)
			( gate "R3M3"
				( objectStatus "@baseboard_fab2_lib.baseboard_fab2(sch_1):page218_i60" )
			)
			( gate "R6L11"
				( objectStatus "@baseboard_fab2_lib.baseboard_fab2(sch_1):page222_i10" )
			)
			( gate "C4A11"
				( objectStatus "@baseboard_fab2_lib.baseboard_fab2(sch_1):page222_i9" )
			)
			( gate "C7A12"
				( objectStatus "@baseboard_fab2_lib.baseboard_fab2(sch_1):page219_i44" )
			)
			( gate "C3L2"
				( objectStatus "@baseboard_fab2_lib.baseboard_fab2(sch_1):page219_i45" )
			)
			( gate "C3L4"
				( objectStatus "@baseboard_fab2_lib.baseboard_fab2(sch_1):page219_i46" )
			)
			( gate "C3L13"
				( objectStatus "@baseboard_fab2_lib.baseboard_fab2(sch_1):page219_i47" )
			)
			( gate "C7A11"
				( objectStatus "@baseboard_fab2_lib.baseboard_fab2(sch_1):page219_i48" )
			)
			( gate "C7A16"
				( objectStatus "@baseboard_fab2_lib.baseboard_fab2(sch_1):page219_i50" )
			)
			( gate "C7A5"
				( objectStatus "@baseboard_fab2_lib.baseboard_fab2(sch_1):page219_i51" )
			)
			( gate "R9U12"
				( objectStatus "@baseboard_fab2_lib.baseboard_fab2(sch_1):page224_i151" )
			)
			( gate "C7G42"
				( objectStatus "@baseboard_fab2_lib.baseboard_fab2(sch_1):page216_i150" )
			)
			( gate "C7A17"
				( objectStatus "@baseboard_fab2_lib.baseboard_fab2(sch_1):page219_i54" )
			)
			( gate "L7G1"
				( objectStatus "@baseboard_fab2_lib.baseboard_fab2(sch_1):page216_i153" )
			)
			( gate "L7A3"
				( objectStatus "@baseboard_fab2_lib.baseboard_fab2(sch_1):page219_i158" )
			)
			( gate "C6A4"
				( objectStatus "@baseboard_fab2_lib.baseboard_fab2(sch_1):page219_i68" )
			)
			( gate "C7A25"
				( objectStatus "@baseboard_fab2_lib.baseboard_fab2(sch_1):page219_i72" )
			)
			( gate "C7C20"
				( objectStatus "@baseboard_fab2_lib.baseboard_fab2(sch_1):page212_i143" )
			)
			( gate "C7A22"
				( objectStatus "@baseboard_fab2_lib.baseboard_fab2(sch_1):page219_i75" )
			)
			( gate "R9U1"
				( objectStatus "@baseboard_fab2_lib.baseboard_fab2(sch_1):page224_i150" )
			)
			( gate "C7A24"
				( objectStatus "@baseboard_fab2_lib.baseboard_fab2(sch_1):page219_i77" )
			)
			( gate "C7A20"
				( objectStatus "@baseboard_fab2_lib.baseboard_fab2(sch_1):page219_i78" )
			)
			( gate "C7A21"
				( objectStatus "@baseboard_fab2_lib.baseboard_fab2(sch_1):page219_i79" )
			)
			( gate "C3L17"
				( objectStatus "@baseboard_fab2_lib.baseboard_fab2(sch_1):page219_i80" )
			)
			( gate "C3L16"
				( objectStatus "@baseboard_fab2_lib.baseboard_fab2(sch_1):page219_i81" )
			)
			( gate "C3L15"
				( objectStatus "@baseboard_fab2_lib.baseboard_fab2(sch_1):page219_i84" )
			)
			( gate "C6A1"
				( objectStatus "@baseboard_fab2_lib.baseboard_fab2(sch_1):page219_i87" )
			)
			( gate "EU7A1"
				( objectStatus "@baseboard_fab2_lib.baseboard_fab2(sch_1):page219_i106" )
			)
			( gate "EU7A4"
				( objectStatus "@baseboard_fab2_lib.baseboard_fab2(sch_1):page219_i107" )
			)
			( gate "R7A20"
				( objectStatus "@baseboard_fab2_lib.baseboard_fab2(sch_1):page219_i108" )
			)
			( gate "R7A21"
				( objectStatus "@baseboard_fab2_lib.baseboard_fab2(sch_1):page219_i110" )
			)
			( gate "R4L4"
				( objectStatus "@baseboard_fab2_lib.baseboard_fab2(sch_1):page220_i58" )
			)
			( gate "R4L2"
				( objectStatus "@baseboard_fab2_lib.baseboard_fab2(sch_1):page220_i74" )
			)
			( gate "C3L6"
				( objectStatus "@baseboard_fab2_lib.baseboard_fab2(sch_1):page220_i75" )
			)
			( gate "C3L14"
				( objectStatus "@baseboard_fab2_lib.baseboard_fab2(sch_1):page220_i76" )
			)
			( gate "C6A5"
				( objectStatus "@baseboard_fab2_lib.baseboard_fab2(sch_1):page220_i77" )
			)
			( gate "C4L5"
				( objectStatus "@baseboard_fab2_lib.baseboard_fab2(sch_1):page220_i78" )
			)
			( gate "C5P5"
				( objectStatus "@baseboard_fab2_lib.baseboard_fab2(sch_1):page220_i317" )
			)
			( gate "C5P3"
				( objectStatus "@baseboard_fab2_lib.baseboard_fab2(sch_1):page220_i315" )
			)
			( gate "C5L14"
				( objectStatus "@baseboard_fab2_lib.baseboard_fab2(sch_1):page220_i313" )
			)
			( gate "C5P4"
				( objectStatus "@baseboard_fab2_lib.baseboard_fab2(sch_1):page220_i318" )
			)
			( gate "C5M12"
				( objectStatus "@baseboard_fab2_lib.baseboard_fab2(sch_1):page220_i312" )
			)
			( gate "C5M8"
				( objectStatus "@baseboard_fab2_lib.baseboard_fab2(sch_1):page220_i314" )
			)
			( gate "C5L2"
				( objectStatus "@baseboard_fab2_lib.baseboard_fab2(sch_1):page220_i311" )
			)
			( gate "C6W11"
				( objectStatus "@baseboard_fab2_lib.baseboard_fab2(sch_1):page221_i44" )
			)
			( gate "L1F1"
				( objectStatus "@baseboard_fab2_lib.baseboard_fab2(sch_1):page225_i253" )
			)
			( gate "C8P34"
				( objectStatus "@baseboard_fab2_lib.baseboard_fab2(sch_1):page225_i315" )
			)
			( gate "C8P31"
				( objectStatus "@baseboard_fab2_lib.baseboard_fab2(sch_1):page225_i314" )
			)
			( gate "C5A13"
				( objectStatus "@baseboard_fab2_lib.baseboard_fab2(sch_1):page220_i265" )
			)
			( gate "C5A12"
				( objectStatus "@baseboard_fab2_lib.baseboard_fab2(sch_1):page220_i264" )
			)
			( gate "C5A15"
				( objectStatus "@baseboard_fab2_lib.baseboard_fab2(sch_1):page220_i263" )
			)
			( gate "C5A1"
				( objectStatus "@baseboard_fab2_lib.baseboard_fab2(sch_1):page220_i262" )
			)
			( gate "C5L15"
				( objectStatus "@baseboard_fab2_lib.baseboard_fab2(sch_1):page220_i192" )
			)
			( gate "C5A5"
				( objectStatus "@baseboard_fab2_lib.baseboard_fab2(sch_1):page220_i193" )
			)
			( gate "C5B1"
				( objectStatus "@baseboard_fab2_lib.baseboard_fab2(sch_1):page220_i194" )
			)
			( gate "C5M9"
				( objectStatus "@baseboard_fab2_lib.baseboard_fab2(sch_1):page220_i195" )
			)
			( gate "C4M5"
				( objectStatus "@baseboard_fab2_lib.baseboard_fab2(sch_1):page220_i196" )
			)
			( gate "C5B2"
				( objectStatus "@baseboard_fab2_lib.baseboard_fab2(sch_1):page220_i197" )
			)
			( gate "C5M10"
				( objectStatus "@baseboard_fab2_lib.baseboard_fab2(sch_1):page220_i198" )
			)
			( gate "C5M3"
				( objectStatus "@baseboard_fab2_lib.baseboard_fab2(sch_1):page220_i199" )
			)
			( gate "C5M11"
				( objectStatus "@baseboard_fab2_lib.baseboard_fab2(sch_1):page220_i200" )
			)
			( gate "C5A11"
				( objectStatus "@baseboard_fab2_lib.baseboard_fab2(sch_1):page220_i293" )
			)
			( gate "C4M2"
				( objectStatus "@baseboard_fab2_lib.baseboard_fab2(sch_1):page220_i292" )
			)
			( gate "C5M1"
				( objectStatus "@baseboard_fab2_lib.baseboard_fab2(sch_1):page220_i291" )
			)
			( gate "C5M2"
				( objectStatus "@baseboard_fab2_lib.baseboard_fab2(sch_1):page220_i290" )
			)
			( gate "C5M4"
				( objectStatus "@baseboard_fab2_lib.baseboard_fab2(sch_1):page220_i289" )
			)
			( gate "C5M5"
				( objectStatus "@baseboard_fab2_lib.baseboard_fab2(sch_1):page220_i288" )
			)
			( gate "C5M6"
				( objectStatus "@baseboard_fab2_lib.baseboard_fab2(sch_1):page220_i287" )
			)
			( gate "C5M7"
				( objectStatus "@baseboard_fab2_lib.baseboard_fab2(sch_1):page220_i286" )
			)
			( gate "C5L13"
				( objectStatus "@baseboard_fab2_lib.baseboard_fab2(sch_1):page220_i285" )
			)
			( gate "C5L12"
				( objectStatus "@baseboard_fab2_lib.baseboard_fab2(sch_1):page220_i284" )
			)
			( gate "C5L11"
				( objectStatus "@baseboard_fab2_lib.baseboard_fab2(sch_1):page220_i283" )
			)
			( gate "C5L10"
				( objectStatus "@baseboard_fab2_lib.baseboard_fab2(sch_1):page220_i282" )
			)
			( gate "C5L9"
				( objectStatus "@baseboard_fab2_lib.baseboard_fab2(sch_1):page220_i281" )
			)
			( gate "C5L8"
				( objectStatus "@baseboard_fab2_lib.baseboard_fab2(sch_1):page220_i280" )
			)
			( gate "C5L7"
				( objectStatus "@baseboard_fab2_lib.baseboard_fab2(sch_1):page220_i279" )
			)
			( gate "C5L6"
				( objectStatus "@baseboard_fab2_lib.baseboard_fab2(sch_1):page220_i278" )
			)
			( gate "C2G14"
				( objectStatus "@baseboard_fab2_lib.baseboard_fab2(sch_1):page225_i287" )
			)
			( gate "C2G13"
				( objectStatus "@baseboard_fab2_lib.baseboard_fab2(sch_1):page225_i286" )
			)
			( gate "C3G2"
				( objectStatus "@baseboard_fab2_lib.baseboard_fab2(sch_1):page225_i285" )
			)
			( gate "C3G1"
				( objectStatus "@baseboard_fab2_lib.baseboard_fab2(sch_1):page225_i284" )
			)
			( gate "C2G6"
				( objectStatus "@baseboard_fab2_lib.baseboard_fab2(sch_1):page225_i283" )
			)
			( gate "C2G5"
				( objectStatus "@baseboard_fab2_lib.baseboard_fab2(sch_1):page225_i282" )
			)
			( gate "C2G4"
				( objectStatus "@baseboard_fab2_lib.baseboard_fab2(sch_1):page225_i281" )
			)
			( gate "C2G3"
				( objectStatus "@baseboard_fab2_lib.baseboard_fab2(sch_1):page225_i280" )
			)
			( gate "C2G2"
				( objectStatus "@baseboard_fab2_lib.baseboard_fab2(sch_1):page225_i279" )
			)
			( gate "C2G9"
				( objectStatus "@baseboard_fab2_lib.baseboard_fab2(sch_1):page225_i278" )
			)
			( gate "C2G1"
				( objectStatus "@baseboard_fab2_lib.baseboard_fab2(sch_1):page225_i277" )
			)
			( gate "C2G12"
				( objectStatus "@baseboard_fab2_lib.baseboard_fab2(sch_1):page225_i276" )
			)
			( gate "C2D42"
				( objectStatus "@baseboard_fab2_lib.baseboard_fab2(sch_1):page225_i273" )
			)
			( gate "C2D44"
				( objectStatus "@baseboard_fab2_lib.baseboard_fab2(sch_1):page225_i272" )
			)
			( gate "C2D41"
				( objectStatus "@baseboard_fab2_lib.baseboard_fab2(sch_1):page225_i271" )
			)
			( gate "C2D43"
				( objectStatus "@baseboard_fab2_lib.baseboard_fab2(sch_1):page225_i270" )
			)
			( gate "SH4L2"
				( objectStatus "@baseboard_fab2_lib.baseboard_fab2(sch_1):page220_i239" )
			)
			( gate "SH4L1"
				( objectStatus "@baseboard_fab2_lib.baseboard_fab2(sch_1):page220_i240" )
			)
			( gate "R7B4"
				( objectStatus "@baseboard_fab2_lib.baseboard_fab2(sch_1):page218_i57" )
			)
			( gate "EU4G3"
				( objectStatus "@baseboard_fab2_lib.baseboard_fab2(sch_1):page221_i15" )
			)
			( gate "R7A11"
				( objectStatus "@baseboard_fab2_lib.baseboard_fab2(sch_1):page218_i56" )
			)
			( gate "C4G16"
				( objectStatus "@baseboard_fab2_lib.baseboard_fab2(sch_1):page221_i22" )
			)
			( gate "C4G24"
				( objectStatus "@baseboard_fab2_lib.baseboard_fab2(sch_1):page221_i24" )
			)
			( gate "R12W30"
				( objectStatus "@baseboard_fab2_lib.baseboard_fab2(sch_1):page218_i55" )
			)
			( gate "R12W29"
				( objectStatus "@baseboard_fab2_lib.baseboard_fab2(sch_1):page218_i46" )
			)
			( gate "R7A12"
				( objectStatus "@baseboard_fab2_lib.baseboard_fab2(sch_1):page218_i45" )
			)
			( gate "C7T1"
				( objectStatus "@baseboard_fab2_lib.baseboard_fab2(sch_1):page225_i309" )
			)
			( gate "C7B3"
				( objectStatus "@baseboard_fab2_lib.baseboard_fab2(sch_1):page218_i41" )
			)
			( gate "C7A38"
				( objectStatus "@baseboard_fab2_lib.baseboard_fab2(sch_1):page218_i38" )
			)
			( gate "R1G22"
				( objectStatus "@baseboard_fab2_lib.baseboard_fab2(sch_1):page223_i74" )
			)
			( gate "C7B1"
				( objectStatus "@baseboard_fab2_lib.baseboard_fab2(sch_1):page218_i30" )
			)
			( gate "C7B2"
				( objectStatus "@baseboard_fab2_lib.baseboard_fab2(sch_1):page218_i28" )
			)
			( gate "CF18"
				( objectStatus "@baseboard_fab2_lib.baseboard_fab2(sch_1):page218_i20" )
			)
			( gate "RF18"
				( objectStatus "@baseboard_fab2_lib.baseboard_fab2(sch_1):page218_i19" )
			)
			( gate "RF17"
				( objectStatus "@baseboard_fab2_lib.baseboard_fab2(sch_1):page218_i18" )
			)
			( gate "R7A7"
				( objectStatus "@baseboard_fab2_lib.baseboard_fab2(sch_1):page218_i13" )
			)
			( gate "C4A10"
				( objectStatus "@baseboard_fab2_lib.baseboard_fab2(sch_1):page222_i12" )
			)
			( gate "R1G16"
				( objectStatus "@baseboard_fab2_lib.baseboard_fab2(sch_1):page223_i48" )
			)
			( gate "R12W34"
				( objectStatus "@baseboard_fab2_lib.baseboard_fab2(sch_1):page226_i74" )
			)
			( gate "R12W32"
				( objectStatus "@baseboard_fab2_lib.baseboard_fab2(sch_1):page223_i45" )
			)
			( gate "C6W12"
				( objectStatus "@baseboard_fab2_lib.baseboard_fab2(sch_1):page229_i43" )
			)
			( gate "C4A1"
				( objectStatus "@baseboard_fab2_lib.baseboard_fab2(sch_1):page222_i28" )
			)
			( gate "SH5L1"
				( objectStatus "@baseboard_fab2_lib.baseboard_fab2(sch_1):page222_i30" )
			)
			( gate "R4A6"
				( objectStatus "@baseboard_fab2_lib.baseboard_fab2(sch_1):page222_i31" )
			)
			( gate "C1G22"
				( objectStatus "@baseboard_fab2_lib.baseboard_fab2(sch_1):page223_i43" )
			)
			( gate "C1G21"
				( objectStatus "@baseboard_fab2_lib.baseboard_fab2(sch_1):page223_i40" )
			)
			( gate "C1G25"
				( objectStatus "@baseboard_fab2_lib.baseboard_fab2(sch_1):page223_i35" )
			)
			( gate "R9U8"
				( objectStatus "@baseboard_fab2_lib.baseboard_fab2(sch_1):page223_i31" )
			)
			( gate "RF20"
				( objectStatus "@baseboard_fab2_lib.baseboard_fab2(sch_1):page223_i19" )
			)
			( gate "R1G7"
				( objectStatus "@baseboard_fab2_lib.baseboard_fab2(sch_1):page223_i18" )
			)
			( gate "CF19"
				( objectStatus "@baseboard_fab2_lib.baseboard_fab2(sch_1):page223_i15" )
			)
			( gate "C1G16"
				( objectStatus "@baseboard_fab2_lib.baseboard_fab2(sch_1):page223_i12" )
			)
			( gate "U25W16"
				( objectStatus "@baseboard_fab2_lib.baseboard_fab2(sch_1):page268_i38" )
			)
			( gate "R1G5"
				( objectStatus "@baseboard_fab2_lib.baseboard_fab2(sch_1):page223_i13" )
			)
			( gate "R9U7"
				( objectStatus "@baseboard_fab2_lib.baseboard_fab2(sch_1):page223_i14" )
			)
			( gate "RF19"
				( objectStatus "@baseboard_fab2_lib.baseboard_fab2(sch_1):page223_i16" )
			)
			( gate "CF20"
				( objectStatus "@baseboard_fab2_lib.baseboard_fab2(sch_1):page223_i17" )
			)
			( gate "R1B5"
				( objectStatus "@baseboard_fab2_lib.baseboard_fab2(sch_1):page226_i55" )
			)
			( gate "R1B4"
				( objectStatus "@baseboard_fab2_lib.baseboard_fab2(sch_1):page226_i54" )
			)
			( gate "EU4G2"
				( objectStatus "@baseboard_fab2_lib.baseboard_fab2(sch_1):page229_i37" )
			)
			( gate "C1G24"
				( objectStatus "@baseboard_fab2_lib.baseboard_fab2(sch_1):page223_i27" )
			)
			( gate "R9U10"
				( objectStatus "@baseboard_fab2_lib.baseboard_fab2(sch_1):page223_i32" )
			)
			( gate "C1G27"
				( objectStatus "@baseboard_fab2_lib.baseboard_fab2(sch_1):page223_i36" )
			)
			( gate "C6W13"
				( objectStatus "@baseboard_fab2_lib.baseboard_fab2(sch_1):page230_i43" )
			)
			( gate "R1G10"
				( objectStatus "@baseboard_fab2_lib.baseboard_fab2(sch_1):page223_i41" )
			)
			( gate "C1G23"
				( objectStatus "@baseboard_fab2_lib.baseboard_fab2(sch_1):page223_i44" )
			)
			( gate "R1G9"
				( objectStatus "@baseboard_fab2_lib.baseboard_fab2(sch_1):page223_i50" )
			)
			( gate "R12W33"
				( objectStatus "@baseboard_fab2_lib.baseboard_fab2(sch_1):page223_i53" )
			)
			( gate "C2F2"
				( objectStatus "@baseboard_fab2_lib.baseboard_fab2(sch_1):page229_i28" )
			)
			( gate "C4G13"
				( objectStatus "@baseboard_fab2_lib.baseboard_fab2(sch_1):page229_i26" )
			)
			( gate "C4G20"
				( objectStatus "@baseboard_fab2_lib.baseboard_fab2(sch_1):page229_i23" )
			)
			( gate "C6U14"
				( objectStatus "@baseboard_fab2_lib.baseboard_fab2(sch_1):page229_i18" )
			)
			( gate "C4G18"
				( objectStatus "@baseboard_fab2_lib.baseboard_fab2(sch_1):page229_i16" )
			)
			( gate "SH8U1"
				( objectStatus "@baseboard_fab2_lib.baseboard_fab2(sch_1):page229_i12" )
			)
			( gate "C6U13"
				( objectStatus "@baseboard_fab2_lib.baseboard_fab2(sch_1):page229_i11" )
			)
			( gate "R4W1"
				( objectStatus "@baseboard_fab2_lib.baseboard_fab2(sch_1):page191_i195" )
			)
			( gate "R6U7"
				( objectStatus "@baseboard_fab2_lib.baseboard_fab2(sch_1):page229_i9" )
			)
			( gate "C4W2"
				( objectStatus "@baseboard_fab2_lib.baseboard_fab2(sch_1):page213_i101" )
			)
			( gate "C1G17"
				( objectStatus "@baseboard_fab2_lib.baseboard_fab2(sch_1):page224_i6" )
			)
			( gate "C1G11"
				( objectStatus "@baseboard_fab2_lib.baseboard_fab2(sch_1):page224_i44" )
			)
			( gate "C9U6"
				( objectStatus "@baseboard_fab2_lib.baseboard_fab2(sch_1):page224_i45" )
			)
			( gate "C9U4"
				( objectStatus "@baseboard_fab2_lib.baseboard_fab2(sch_1):page224_i46" )
			)
			( gate "C9T4"
				( objectStatus "@baseboard_fab2_lib.baseboard_fab2(sch_1):page224_i47" )
			)
			( gate "C1F27"
				( objectStatus "@baseboard_fab2_lib.baseboard_fab2(sch_1):page224_i48" )
			)
			( gate "C1G6"
				( objectStatus "@baseboard_fab2_lib.baseboard_fab2(sch_1):page224_i50" )
			)
			( gate "C1G14"
				( objectStatus "@baseboard_fab2_lib.baseboard_fab2(sch_1):page224_i51" )
			)
			( gate "R3L4"
				( objectStatus "@baseboard_fab2_lib.baseboard_fab2(sch_1):page236_i177" )
			)
			( gate "C3L29"
				( objectStatus "@baseboard_fab2_lib.baseboard_fab2(sch_1):page236_i181" )
			)
			( gate "C1G5"
				( objectStatus "@baseboard_fab2_lib.baseboard_fab2(sch_1):page224_i54" )
			)
			( gate "L1A2"
				( objectStatus "@baseboard_fab2_lib.baseboard_fab2(sch_1):page227_i152" )
			)
			( gate "C1G20"
				( objectStatus "@baseboard_fab2_lib.baseboard_fab2(sch_1):page224_i68" )
			)
			( gate "C1G29"
				( objectStatus "@baseboard_fab2_lib.baseboard_fab2(sch_1):page224_i72" )
			)
			( gate "C3L1"
				( objectStatus "@baseboard_fab2_lib.baseboard_fab2(sch_1):page236_i180" )
			)
			( gate "C1F26"
				( objectStatus "@baseboard_fab2_lib.baseboard_fab2(sch_1):page224_i75" )
			)
			( gate "R3L1"
				( objectStatus "@baseboard_fab2_lib.baseboard_fab2(sch_1):page236_i175" )
			)
			( gate "C1G28"
				( objectStatus "@baseboard_fab2_lib.baseboard_fab2(sch_1):page224_i77" )
			)
			( gate "C1F28"
				( objectStatus "@baseboard_fab2_lib.baseboard_fab2(sch_1):page224_i78" )
			)
			( gate "C1G13"
				( objectStatus "@baseboard_fab2_lib.baseboard_fab2(sch_1):page224_i79" )
			)
			( gate "C9U3"
				( objectStatus "@baseboard_fab2_lib.baseboard_fab2(sch_1):page224_i80" )
			)
			( gate "C9T6"
				( objectStatus "@baseboard_fab2_lib.baseboard_fab2(sch_1):page224_i81" )
			)
			( gate "C9T9"
				( objectStatus "@baseboard_fab2_lib.baseboard_fab2(sch_1):page224_i84" )
			)
			( gate "EU1G1"
				( objectStatus "@baseboard_fab2_lib.baseboard_fab2(sch_1):page224_i110" )
			)
			( gate "EU1F1"
				( objectStatus "@baseboard_fab2_lib.baseboard_fab2(sch_1):page224_i111" )
			)
			( gate "R1G26"
				( objectStatus "@baseboard_fab2_lib.baseboard_fab2(sch_1):page224_i112" )
			)
			( gate "R1G25"
				( objectStatus "@baseboard_fab2_lib.baseboard_fab2(sch_1):page224_i114" )
			)
			( gate "R1G20"
				( objectStatus "@baseboard_fab2_lib.baseboard_fab2(sch_1):page225_i58" )
			)
			( gate "R7U2"
				( objectStatus "@baseboard_fab2_lib.baseboard_fab2(sch_1):page225_i74" )
			)
			( gate "C9T5"
				( objectStatus "@baseboard_fab2_lib.baseboard_fab2(sch_1):page225_i75" )
			)
			( gate "C9U2"
				( objectStatus "@baseboard_fab2_lib.baseboard_fab2(sch_1):page225_i76" )
			)
			( gate "C9U9"
				( objectStatus "@baseboard_fab2_lib.baseboard_fab2(sch_1):page225_i77" )
			)
			( gate "C9U5"
				( objectStatus "@baseboard_fab2_lib.baseboard_fab2(sch_1):page225_i78" )
			)
			( gate "C8U8"
				( objectStatus "@baseboard_fab2_lib.baseboard_fab2(sch_1):page225_i320" )
			)
			( gate "C8L1"
				( objectStatus "@baseboard_fab2_lib.baseboard_fab2(sch_1):page228_i301" )
			)
			( gate "C2G16"
				( objectStatus "@baseboard_fab2_lib.baseboard_fab2(sch_1):page225_i311" )
			)
			( gate "C7U7"
				( objectStatus "@baseboard_fab2_lib.baseboard_fab2(sch_1):page225_i308" )
			)
			( gate "C8L11"
				( objectStatus "@baseboard_fab2_lib.baseboard_fab2(sch_1):page228_i302" )
			)
			( gate "C8U12"
				( objectStatus "@baseboard_fab2_lib.baseboard_fab2(sch_1):page225_i310" )
			)
			( gate "C8P30"
				( objectStatus "@baseboard_fab2_lib.baseboard_fab2(sch_1):page225_i313" )
			)
			( gate "C2G7"
				( objectStatus "@baseboard_fab2_lib.baseboard_fab2(sch_1):page225_i312" )
			)
			( gate "L1B1"
				( objectStatus "@baseboard_fab2_lib.baseboard_fab2(sch_1):page228_i247" )
			)
			( gate "C7P2"
				( objectStatus "@baseboard_fab2_lib.baseboard_fab2(sch_1):page228_i305" )
			)
			( gate "C2G11"
				( objectStatus "@baseboard_fab2_lib.baseboard_fab2(sch_1):page225_i275" )
			)
			( gate "C2G10"
				( objectStatus "@baseboard_fab2_lib.baseboard_fab2(sch_1):page225_i274" )
			)
			( gate "C8C12"
				( objectStatus "@baseboard_fab2_lib.baseboard_fab2(sch_1):page188_i121" )
			)
			( gate "C8C13"
				( objectStatus "@baseboard_fab2_lib.baseboard_fab2(sch_1):page188_i120" )
			)
			( gate "C8P3"
				( objectStatus "@baseboard_fab2_lib.baseboard_fab2(sch_1):page228_i306" )
			)
			( gate "C1G2"
				( objectStatus "@baseboard_fab2_lib.baseboard_fab2(sch_1):page225_i250" )
			)
			( gate "C22W3"
				( objectStatus "@baseboard_fab2_lib.baseboard_fab2(sch_1):page225_i249" )
			)
			( gate "C4B1"
				( objectStatus "@baseboard_fab2_lib.baseboard_fab2(sch_1):page234_i223" )
			)
			( gate "C22W5"
				( objectStatus "@baseboard_fab2_lib.baseboard_fab2(sch_1):page234_i222" )
			)
			( gate "C8T4"
				( objectStatus "@baseboard_fab2_lib.baseboard_fab2(sch_1):page225_i196" )
			)
			( gate "C2G8"
				( objectStatus "@baseboard_fab2_lib.baseboard_fab2(sch_1):page225_i197" )
			)
			( gate "C8T2"
				( objectStatus "@baseboard_fab2_lib.baseboard_fab2(sch_1):page225_i198" )
			)
			( gate "C8U13"
				( objectStatus "@baseboard_fab2_lib.baseboard_fab2(sch_1):page225_i199" )
			)
			( gate "C2G15"
				( objectStatus "@baseboard_fab2_lib.baseboard_fab2(sch_1):page225_i200" )
			)
			( gate "C2F1"
				( objectStatus "@baseboard_fab2_lib.baseboard_fab2(sch_1):page225_i201" )
			)
			( gate "C8T1"
				( objectStatus "@baseboard_fab2_lib.baseboard_fab2(sch_1):page225_i202" )
			)
			( gate "C8U9"
				( objectStatus "@baseboard_fab2_lib.baseboard_fab2(sch_1):page225_i203" )
			)
			( gate "C8T11"
				( objectStatus "@baseboard_fab2_lib.baseboard_fab2(sch_1):page225_i204" )
			)
			( gate "C2A2"
				( objectStatus "@baseboard_fab2_lib.baseboard_fab2(sch_1):page228_i283" )
			)
			( gate "C2A1"
				( objectStatus "@baseboard_fab2_lib.baseboard_fab2(sch_1):page228_i282" )
			)
			( gate "C2A12"
				( objectStatus "@baseboard_fab2_lib.baseboard_fab2(sch_1):page228_i281" )
			)
			( gate "C2A13"
				( objectStatus "@baseboard_fab2_lib.baseboard_fab2(sch_1):page228_i280" )
			)
			( gate "C2A11"
				( objectStatus "@baseboard_fab2_lib.baseboard_fab2(sch_1):page228_i279" )
			)
			( gate "C2A10"
				( objectStatus "@baseboard_fab2_lib.baseboard_fab2(sch_1):page228_i278" )
			)
			( gate "C2A9"
				( objectStatus "@baseboard_fab2_lib.baseboard_fab2(sch_1):page228_i277" )
			)
			( gate "C3A2"
				( objectStatus "@baseboard_fab2_lib.baseboard_fab2(sch_1):page228_i276" )
			)
			( gate "C3A1"
				( objectStatus "@baseboard_fab2_lib.baseboard_fab2(sch_1):page228_i275" )
			)
			( gate "C2A7"
				( objectStatus "@baseboard_fab2_lib.baseboard_fab2(sch_1):page228_i274" )
			)
			( gate "C2A6"
				( objectStatus "@baseboard_fab2_lib.baseboard_fab2(sch_1):page228_i273" )
			)
			( gate "C2A14"
				( objectStatus "@baseboard_fab2_lib.baseboard_fab2(sch_1):page228_i272" )
			)
			( gate "C2D6"
				( objectStatus "@baseboard_fab2_lib.baseboard_fab2(sch_1):page228_i267" )
			)
			( gate "C2D5"
				( objectStatus "@baseboard_fab2_lib.baseboard_fab2(sch_1):page228_i266" )
			)
			( gate "C2D4"
				( objectStatus "@baseboard_fab2_lib.baseboard_fab2(sch_1):page228_i265" )
			)
			( gate "C2D7"
				( objectStatus "@baseboard_fab2_lib.baseboard_fab2(sch_1):page228_i264" )
			)
			( gate "SH7U1"
				( objectStatus "@baseboard_fab2_lib.baseboard_fab2(sch_1):page225_i243" )
			)
			( gate "SH7U2"
				( objectStatus "@baseboard_fab2_lib.baseboard_fab2(sch_1):page225_i244" )
			)
			( gate "R12W18"
				( objectStatus "@baseboard_fab2_lib.baseboard_fab2(sch_1):page197_i114" )
			)
			( gate "R1B16"
				( objectStatus "@baseboard_fab2_lib.baseboard_fab2(sch_1):page226_i13" )
			)
			( gate "R9M9"
				( objectStatus "@baseboard_fab2_lib.baseboard_fab2(sch_1):page226_i14" )
			)
			( gate "RF21"
				( objectStatus "@baseboard_fab2_lib.baseboard_fab2(sch_1):page226_i16" )
			)
			( gate "CF22"
				( objectStatus "@baseboard_fab2_lib.baseboard_fab2(sch_1):page226_i17" )
			)
			( gate "R12W9"
				( objectStatus "@baseboard_fab2_lib.baseboard_fab2(sch_1):page197_i21" )
			)
			( gate "C1B11"
				( objectStatus "@baseboard_fab2_lib.baseboard_fab2(sch_1):page226_i23" )
			)
			( gate "Q12W2"
				( objectStatus "@baseboard_fab2_lib.baseboard_fab2(sch_1):page197_i19" )
			)
			( gate "R2L9"
				( objectStatus "@baseboard_fab2_lib.baseboard_fab2(sch_1):page235_i254" )
			)
			( gate "C1B5"
				( objectStatus "@baseboard_fab2_lib.baseboard_fab2(sch_1):page226_i32" )
			)
			( gate "R9M3"
				( objectStatus "@baseboard_fab2_lib.baseboard_fab2(sch_1):page226_i36" )
			)
			( gate "C12W4"
				( objectStatus "@baseboard_fab2_lib.baseboard_fab2(sch_1):page197_i18" )
			)
			( gate "R1B10"
				( objectStatus "@baseboard_fab2_lib.baseboard_fab2(sch_1):page226_i41" )
			)
			( gate "C1B2"
				( objectStatus "@baseboard_fab2_lib.baseboard_fab2(sch_1):page226_i44" )
			)
			( gate "R1B2"
				( objectStatus "@baseboard_fab2_lib.baseboard_fab2(sch_1):page226_i50" )
			)
			( gate "R12W36"
				( objectStatus "@baseboard_fab2_lib.baseboard_fab2(sch_1):page226_i53" )
			)
			( gate "R4F2"
				( objectStatus "@baseboard_fab2_lib.baseboard_fab2(sch_1):page197_i14" )
			)
			( gate "R12W3"
				( objectStatus "@baseboard_fab2_lib.baseboard_fab2(sch_1):page197_i115" )
			)
			( gate "C12W1"
				( objectStatus "@baseboard_fab2_lib.baseboard_fab2(sch_1):page197_i8" )
			)
			( gate "R4B12"
				( objectStatus "@baseboard_fab2_lib.baseboard_fab2(sch_1):page197_i6" )
			)
			( gate "C4W1"
				( objectStatus "@baseboard_fab2_lib.baseboard_fab2(sch_1):page211_i97" )
			)
			( gate "C1A12"
				( objectStatus "@baseboard_fab2_lib.baseboard_fab2(sch_1):page227_i6" )
			)
			( gate "C1A18"
				( objectStatus "@baseboard_fab2_lib.baseboard_fab2(sch_1):page227_i44" )
			)
			( gate "C9L11"
				( objectStatus "@baseboard_fab2_lib.baseboard_fab2(sch_1):page227_i45" )
			)
			( gate "C9L10"
				( objectStatus "@baseboard_fab2_lib.baseboard_fab2(sch_1):page227_i46" )
			)
			( gate "C9L6"
				( objectStatus "@baseboard_fab2_lib.baseboard_fab2(sch_1):page227_i47" )
			)
			( gate "C1A19"
				( objectStatus "@baseboard_fab2_lib.baseboard_fab2(sch_1):page227_i48" )
			)
			( gate "C1B20"
				( objectStatus "@baseboard_fab2_lib.baseboard_fab2(sch_1):page227_i50" )
			)
			( gate "C1A10"
				( objectStatus "@baseboard_fab2_lib.baseboard_fab2(sch_1):page227_i51" )
			)
			( gate "C1D5"
				( objectStatus "@baseboard_fab2_lib.baseboard_fab2(sch_1):page208_i119" )
			)
			( gate "C1B21"
				( objectStatus "@baseboard_fab2_lib.baseboard_fab2(sch_1):page227_i54" )
			)
			( gate "L7C1"
				( objectStatus "@baseboard_fab2_lib.baseboard_fab2(sch_1):page212_i142" )
			)
			( gate "L7C2"
				( objectStatus "@baseboard_fab2_lib.baseboard_fab2(sch_1):page212_i141" )
			)
			( gate "C1A1"
				( objectStatus "@baseboard_fab2_lib.baseboard_fab2(sch_1):page227_i68" )
			)
			( gate "C1A13"
				( objectStatus "@baseboard_fab2_lib.baseboard_fab2(sch_1):page227_i72" )
			)
			( gate "C1C3"
				( objectStatus "@baseboard_fab2_lib.baseboard_fab2(sch_1):page210_i73" )
			)
			( gate "C1A8"
				( objectStatus "@baseboard_fab2_lib.baseboard_fab2(sch_1):page227_i75" )
			)
			( gate "C1A6"
				( objectStatus "@baseboard_fab2_lib.baseboard_fab2(sch_1):page227_i77" )
			)
			( gate "C1A20"
				( objectStatus "@baseboard_fab2_lib.baseboard_fab2(sch_1):page227_i78" )
			)
			( gate "C1A9"
				( objectStatus "@baseboard_fab2_lib.baseboard_fab2(sch_1):page227_i79" )
			)
			( gate "C9L5"
				( objectStatus "@baseboard_fab2_lib.baseboard_fab2(sch_1):page227_i80" )
			)
			( gate "C9L13"
				( objectStatus "@baseboard_fab2_lib.baseboard_fab2(sch_1):page227_i81" )
			)
			( gate "C9L14"
				( objectStatus "@baseboard_fab2_lib.baseboard_fab2(sch_1):page227_i84" )
			)
			( gate "EU1A2"
				( objectStatus "@baseboard_fab2_lib.baseboard_fab2(sch_1):page227_i101" )
			)
			( gate "EU1A1"
				( objectStatus "@baseboard_fab2_lib.baseboard_fab2(sch_1):page227_i102" )
			)
			( gate "R1A3"
				( objectStatus "@baseboard_fab2_lib.baseboard_fab2(sch_1):page227_i103" )
			)
			( gate "R1A2"
				( objectStatus "@baseboard_fab2_lib.baseboard_fab2(sch_1):page227_i105" )
			)
			( gate "R1A1"
				( objectStatus "@baseboard_fab2_lib.baseboard_fab2(sch_1):page228_i58" )
			)
			( gate "R7L2"
				( objectStatus "@baseboard_fab2_lib.baseboard_fab2(sch_1):page228_i74" )
			)
			( gate "C9L9"
				( objectStatus "@baseboard_fab2_lib.baseboard_fab2(sch_1):page228_i75" )
			)
			( gate "C9L12"
				( objectStatus "@baseboard_fab2_lib.baseboard_fab2(sch_1):page228_i76" )
			)
			( gate "C9L4"
				( objectStatus "@baseboard_fab2_lib.baseboard_fab2(sch_1):page228_i77" )
			)
			( gate "C9L2"
				( objectStatus "@baseboard_fab2_lib.baseboard_fab2(sch_1):page228_i78" )
			)
			( gate "C8L2"
				( objectStatus "@baseboard_fab2_lib.baseboard_fab2(sch_1):page228_i310" )
			)
			( gate "C8M11"
				( objectStatus "@baseboard_fab2_lib.baseboard_fab2(sch_1):page228_i311" )
			)
			( gate "C8U10"
				( objectStatus "@baseboard_fab2_lib.baseboard_fab2(sch_1):page229_i42" )
			)
			( gate "C7L1"
				( objectStatus "@baseboard_fab2_lib.baseboard_fab2(sch_1):page228_i314" )
			)
			( gate "C8T3"
				( objectStatus "@baseboard_fab2_lib.baseboard_fab2(sch_1):page229_i41" )
			)
			( gate "C8P4"
				( objectStatus "@baseboard_fab2_lib.baseboard_fab2(sch_1):page228_i307" )
			)
			( gate "C1B10"
				( objectStatus "@baseboard_fab2_lib.baseboard_fab2(sch_1):page228_i175" )
			)
			( gate "C8M7"
				( objectStatus "@baseboard_fab2_lib.baseboard_fab2(sch_1):page228_i312" )
			)
			( gate "C7P1"
				( objectStatus "@baseboard_fab2_lib.baseboard_fab2(sch_1):page228_i308" )
			)
			( gate "C2A15"
				( objectStatus "@baseboard_fab2_lib.baseboard_fab2(sch_1):page228_i271" )
			)
			( gate "C3A5"
				( objectStatus "@baseboard_fab2_lib.baseboard_fab2(sch_1):page228_i270" )
			)
			( gate "C3A6"
				( objectStatus "@baseboard_fab2_lib.baseboard_fab2(sch_1):page228_i269" )
			)
			( gate "C7L5"
				( objectStatus "@baseboard_fab2_lib.baseboard_fab2(sch_1):page228_i268" )
			)
			( gate "C8M8"
				( objectStatus "@baseboard_fab2_lib.baseboard_fab2(sch_1):page228_i198" )
			)
			( gate "C2A5"
				( objectStatus "@baseboard_fab2_lib.baseboard_fab2(sch_1):page228_i199" )
			)
			( gate "C2B1"
				( objectStatus "@baseboard_fab2_lib.baseboard_fab2(sch_1):page228_i200" )
			)
			( gate "C8L12"
				( objectStatus "@baseboard_fab2_lib.baseboard_fab2(sch_1):page228_i201" )
			)
			( gate "C7M5"
				( objectStatus "@baseboard_fab2_lib.baseboard_fab2(sch_1):page228_i202" )
			)
			( gate "C8M10"
				( objectStatus "@baseboard_fab2_lib.baseboard_fab2(sch_1):page228_i203" )
			)
			( gate "C2B2"
				( objectStatus "@baseboard_fab2_lib.baseboard_fab2(sch_1):page228_i204" )
			)
			( gate "C8M9"
				( objectStatus "@baseboard_fab2_lib.baseboard_fab2(sch_1):page228_i205" )
			)
			( gate "C8M2"
				( objectStatus "@baseboard_fab2_lib.baseboard_fab2(sch_1):page228_i206" )
			)
			( gate "C8M3"
				( objectStatus "@baseboard_fab2_lib.baseboard_fab2(sch_1):page228_i299" )
			)
			( gate "C8M5"
				( objectStatus "@baseboard_fab2_lib.baseboard_fab2(sch_1):page228_i298" )
			)
			( gate "C8L10"
				( objectStatus "@baseboard_fab2_lib.baseboard_fab2(sch_1):page228_i297" )
			)
			( gate "C2A3"
				( objectStatus "@baseboard_fab2_lib.baseboard_fab2(sch_1):page228_i296" )
			)
			( gate "C7M1"
				( objectStatus "@baseboard_fab2_lib.baseboard_fab2(sch_1):page228_i295" )
			)
			( gate "C7M2"
				( objectStatus "@baseboard_fab2_lib.baseboard_fab2(sch_1):page228_i294" )
			)
			( gate "C8M4"
				( objectStatus "@baseboard_fab2_lib.baseboard_fab2(sch_1):page228_i293" )
			)
			( gate "C2A4"
				( objectStatus "@baseboard_fab2_lib.baseboard_fab2(sch_1):page228_i292" )
			)
			( gate "C8M6"
				( objectStatus "@baseboard_fab2_lib.baseboard_fab2(sch_1):page228_i291" )
			)
			( gate "C8L9"
				( objectStatus "@baseboard_fab2_lib.baseboard_fab2(sch_1):page228_i290" )
			)
			( gate "C8L8"
				( objectStatus "@baseboard_fab2_lib.baseboard_fab2(sch_1):page228_i289" )
			)
			( gate "C7L4"
				( objectStatus "@baseboard_fab2_lib.baseboard_fab2(sch_1):page228_i288" )
			)
			( gate "C8L7"
				( objectStatus "@baseboard_fab2_lib.baseboard_fab2(sch_1):page228_i287" )
			)
			( gate "C8L6"
				( objectStatus "@baseboard_fab2_lib.baseboard_fab2(sch_1):page228_i286" )
			)
			( gate "C8L5"
				( objectStatus "@baseboard_fab2_lib.baseboard_fab2(sch_1):page228_i285" )
			)
			( gate "C8M1"
				( objectStatus "@baseboard_fab2_lib.baseboard_fab2(sch_1):page228_i284" )
			)
			( gate "SH7L2"
				( objectStatus "@baseboard_fab2_lib.baseboard_fab2(sch_1):page228_i245" )
			)
			( gate "SH7L1"
				( objectStatus "@baseboard_fab2_lib.baseboard_fab2(sch_1):page228_i246" )
			)
			( gate "C6U11"
				( objectStatus "@baseboard_fab2_lib.baseboard_fab2(sch_1):page229_i14" )
			)
			( gate "R1B1"
				( objectStatus "@baseboard_fab2_lib.baseboard_fab2(sch_1):page226_i49" )
			)
			( gate "R1B11"
				( objectStatus "@baseboard_fab2_lib.baseboard_fab2(sch_1):page226_i48" )
			)
			( gate "C4G21"
				( objectStatus "@baseboard_fab2_lib.baseboard_fab2(sch_1):page229_i21" )
			)
			( gate "R4G17"
				( objectStatus "@baseboard_fab2_lib.baseboard_fab2(sch_1):page229_i24" )
			)
			( gate "R12W35"
				( objectStatus "@baseboard_fab2_lib.baseboard_fab2(sch_1):page226_i46" )
			)
			( gate "C1B3"
				( objectStatus "@baseboard_fab2_lib.baseboard_fab2(sch_1):page226_i45" )
			)
			( gate "R4G15"
				( objectStatus "@baseboard_fab2_lib.baseboard_fab2(sch_1):page229_i32" )
			)
			( gate "C1B4"
				( objectStatus "@baseboard_fab2_lib.baseboard_fab2(sch_1):page226_i40" )
			)
			( gate "C1B6"
				( objectStatus "@baseboard_fab2_lib.baseboard_fab2(sch_1):page226_i38" )
			)
			( gate "R9M5"
				( objectStatus "@baseboard_fab2_lib.baseboard_fab2(sch_1):page226_i34" )
			)
			( gate "R9U4"
				( objectStatus "@baseboard_fab2_lib.baseboard_fab2(sch_1):page223_i70" )
			)
			( gate "R1B8"
				( objectStatus "@baseboard_fab2_lib.baseboard_fab2(sch_1):page226_i19" )
			)
			( gate "RF22"
				( objectStatus "@baseboard_fab2_lib.baseboard_fab2(sch_1):page226_i18" )
			)
			( gate "CF21"
				( objectStatus "@baseboard_fab2_lib.baseboard_fab2(sch_1):page226_i15" )
			)
			( gate "C1B12"
				( objectStatus "@baseboard_fab2_lib.baseboard_fab2(sch_1):page226_i12" )
			)
			( gate "C4A15"
				( objectStatus "@baseboard_fab2_lib.baseboard_fab2(sch_1):page230_i17" )
			)
			( gate "R4A5"
				( objectStatus "@baseboard_fab2_lib.baseboard_fab2(sch_1):page230_i21" )
			)
			( gate "SH8L1"
				( objectStatus "@baseboard_fab2_lib.baseboard_fab2(sch_1):page230_i30" )
			)
			( gate "C5U12"
				( objectStatus "@baseboard_fab2_lib.baseboard_fab2(sch_1):page221_i45" )
			)
			( gate "EU4A2"
				( objectStatus "@baseboard_fab2_lib.baseboard_fab2(sch_1):page230_i37" )
			)
			( gate "C6F6"
				( objectStatus "@baseboard_fab2_lib.baseboard_fab2(sch_1):page231_i122" )
			)
			( gate "C4T6"
				( objectStatus "@baseboard_fab2_lib.baseboard_fab2(sch_1):page231_i124" )
			)
			( gate "C4T5"
				( objectStatus "@baseboard_fab2_lib.baseboard_fab2(sch_1):page231_i125" )
			)
			( gate "C6G1"
				( objectStatus "@baseboard_fab2_lib.baseboard_fab2(sch_1):page231_i126" )
			)
			( gate "C6G2"
				( objectStatus "@baseboard_fab2_lib.baseboard_fab2(sch_1):page231_i128" )
			)
			( gate "C4U2"
				( objectStatus "@baseboard_fab2_lib.baseboard_fab2(sch_1):page231_i129" )
			)
			( gate "C4U1"
				( objectStatus "@baseboard_fab2_lib.baseboard_fab2(sch_1):page231_i130" )
			)
			( gate "C6G4"
				( objectStatus "@baseboard_fab2_lib.baseboard_fab2(sch_1):page231_i131" )
			)
			( gate "R7F15"
				( objectStatus "@baseboard_fab2_lib.baseboard_fab2(sch_1):page231_i134" )
			)
			( gate "R7F14"
				( objectStatus "@baseboard_fab2_lib.baseboard_fab2(sch_1):page231_i136" )
			)
			( gate "C7F8"
				( objectStatus "@baseboard_fab2_lib.baseboard_fab2(sch_1):page231_i140" )
			)
			( gate "C7F11"
				( objectStatus "@baseboard_fab2_lib.baseboard_fab2(sch_1):page231_i142" )
			)
			( gate "R7F19"
				( objectStatus "@baseboard_fab2_lib.baseboard_fab2(sch_1):page231_i143" )
			)
			( gate "C6G5"
				( objectStatus "@baseboard_fab2_lib.baseboard_fab2(sch_1):page231_i145" )
			)
			( gate "C4U4"
				( objectStatus "@baseboard_fab2_lib.baseboard_fab2(sch_1):page231_i146" )
			)
			( gate "C4U3"
				( objectStatus "@baseboard_fab2_lib.baseboard_fab2(sch_1):page231_i148" )
			)
			( gate "C6F5"
				( objectStatus "@baseboard_fab2_lib.baseboard_fab2(sch_1):page231_i149" )
			)
			( gate "C8E11"
				( objectStatus "@baseboard_fab2_lib.baseboard_fab2(sch_1):page240_i183" )
			)
			( gate "R7B19"
				( objectStatus "@baseboard_fab2_lib.baseboard_fab2(sch_1):page232_i313" )
			)
			( gate "C7F4"
				( objectStatus "@baseboard_fab2_lib.baseboard_fab2(sch_1):page231_i159" )
			)
			( gate "C3T10"
				( objectStatus "@baseboard_fab2_lib.baseboard_fab2(sch_1):page231_i161" )
			)
			( gate "FB7F1"
				( objectStatus "@baseboard_fab2_lib.baseboard_fab2(sch_1):page231_i162" )
			)
			( gate "R7B13"
				( objectStatus "@baseboard_fab2_lib.baseboard_fab2(sch_1):page232_i314" )
			)
			( gate "R7F13"
				( objectStatus "@baseboard_fab2_lib.baseboard_fab2(sch_1):page231_i167" )
			)
			( gate "R7F12"
				( objectStatus "@baseboard_fab2_lib.baseboard_fab2(sch_1):page231_i168" )
			)
			( gate "R7F35"
				( objectStatus "@baseboard_fab2_lib.baseboard_fab2(sch_1):page231_i170" )
			)
			( gate "R7F7"
				( objectStatus "@baseboard_fab2_lib.baseboard_fab2(sch_1):page231_i174" )
			)
			( gate "C7F3"
				( objectStatus "@baseboard_fab2_lib.baseboard_fab2(sch_1):page231_i175" )
			)
			( gate "R7F10"
				( objectStatus "@baseboard_fab2_lib.baseboard_fab2(sch_1):page231_i177" )
			)
			( gate "L7F1"
				( objectStatus "@baseboard_fab2_lib.baseboard_fab2(sch_1):page231_i178" )
			)
			( gate "C6F4"
				( objectStatus "@baseboard_fab2_lib.baseboard_fab2(sch_1):page231_i180" )
			)
			( gate "C3T7"
				( objectStatus "@baseboard_fab2_lib.baseboard_fab2(sch_1):page231_i184" )
			)
			( gate "C3T9"
				( objectStatus "@baseboard_fab2_lib.baseboard_fab2(sch_1):page231_i186" )
			)
			( gate "EU7F1"
				( objectStatus "@baseboard_fab2_lib.baseboard_fab2(sch_1):page231_i193" )
			)
			( gate "C7F10"
				( objectStatus "@baseboard_fab2_lib.baseboard_fab2(sch_1):page231_i194" )
			)
			( gate "C7F9"
				( objectStatus "@baseboard_fab2_lib.baseboard_fab2(sch_1):page231_i199" )
			)
			( gate "C7F12"
				( objectStatus "@baseboard_fab2_lib.baseboard_fab2(sch_1):page231_i200" )
			)
			( gate "R7F18"
				( objectStatus "@baseboard_fab2_lib.baseboard_fab2(sch_1):page231_i201" )
			)
			( gate "C3T11"
				( objectStatus "@baseboard_fab2_lib.baseboard_fab2(sch_1):page231_i202" )
			)
			( gate "C7F6"
				( objectStatus "@baseboard_fab2_lib.baseboard_fab2(sch_1):page231_i205" )
			)
			( gate "R7F16"
				( objectStatus "@baseboard_fab2_lib.baseboard_fab2(sch_1):page231_i208" )
			)
			( gate "C7F5"
				( objectStatus "@baseboard_fab2_lib.baseboard_fab2(sch_1):page231_i209" )
			)
			( gate "C3T8"
				( objectStatus "@baseboard_fab2_lib.baseboard_fab2(sch_1):page231_i210" )
			)
			( gate "C3T14"
				( objectStatus "@baseboard_fab2_lib.baseboard_fab2(sch_1):page231_i211" )
			)
			( gate "C3T12"
				( objectStatus "@baseboard_fab2_lib.baseboard_fab2(sch_1):page231_i215" )
			)
			( gate "C4T3"
				( objectStatus "@baseboard_fab2_lib.baseboard_fab2(sch_1):page231_i217" )
			)
			( gate "R7F17"
				( objectStatus "@baseboard_fab2_lib.baseboard_fab2(sch_1):page231_i218" )
			)
			( gate "C7F13"
				( objectStatus "@baseboard_fab2_lib.baseboard_fab2(sch_1):page231_i219" )
			)
			( gate "R7F9"
				( objectStatus "@baseboard_fab2_lib.baseboard_fab2(sch_1):page231_i220" )
			)
			( gate "C4L2"
				( objectStatus "@baseboard_fab2_lib.baseboard_fab2(sch_1):page232_i102" )
			)
			( gate "C6A3"
				( objectStatus "@baseboard_fab2_lib.baseboard_fab2(sch_1):page232_i104" )
			)
			( gate "C6A2"
				( objectStatus "@baseboard_fab2_lib.baseboard_fab2(sch_1):page232_i105" )
			)
			( gate "C4L3"
				( objectStatus "@baseboard_fab2_lib.baseboard_fab2(sch_1):page232_i106" )
			)
			( gate "C4L4"
				( objectStatus "@baseboard_fab2_lib.baseboard_fab2(sch_1):page232_i108" )
			)
			( gate "C6A7"
				( objectStatus "@baseboard_fab2_lib.baseboard_fab2(sch_1):page232_i109" )
			)
			( gate "C6A6"
				( objectStatus "@baseboard_fab2_lib.baseboard_fab2(sch_1):page232_i110" )
			)
			( gate "C4M3"
				( objectStatus "@baseboard_fab2_lib.baseboard_fab2(sch_1):page232_i111" )
			)
			( gate "C4M4"
				( objectStatus "@baseboard_fab2_lib.baseboard_fab2(sch_1):page232_i125" )
			)
			( gate "C6B2"
				( objectStatus "@baseboard_fab2_lib.baseboard_fab2(sch_1):page232_i126" )
			)
			( gate "C6B1"
				( objectStatus "@baseboard_fab2_lib.baseboard_fab2(sch_1):page232_i128" )
			)
			( gate "C4L1"
				( objectStatus "@baseboard_fab2_lib.baseboard_fab2(sch_1):page232_i129" )
			)
			( gate "R7B20"
				( objectStatus "@baseboard_fab2_lib.baseboard_fab2(sch_1):page232_i150" )
			)
			( gate "C7B9"
				( objectStatus "@baseboard_fab2_lib.baseboard_fab2(sch_1):page232_i185" )
			)
			( gate "R4G11"
				( objectStatus "@baseboard_fab2_lib.baseboard_fab2(sch_1):page233_i284" )
			)
			( gate "C7B11"
				( objectStatus "@baseboard_fab2_lib.baseboard_fab2(sch_1):page232_i197" )
			)
			( gate "FB7B1"
				( objectStatus "@baseboard_fab2_lib.baseboard_fab2(sch_1):page232_i200" )
			)
			( gate "C7E13"
				( objectStatus "@baseboard_fab2_lib.baseboard_fab2(sch_1):page241_i92" )
			)
			( gate "C3M9"
				( objectStatus "@baseboard_fab2_lib.baseboard_fab2(sch_1):page232_i207" )
			)
			( gate "C7B12"
				( objectStatus "@baseboard_fab2_lib.baseboard_fab2(sch_1):page232_i209" )
			)
			( gate "R7B17"
				( objectStatus "@baseboard_fab2_lib.baseboard_fab2(sch_1):page232_i210" )
			)
			( gate "EU7B1"
				( objectStatus "@baseboard_fab2_lib.baseboard_fab2(sch_1):page232_i214" )
			)
			( gate "R7A15"
				( objectStatus "@baseboard_fab2_lib.baseboard_fab2(sch_1):page232_i218" )
			)
			( gate "C7A34"
				( objectStatus "@baseboard_fab2_lib.baseboard_fab2(sch_1):page232_i220" )
			)
			( gate "R7B10"
				( objectStatus "@baseboard_fab2_lib.baseboard_fab2(sch_1):page232_i227" )
			)
			( gate "C6B7"
				( objectStatus "@baseboard_fab2_lib.baseboard_fab2(sch_1):page232_i229" )
			)
			( gate "C6B3"
				( objectStatus "@baseboard_fab2_lib.baseboard_fab2(sch_1):page232_i236" )
			)
			( gate "C7B7"
				( objectStatus "@baseboard_fab2_lib.baseboard_fab2(sch_1):page232_i238" )
			)
			( gate "L7B1"
				( objectStatus "@baseboard_fab2_lib.baseboard_fab2(sch_1):page232_i239" )
			)
			( gate "R4B13"
				( objectStatus "@baseboard_fab2_lib.baseboard_fab2(sch_1):page234_i226" )
			)
			( gate "C7B30"
				( objectStatus "@baseboard_fab2_lib.baseboard_fab2(sch_1):page232_i241" )
			)
			( gate "C7B6"
				( objectStatus "@baseboard_fab2_lib.baseboard_fab2(sch_1):page232_i252" )
			)
			( gate "C3M10"
				( objectStatus "@baseboard_fab2_lib.baseboard_fab2(sch_1):page232_i253" )
			)
			( gate "R7B12"
				( objectStatus "@baseboard_fab2_lib.baseboard_fab2(sch_1):page232_i257" )
			)
			( gate "C3M8"
				( objectStatus "@baseboard_fab2_lib.baseboard_fab2(sch_1):page232_i259" )
			)
			( gate "C3M15"
				( objectStatus "@baseboard_fab2_lib.baseboard_fab2(sch_1):page232_i260" )
			)
			( gate "C3M16"
				( objectStatus "@baseboard_fab2_lib.baseboard_fab2(sch_1):page232_i261" )
			)
			( gate "C7B5"
				( objectStatus "@baseboard_fab2_lib.baseboard_fab2(sch_1):page232_i262" )
			)
			( gate "C4M1"
				( objectStatus "@baseboard_fab2_lib.baseboard_fab2(sch_1):page232_i267" )
			)
			( gate "R7B18"
				( objectStatus "@baseboard_fab2_lib.baseboard_fab2(sch_1):page232_i298" )
			)
			( gate "R7B11"
				( objectStatus "@baseboard_fab2_lib.baseboard_fab2(sch_1):page232_i299" )
			)
			( gate "R7B16"
				( objectStatus "@baseboard_fab2_lib.baseboard_fab2(sch_1):page232_i300" )
			)
			( gate "C7B10"
				( objectStatus "@baseboard_fab2_lib.baseboard_fab2(sch_1):page232_i301" )
			)
			( gate "C7B13"
				( objectStatus "@baseboard_fab2_lib.baseboard_fab2(sch_1):page232_i302" )
			)
			( gate "R7B15"
				( objectStatus "@baseboard_fab2_lib.baseboard_fab2(sch_1):page232_i303" )
			)
			( gate "R4G9"
				( objectStatus "@baseboard_fab2_lib.baseboard_fab2(sch_1):page233_i283" )
			)
			( gate "C7B14"
				( objectStatus "@baseboard_fab2_lib.baseboard_fab2(sch_1):page232_i306" )
			)
			( gate "R7B9"
				( objectStatus "@baseboard_fab2_lib.baseboard_fab2(sch_1):page232_i307" )
			)
			( gate "C7U4"
				( objectStatus "@baseboard_fab2_lib.baseboard_fab2(sch_1):page233_i109" )
			)
			( gate "C7U5"
				( objectStatus "@baseboard_fab2_lib.baseboard_fab2(sch_1):page233_i111" )
			)
			( gate "C7T2"
				( objectStatus "@baseboard_fab2_lib.baseboard_fab2(sch_1):page233_i112" )
			)
			( gate "C7T3"
				( objectStatus "@baseboard_fab2_lib.baseboard_fab2(sch_1):page233_i113" )
			)
			( gate "C7U6"
				( objectStatus "@baseboard_fab2_lib.baseboard_fab2(sch_1):page233_i115" )
			)
			( gate "C3F3"
				( objectStatus "@baseboard_fab2_lib.baseboard_fab2(sch_1):page233_i116" )
			)
			( gate "C3F4"
				( objectStatus "@baseboard_fab2_lib.baseboard_fab2(sch_1):page233_i117" )
			)
			( gate "C3G3"
				( objectStatus "@baseboard_fab2_lib.baseboard_fab2(sch_1):page233_i118" )
			)
			( gate "C3G7"
				( objectStatus "@baseboard_fab2_lib.baseboard_fab2(sch_1):page233_i132" )
			)
			( gate "C3G4"
				( objectStatus "@baseboard_fab2_lib.baseboard_fab2(sch_1):page233_i133" )
			)
			( gate "C3G8"
				( objectStatus "@baseboard_fab2_lib.baseboard_fab2(sch_1):page233_i135" )
			)
			( gate "C7U3"
				( objectStatus "@baseboard_fab2_lib.baseboard_fab2(sch_1):page233_i136" )
			)
			( gate "R4G25"
				( objectStatus "@baseboard_fab2_lib.baseboard_fab2(sch_1):page233_i157" )
			)
			( gate "R4G5"
				( objectStatus "@baseboard_fab2_lib.baseboard_fab2(sch_1):page233_i182" )
			)
			( gate "C4G7"
				( objectStatus "@baseboard_fab2_lib.baseboard_fab2(sch_1):page233_i183" )
			)
			( gate "R4B6"
				( objectStatus "@baseboard_fab2_lib.baseboard_fab2(sch_1):page234_i228" )
			)
			( gate "R4G14"
				( objectStatus "@baseboard_fab2_lib.baseboard_fab2(sch_1):page233_i185" )
			)
			( gate "C6U6"
				( objectStatus "@baseboard_fab2_lib.baseboard_fab2(sch_1):page233_i187" )
			)
			( gate "C7B8"
				( objectStatus "@baseboard_fab2_lib.baseboard_fab2(sch_1):page232_i309" )
			)
			( gate "C4G8"
				( objectStatus "@baseboard_fab2_lib.baseboard_fab2(sch_1):page233_i194" )
			)
			( gate "C4G4"
				( objectStatus "@baseboard_fab2_lib.baseboard_fab2(sch_1):page233_i196" )
			)
			( gate "FB4G1"
				( objectStatus "@baseboard_fab2_lib.baseboard_fab2(sch_1):page233_i198" )
			)
			( gate "C4G9"
				( objectStatus "@baseboard_fab2_lib.baseboard_fab2(sch_1):page233_i201" )
			)
			( gate "R4F6"
				( objectStatus "@baseboard_fab2_lib.baseboard_fab2(sch_1):page233_i208" )
			)
			( gate "C4F12"
				( objectStatus "@baseboard_fab2_lib.baseboard_fab2(sch_1):page233_i209" )
			)
			( gate "R4G6"
				( objectStatus "@baseboard_fab2_lib.baseboard_fab2(sch_1):page233_i211" )
			)
			( gate "C4F7"
				( objectStatus "@baseboard_fab2_lib.baseboard_fab2(sch_1):page233_i217" )
			)
			( gate "C6U3"
				( objectStatus "@baseboard_fab2_lib.baseboard_fab2(sch_1):page233_i221" )
			)
			( gate "C6U2"
				( objectStatus "@baseboard_fab2_lib.baseboard_fab2(sch_1):page233_i223" )
			)
			( gate "C4G26"
				( objectStatus "@baseboard_fab2_lib.baseboard_fab2(sch_1):page233_i224" )
			)
			( gate "EU4G1"
				( objectStatus "@baseboard_fab2_lib.baseboard_fab2(sch_1):page233_i225" )
			)
			( gate "C6U5"
				( objectStatus "@baseboard_fab2_lib.baseboard_fab2(sch_1):page233_i242" )
			)
			( gate "R4G12"
				( objectStatus "@baseboard_fab2_lib.baseboard_fab2(sch_1):page233_i247" )
			)
			( gate "C6U4"
				( objectStatus "@baseboard_fab2_lib.baseboard_fab2(sch_1):page233_i248" )
			)
			( gate "C4G2"
				( objectStatus "@baseboard_fab2_lib.baseboard_fab2(sch_1):page233_i253" )
			)
			( gate "C6U7"
				( objectStatus "@baseboard_fab2_lib.baseboard_fab2(sch_1):page233_i254" )
			)
			( gate "C6U8"
				( objectStatus "@baseboard_fab2_lib.baseboard_fab2(sch_1):page233_i255" )
			)
			( gate "C4F11"
				( objectStatus "@baseboard_fab2_lib.baseboard_fab2(sch_1):page233_i256" )
			)
			( gate "R4G10"
				( objectStatus "@baseboard_fab2_lib.baseboard_fab2(sch_1):page233_i266" )
			)
			( gate "C4G11"
				( objectStatus "@baseboard_fab2_lib.baseboard_fab2(sch_1):page233_i267" )
			)
			( gate "R4B4"
				( objectStatus "@baseboard_fab2_lib.baseboard_fab2(sch_1):page234_i227" )
			)
			( gate "R4G7"
				( objectStatus "@baseboard_fab2_lib.baseboard_fab2(sch_1):page233_i270" )
			)
			( gate "R4G8"
				( objectStatus "@baseboard_fab2_lib.baseboard_fab2(sch_1):page233_i271" )
			)
			( gate "R4G13"
				( objectStatus "@baseboard_fab2_lib.baseboard_fab2(sch_1):page233_i272" )
			)
			( gate "C4G6"
				( objectStatus "@baseboard_fab2_lib.baseboard_fab2(sch_1):page233_i273" )
			)
			( gate "C4G10"
				( objectStatus "@baseboard_fab2_lib.baseboard_fab2(sch_1):page233_i274" )
			)
			( gate "R4G4"
				( objectStatus "@baseboard_fab2_lib.baseboard_fab2(sch_1):page233_i275" )
			)
			( gate "L4G1"
				( objectStatus "@baseboard_fab2_lib.baseboard_fab2(sch_1):page233_i277" )
			)
			( gate "R4B14"
				( objectStatus "@baseboard_fab2_lib.baseboard_fab2(sch_1):page234_i29" )
			)
			( gate "C3B2"
				( objectStatus "@baseboard_fab2_lib.baseboard_fab2(sch_1):page234_i84" )
			)
			( gate "C3A8"
				( objectStatus "@baseboard_fab2_lib.baseboard_fab2(sch_1):page234_i86" )
			)
			( gate "C7L3"
				( objectStatus "@baseboard_fab2_lib.baseboard_fab2(sch_1):page234_i87" )
			)
			( gate "C7L2"
				( objectStatus "@baseboard_fab2_lib.baseboard_fab2(sch_1):page234_i88" )
			)
			( gate "C7L7"
				( objectStatus "@baseboard_fab2_lib.baseboard_fab2(sch_1):page234_i89" )
			)
			( gate "C7L6"
				( objectStatus "@baseboard_fab2_lib.baseboard_fab2(sch_1):page234_i90" )
			)
			( gate "C7M4"
				( objectStatus "@baseboard_fab2_lib.baseboard_fab2(sch_1):page234_i91" )
			)
			( gate "C7M3"
				( objectStatus "@baseboard_fab2_lib.baseboard_fab2(sch_1):page234_i92" )
			)
			( gate "C3A4"
				( objectStatus "@baseboard_fab2_lib.baseboard_fab2(sch_1):page234_i93" )
			)
			( gate "C3B1"
				( objectStatus "@baseboard_fab2_lib.baseboard_fab2(sch_1):page234_i94" )
			)
			( gate "C3A7"
				( objectStatus "@baseboard_fab2_lib.baseboard_fab2(sch_1):page234_i95" )
			)
			( gate "C3A3"
				( objectStatus "@baseboard_fab2_lib.baseboard_fab2(sch_1):page234_i97" )
			)
			( gate "C4B5"
				( objectStatus "@baseboard_fab2_lib.baseboard_fab2(sch_1):page234_i129" )
			)
			( gate "C22W6"
				( objectStatus "@baseboard_fab2_lib.baseboard_fab2(sch_1):page233_i278" )
			)
			( gate "C4B8"
				( objectStatus "@baseboard_fab2_lib.baseboard_fab2(sch_1):page234_i139" )
			)
			( gate "R4B10"
				( objectStatus "@baseboard_fab2_lib.baseboard_fab2(sch_1):page234_i143" )
			)
			( gate "C6L12"
				( objectStatus "@baseboard_fab2_lib.baseboard_fab2(sch_1):page234_i144" )
			)
			( gate "C4B6"
				( objectStatus "@baseboard_fab2_lib.baseboard_fab2(sch_1):page234_i146" )
			)
			( gate "C6L11"
				( objectStatus "@baseboard_fab2_lib.baseboard_fab2(sch_1):page234_i152" )
			)
			( gate "FB4A1"
				( objectStatus "@baseboard_fab2_lib.baseboard_fab2(sch_1):page234_i154" )
			)
			( gate "R4G24"
				( objectStatus "@baseboard_fab2_lib.baseboard_fab2(sch_1):page233_i282" )
			)
			( gate "R4A7"
				( objectStatus "@baseboard_fab2_lib.baseboard_fab2(sch_1):page234_i162" )
			)
			( gate "C4A16"
				( objectStatus "@baseboard_fab2_lib.baseboard_fab2(sch_1):page234_i163" )
			)
			( gate "L4A1"
				( objectStatus "@baseboard_fab2_lib.baseboard_fab2(sch_1):page234_i164" )
			)
			( gate "C3B3"
				( objectStatus "@baseboard_fab2_lib.baseboard_fab2(sch_1):page234_i167" )
			)
			( gate "C4B3"
				( objectStatus "@baseboard_fab2_lib.baseboard_fab2(sch_1):page234_i177" )
			)
			( gate "C4B2"
				( objectStatus "@baseboard_fab2_lib.baseboard_fab2(sch_1):page234_i180" )
			)
			( gate "C4B15"
				( objectStatus "@baseboard_fab2_lib.baseboard_fab2(sch_1):page234_i182" )
			)
			( gate "R4B2"
				( objectStatus "@baseboard_fab2_lib.baseboard_fab2(sch_1):page234_i183" )
			)
			( gate "EU4A3"
				( objectStatus "@baseboard_fab2_lib.baseboard_fab2(sch_1):page234_i184" )
			)
			( gate "C4A20"
				( objectStatus "@baseboard_fab2_lib.baseboard_fab2(sch_1):page234_i199" )
			)
			( gate "R4B7"
				( objectStatus "@baseboard_fab2_lib.baseboard_fab2(sch_1):page234_i201" )
			)
			( gate "C6L10"
				( objectStatus "@baseboard_fab2_lib.baseboard_fab2(sch_1):page234_i202" )
			)
			( gate "C6M3"
				( objectStatus "@baseboard_fab2_lib.baseboard_fab2(sch_1):page234_i203" )
			)
			( gate "C6M5"
				( objectStatus "@baseboard_fab2_lib.baseboard_fab2(sch_1):page234_i204" )
			)
			( gate "C4A19"
				( objectStatus "@baseboard_fab2_lib.baseboard_fab2(sch_1):page234_i205" )
			)
			( gate "C6L8"
				( objectStatus "@baseboard_fab2_lib.baseboard_fab2(sch_1):page234_i210" )
			)
			( gate "C4B9"
				( objectStatus "@baseboard_fab2_lib.baseboard_fab2(sch_1):page234_i211" )
			)
			( gate "C4B4"
				( objectStatus "@baseboard_fab2_lib.baseboard_fab2(sch_1):page234_i212" )
			)
			( gate "R4B8"
				( objectStatus "@baseboard_fab2_lib.baseboard_fab2(sch_1):page234_i213" )
			)
			( gate "R4B3"
				( objectStatus "@baseboard_fab2_lib.baseboard_fab2(sch_1):page234_i214" )
			)
			( gate "R4B5"
				( objectStatus "@baseboard_fab2_lib.baseboard_fab2(sch_1):page234_i215" )
			)
			( gate "C4B7"
				( objectStatus "@baseboard_fab2_lib.baseboard_fab2(sch_1):page234_i218" )
			)
			( gate "R4B9"
				( objectStatus "@baseboard_fab2_lib.baseboard_fab2(sch_1):page234_i219" )
			)
			( gate "R4B1"
				( objectStatus "@baseboard_fab2_lib.baseboard_fab2(sch_1):page234_i220" )
			)
			( gate "C8A7"
				( objectStatus "@baseboard_fab2_lib.baseboard_fab2(sch_1):page235_i143" )
			)
			( gate "C8A8"
				( objectStatus "@baseboard_fab2_lib.baseboard_fab2(sch_1):page235_i145" )
			)
			( gate "R2L16"
				( objectStatus "@baseboard_fab2_lib.baseboard_fab2(sch_1):page235_i147" )
			)
			( gate "R2L24"
				( objectStatus "@baseboard_fab2_lib.baseboard_fab2(sch_1):page235_i148" )
			)
			( gate "R8A6"
				( objectStatus "@baseboard_fab2_lib.baseboard_fab2(sch_1):page235_i149" )
			)
			( gate "C2L8"
				( objectStatus "@baseboard_fab2_lib.baseboard_fab2(sch_1):page235_i151" )
			)
			( gate "C2L2"
				( objectStatus "@baseboard_fab2_lib.baseboard_fab2(sch_1):page235_i153" )
			)
			( gate "R2L8"
				( objectStatus "@baseboard_fab2_lib.baseboard_fab2(sch_1):page235_i154" )
			)
			( gate "R2L14"
				( objectStatus "@baseboard_fab2_lib.baseboard_fab2(sch_1):page235_i159" )
			)
			( gate "R8A4"
				( objectStatus "@baseboard_fab2_lib.baseboard_fab2(sch_1):page235_i165" )
			)
			( gate "R2L10"
				( objectStatus "@baseboard_fab2_lib.baseboard_fab2(sch_1):page235_i166" )
			)
			( gate "C2L11"
				( objectStatus "@baseboard_fab2_lib.baseboard_fab2(sch_1):page235_i169" )
			)
			( gate "C8A2"
				( objectStatus "@baseboard_fab2_lib.baseboard_fab2(sch_1):page235_i209" )
			)
			( gate "R8A1"
				( objectStatus "@baseboard_fab2_lib.baseboard_fab2(sch_1):page235_i210" )
			)
			( gate "R8A5"
				( objectStatus "@baseboard_fab2_lib.baseboard_fab2(sch_1):page235_i216" )
			)
			( gate "R8A2"
				( objectStatus "@baseboard_fab2_lib.baseboard_fab2(sch_1):page235_i217" )
			)
			( gate "C8A9"
				( objectStatus "@baseboard_fab2_lib.baseboard_fab2(sch_1):page235_i218" )
			)
			( gate "R2L17"
				( objectStatus "@baseboard_fab2_lib.baseboard_fab2(sch_1):page235_i221" )
			)
			( gate "R8A7"
				( objectStatus "@baseboard_fab2_lib.baseboard_fab2(sch_1):page235_i222" )
			)
			( gate "EU8A1"
				( objectStatus "@baseboard_fab2_lib.baseboard_fab2(sch_1):page235_i229" )
			)
			( gate "R2P8"
				( objectStatus "@baseboard_fab2_lib.baseboard_fab2(sch_1):page170_i75" )
			)
			( gate "C7A30"
				( objectStatus "@baseboard_fab2_lib.baseboard_fab2(sch_1):page236_i9" )
			)
			( gate "C7A8"
				( objectStatus "@baseboard_fab2_lib.baseboard_fab2(sch_1):page236_i16" )
			)
			( gate "C4D6"
				( objectStatus "@baseboard_fab2_lib.baseboard_fab2(sch_1):page203_i133" )
			)
			( gate "C7A6"
				( objectStatus "@baseboard_fab2_lib.baseboard_fab2(sch_1):page236_i19" )
			)
			( gate "C7A39"
				( objectStatus "@baseboard_fab2_lib.baseboard_fab2(sch_1):page236_i20" )
			)
			( gate "C7A43"
				( objectStatus "@baseboard_fab2_lib.baseboard_fab2(sch_1):page236_i21" )
			)
			( gate "C7A7"
				( objectStatus "@baseboard_fab2_lib.baseboard_fab2(sch_1):page236_i22" )
			)
			( gate "C3L12"
				( objectStatus "@baseboard_fab2_lib.baseboard_fab2(sch_1):page236_i23" )
			)
			( gate "C3L11"
				( objectStatus "@baseboard_fab2_lib.baseboard_fab2(sch_1):page236_i24" )
			)
			( gate "C3L8"
				( objectStatus "@baseboard_fab2_lib.baseboard_fab2(sch_1):page236_i26" )
			)
			( gate "C3L9"
				( objectStatus "@baseboard_fab2_lib.baseboard_fab2(sch_1):page236_i29" )
			)
			( gate "C3L7"
				( objectStatus "@baseboard_fab2_lib.baseboard_fab2(sch_1):page236_i31" )
			)
			( gate "C3L10"
				( objectStatus "@baseboard_fab2_lib.baseboard_fab2(sch_1):page236_i32" )
			)
			( gate "C7A9"
				( objectStatus "@baseboard_fab2_lib.baseboard_fab2(sch_1):page236_i33" )
			)
			( gate "C7A44"
				( objectStatus "@baseboard_fab2_lib.baseboard_fab2(sch_1):page236_i34" )
			)
			( gate "C7A40"
				( objectStatus "@baseboard_fab2_lib.baseboard_fab2(sch_1):page236_i35" )
			)
			( gate "C7A10"
				( objectStatus "@baseboard_fab2_lib.baseboard_fab2(sch_1):page236_i36" )
			)
			( gate "C4C4"
				( objectStatus "@baseboard_fab2_lib.baseboard_fab2(sch_1):page205_i83" )
			)
			( gate "C7A41"
				( objectStatus "@baseboard_fab2_lib.baseboard_fab2(sch_1):page236_i39" )
			)
			( gate "L4C1"
				( objectStatus "@baseboard_fab2_lib.baseboard_fab2(sch_1):page204_i105" )
			)
			( gate "C7A42"
				( objectStatus "@baseboard_fab2_lib.baseboard_fab2(sch_1):page236_i46" )
			)
			( gate "R8B14"
				( objectStatus "@baseboard_fab2_lib.baseboard_fab2(sch_1):page236_i56" )
			)
			( gate "R8B15"
				( objectStatus "@baseboard_fab2_lib.baseboard_fab2(sch_1):page236_i57" )
			)
			( gate "R8B12"
				( objectStatus "@baseboard_fab2_lib.baseboard_fab2(sch_1):page236_i59" )
			)
			( gate "C22W32"
				( objectStatus "@baseboard_fab2_lib.baseboard_fab2(sch_1):page212_i126" )
			)
			( gate "C22W33"
				( objectStatus "@baseboard_fab2_lib.baseboard_fab2(sch_1):page212_i124" )
			)
			( gate "C3L18"
				( objectStatus "@baseboard_fab2_lib.baseboard_fab2(sch_1):page236_i71" )
			)
			( gate "C3L20"
				( objectStatus "@baseboard_fab2_lib.baseboard_fab2(sch_1):page236_i73" )
			)
			( gate "C3L21"
				( objectStatus "@baseboard_fab2_lib.baseboard_fab2(sch_1):page236_i74" )
			)
			( gate "C7A27"
				( objectStatus "@baseboard_fab2_lib.baseboard_fab2(sch_1):page236_i75" )
			)
			( gate "C3L19"
				( objectStatus "@baseboard_fab2_lib.baseboard_fab2(sch_1):page236_i76" )
			)
			( gate "C2L46"
				( objectStatus "@baseboard_fab2_lib.baseboard_fab2(sch_1):page236_i77" )
			)
			( gate "C8A15"
				( objectStatus "@baseboard_fab2_lib.baseboard_fab2(sch_1):page236_i78" )
			)
			( gate "C2L25"
				( objectStatus "@baseboard_fab2_lib.baseboard_fab2(sch_1):page236_i79" )
			)
			( gate "R7A13"
				( objectStatus "@baseboard_fab2_lib.baseboard_fab2(sch_1):page236_i90" )
			)
			( gate "R7A18"
				( objectStatus "@baseboard_fab2_lib.baseboard_fab2(sch_1):page236_i92" )
			)
			( gate "R7A19"
				( objectStatus "@baseboard_fab2_lib.baseboard_fab2(sch_1):page236_i93" )
			)
			( gate "R7A14"
				( objectStatus "@baseboard_fab2_lib.baseboard_fab2(sch_1):page236_i94" )
			)
			( gate "EU7A3"
				( objectStatus "@baseboard_fab2_lib.baseboard_fab2(sch_1):page236_i116" )
			)
			( gate "EU7A2"
				( objectStatus "@baseboard_fab2_lib.baseboard_fab2(sch_1):page236_i117" )
			)
			( gate "R3L15"
				( objectStatus "@baseboard_fab2_lib.baseboard_fab2(sch_1):page236_i118" )
			)
			( gate "R3L14"
				( objectStatus "@baseboard_fab2_lib.baseboard_fab2(sch_1):page236_i120" )
			)
			( gate "R8A10"
				( objectStatus "@baseboard_fab2_lib.baseboard_fab2(sch_1):page237_i3" )
			)
			( gate "C8A11"
				( objectStatus "@baseboard_fab2_lib.baseboard_fab2(sch_1):page237_i5" )
			)
			( gate "C2L45"
				( objectStatus "@baseboard_fab2_lib.baseboard_fab2(sch_1):page237_i12" )
			)
			( gate "C8A14"
				( objectStatus "@baseboard_fab2_lib.baseboard_fab2(sch_1):page237_i13" )
			)
			( gate "R8A12"
				( objectStatus "@baseboard_fab2_lib.baseboard_fab2(sch_1):page237_i15" )
			)
			( gate "C8A6"
				( objectStatus "@baseboard_fab2_lib.baseboard_fab2(sch_1):page237_i29" )
			)
			( gate "C8A4"
				( objectStatus "@baseboard_fab2_lib.baseboard_fab2(sch_1):page237_i31" )
			)
			( gate "C8A10"
				( objectStatus "@baseboard_fab2_lib.baseboard_fab2(sch_1):page237_i55" )
			)
			( gate "C8A12"
				( objectStatus "@baseboard_fab2_lib.baseboard_fab2(sch_1):page237_i77" )
			)
			( gate "C2L32"
				( objectStatus "@baseboard_fab2_lib.baseboard_fab2(sch_1):page237_i79" )
			)
			( gate "R2L19"
				( objectStatus "@baseboard_fab2_lib.baseboard_fab2(sch_1):page237_i80" )
			)
			( gate "R2L20"
				( objectStatus "@baseboard_fab2_lib.baseboard_fab2(sch_1):page237_i81" )
			)
			( gate "EU8A2"
				( objectStatus "@baseboard_fab2_lib.baseboard_fab2(sch_1):page237_i86" )
			)
			( gate "R8A11"
				( objectStatus "@baseboard_fab2_lib.baseboard_fab2(sch_1):page237_i90" )
			)
			( gate "C9F9"
				( objectStatus "@baseboard_fab2_lib.baseboard_fab2(sch_1):page238_i5" )
			)
			( gate "C9F3"
				( objectStatus "@baseboard_fab2_lib.baseboard_fab2(sch_1):page238_i7" )
			)
			( gate "R9F8"
				( objectStatus "@baseboard_fab2_lib.baseboard_fab2(sch_1):page238_i14" )
			)
			( gate "C9F8"
				( objectStatus "@baseboard_fab2_lib.baseboard_fab2(sch_1):page238_i19" )
			)
			( gate "R9F13"
				( objectStatus "@baseboard_fab2_lib.baseboard_fab2(sch_1):page238_i21" )
			)
			( gate "C9E10"
				( objectStatus "@baseboard_fab2_lib.baseboard_fab2(sch_1):page238_i23" )
			)
			( gate "C9F4"
				( objectStatus "@baseboard_fab2_lib.baseboard_fab2(sch_1):page238_i30" )
			)
			( gate "C9E11"
				( objectStatus "@baseboard_fab2_lib.baseboard_fab2(sch_1):page238_i39" )
			)
			( gate "EU9F1"
				( objectStatus "@baseboard_fab2_lib.baseboard_fab2(sch_1):page238_i40" )
			)
			( gate "R9F11"
				( objectStatus "@baseboard_fab2_lib.baseboard_fab2(sch_1):page238_i41" )
			)
			( gate "C9F10"
				( objectStatus "@baseboard_fab2_lib.baseboard_fab2(sch_1):page239_i4" )
			)
			( gate "R9F12"
				( objectStatus "@baseboard_fab2_lib.baseboard_fab2(sch_1):page239_i6" )
			)
			( gate "C9F13"
				( objectStatus "@baseboard_fab2_lib.baseboard_fab2(sch_1):page239_i7" )
			)
			( gate "C1T15"
				( objectStatus "@baseboard_fab2_lib.baseboard_fab2(sch_1):page239_i12" )
			)
			( gate "R9F6"
				( objectStatus "@baseboard_fab2_lib.baseboard_fab2(sch_1):page238_i45" )
			)
			( gate "C1T7"
				( objectStatus "@baseboard_fab2_lib.baseboard_fab2(sch_1):page239_i22" )
			)
			( gate "C9F6"
				( objectStatus "@baseboard_fab2_lib.baseboard_fab2(sch_1):page239_i30" )
			)
			( gate "EU9F2"
				( objectStatus "@baseboard_fab2_lib.baseboard_fab2(sch_1):page239_i70" )
			)
			( gate "C9F5"
				( objectStatus "@baseboard_fab2_lib.baseboard_fab2(sch_1):page239_i71" )
			)
			( gate "R1T9"
				( objectStatus "@baseboard_fab2_lib.baseboard_fab2(sch_1):page239_i72" )
			)
			( gate "R7B14"
				( objectStatus "@baseboard_fab2_lib.baseboard_fab2(sch_1):page232_i315" )
			)
			( gate "C9B9"
				( objectStatus "@baseboard_fab2_lib.baseboard_fab2(sch_1):page186_i357" )
			)
			( gate "R8F1"
				( objectStatus "@baseboard_fab2_lib.baseboard_fab2(sch_1):page240_i111" )
			)
			( gate "C8E17"
				( objectStatus "@baseboard_fab2_lib.baseboard_fab2(sch_1):page240_i113" )
			)
			( gate "C8F2"
				( objectStatus "@baseboard_fab2_lib.baseboard_fab2(sch_1):page240_i116" )
			)
			( gate "R8F5"
				( objectStatus "@baseboard_fab2_lib.baseboard_fab2(sch_1):page240_i117" )
			)
			( gate "EU8F1"
				( objectStatus "@baseboard_fab2_lib.baseboard_fab2(sch_1):page240_i125" )
			)
			( gate "R8E35"
				( objectStatus "@baseboard_fab2_lib.baseboard_fab2(sch_1):page240_i127" )
			)
			( gate "C8E12"
				( objectStatus "@baseboard_fab2_lib.baseboard_fab2(sch_1):page240_i129" )
			)
			( gate "U1W3"
				( objectStatus "@baseboard_fab2_lib.baseboard_fab2(sch_1):page176_i162" )
			)
			( gate "C22W13"
				( objectStatus "@baseboard_fab2_lib.baseboard_fab2(sch_1):page214_i149" )
			)
			( gate "C4E14"
				( objectStatus "@baseboard_fab2_lib.baseboard_fab2(sch_1):page214_i148" )
			)
			( gate "C8E10"
				( objectStatus "@baseboard_fab2_lib.baseboard_fab2(sch_1):page240_i137" )
			)
			( gate "C8E14"
				( objectStatus "@baseboard_fab2_lib.baseboard_fab2(sch_1):page240_i139" )
			)
			( gate "R8E38"
				( objectStatus "@baseboard_fab2_lib.baseboard_fab2(sch_1):page240_i140" )
			)
			( gate "R8E34"
				( objectStatus "@baseboard_fab2_lib.baseboard_fab2(sch_1):page240_i142" )
			)
			( gate "R8E31"
				( objectStatus "@baseboard_fab2_lib.baseboard_fab2(sch_1):page240_i143" )
			)
			( gate "R8E25"
				( objectStatus "@baseboard_fab2_lib.baseboard_fab2(sch_1):page240_i144" )
			)
			( gate "R8F11"
				( objectStatus "@baseboard_fab2_lib.baseboard_fab2(sch_1):page240_i146" )
			)
			( gate "R8F3"
				( objectStatus "@baseboard_fab2_lib.baseboard_fab2(sch_1):page240_i148" )
			)
			( gate "R2T4"
				( objectStatus "@baseboard_fab2_lib.baseboard_fab2(sch_1):page240_i152" )
			)
			( gate "C2T7"
				( objectStatus "@baseboard_fab2_lib.baseboard_fab2(sch_1):page240_i158" )
			)
			( gate "C2T6"
				( objectStatus "@baseboard_fab2_lib.baseboard_fab2(sch_1):page240_i160" )
			)
			( gate "C8F3"
				( objectStatus "@baseboard_fab2_lib.baseboard_fab2(sch_1):page240_i163" )
			)
			( gate "EU8E1"
				( objectStatus "@baseboard_fab2_lib.baseboard_fab2(sch_1):page240_i170" )
			)
			( gate "R8F10"
				( objectStatus "@baseboard_fab2_lib.baseboard_fab2(sch_1):page240_i171" )
			)
			( gate "R1L19"
				( objectStatus "@baseboard_fab2_lib.baseboard_fab2(sch_1):page175_i99" )
			)
			( gate "C2T9"
				( objectStatus "@baseboard_fab2_lib.baseboard_fab2(sch_1):page240_i174" )
			)
			( gate "R8F2"
				( objectStatus "@baseboard_fab2_lib.baseboard_fab2(sch_1):page240_i176" )
			)
			( gate "R8E40"
				( objectStatus "@baseboard_fab2_lib.baseboard_fab2(sch_1):page240_i177" )
			)
			( gate "C1A2"
				( objectStatus "@baseboard_fab2_lib.baseboard_fab2(sch_1):page227_i148" )
			)
			( gate "C2R11"
				( objectStatus "@baseboard_fab2_lib.baseboard_fab2(sch_1):page240_i191" )
			)
			( gate "R8E18"
				( objectStatus "@baseboard_fab2_lib.baseboard_fab2(sch_1):page241_i9" )
			)
			( gate "R7E12"
				( objectStatus "@baseboard_fab2_lib.baseboard_fab2(sch_1):page241_i11" )
			)
			( gate "C8E6"
				( objectStatus "@baseboard_fab2_lib.baseboard_fab2(sch_1):page241_i12" )
			)
			( gate "C7E10"
				( objectStatus "@baseboard_fab2_lib.baseboard_fab2(sch_1):page241_i14" )
			)
			( gate "R7E14"
				( objectStatus "@baseboard_fab2_lib.baseboard_fab2(sch_1):page241_i18" )
			)
			( gate "C7E14"
				( objectStatus "@baseboard_fab2_lib.baseboard_fab2(sch_1):page241_i30" )
			)
			( gate "R7E17"
				( objectStatus "@baseboard_fab2_lib.baseboard_fab2(sch_1):page241_i37" )
			)
			( gate "C7E11"
				( objectStatus "@baseboard_fab2_lib.baseboard_fab2(sch_1):page241_i39" )
			)
			( gate "C8E13"
				( objectStatus "@baseboard_fab2_lib.baseboard_fab2(sch_1):page241_i41" )
			)
			( gate "C22W11"
				( objectStatus "@baseboard_fab2_lib.baseboard_fab2(sch_1):page240_i182" )
			)
			( gate "R7F1"
				( objectStatus "@baseboard_fab2_lib.baseboard_fab2(sch_1):page241_i50" )
			)
			( gate "R7E16"
				( objectStatus "@baseboard_fab2_lib.baseboard_fab2(sch_1):page241_i51" )
			)
			( gate "C8E16"
				( objectStatus "@baseboard_fab2_lib.baseboard_fab2(sch_1):page241_i53" )
			)
			( gate "R8E39"
				( objectStatus "@baseboard_fab2_lib.baseboard_fab2(sch_1):page241_i54" )
			)
			( gate "C8F1"
				( objectStatus "@baseboard_fab2_lib.baseboard_fab2(sch_1):page241_i57" )
			)
			( gate "R7E13"
				( objectStatus "@baseboard_fab2_lib.baseboard_fab2(sch_1):page241_i58" )
			)
			( gate "C8E15"
				( objectStatus "@baseboard_fab2_lib.baseboard_fab2(sch_1):page241_i63" )
			)
			( gate "R8E37"
				( objectStatus "@baseboard_fab2_lib.baseboard_fab2(sch_1):page241_i78" )
			)
			( gate "FB7E1"
				( objectStatus "@baseboard_fab2_lib.baseboard_fab2(sch_1):page241_i82" )
			)
			( gate "EU7E2"
				( objectStatus "@baseboard_fab2_lib.baseboard_fab2(sch_1):page241_i83" )
			)
			( gate "R7E15"
				( objectStatus "@baseboard_fab2_lib.baseboard_fab2(sch_1):page241_i89" )
			)
			( gate "L8E1"
				( objectStatus "@baseboard_fab2_lib.baseboard_fab2(sch_1):page241_i90" )
			)
			( gate "R8E33"
				( objectStatus "@baseboard_fab2_lib.baseboard_fab2(sch_1):page241_i91" )
			)
			( gate "C5G106"
				( objectStatus "@baseboard_fab2_lib.baseboard_fab2(sch_1):page243_i88" )
			)
			( gate "C5G107"
				( objectStatus "@baseboard_fab2_lib.baseboard_fab2(sch_1):page243_i87" )
			)
			( gate "C5G108"
				( objectStatus "@baseboard_fab2_lib.baseboard_fab2(sch_1):page243_i86" )
			)
			( gate "C5G109"
				( objectStatus "@baseboard_fab2_lib.baseboard_fab2(sch_1):page243_i85" )
			)
			( gate "C5G110"
				( objectStatus "@baseboard_fab2_lib.baseboard_fab2(sch_1):page243_i84" )
			)
			( gate "C5G111"
				( objectStatus "@baseboard_fab2_lib.baseboard_fab2(sch_1):page243_i83" )
			)
			( gate "C5G112"
				( objectStatus "@baseboard_fab2_lib.baseboard_fab2(sch_1):page243_i82" )
			)
			( gate "C5G113"
				( objectStatus "@baseboard_fab2_lib.baseboard_fab2(sch_1):page243_i81" )
			)
			( gate "C5G117"
				( objectStatus "@baseboard_fab2_lib.baseboard_fab2(sch_1):page243_i92" )
			)
			( gate "C5G114"
				( objectStatus "@baseboard_fab2_lib.baseboard_fab2(sch_1):page243_i80" )
			)
			( gate "C5G97"
				( objectStatus "@baseboard_fab2_lib.baseboard_fab2(sch_1):page243_i79" )
			)
			( gate "C5G98"
				( objectStatus "@baseboard_fab2_lib.baseboard_fab2(sch_1):page243_i78" )
			)
			( gate "C5G99"
				( objectStatus "@baseboard_fab2_lib.baseboard_fab2(sch_1):page243_i77" )
			)
			( gate "C5G100"
				( objectStatus "@baseboard_fab2_lib.baseboard_fab2(sch_1):page243_i76" )
			)
			( gate "C5G101"
				( objectStatus "@baseboard_fab2_lib.baseboard_fab2(sch_1):page243_i75" )
			)
			( gate "C5G102"
				( objectStatus "@baseboard_fab2_lib.baseboard_fab2(sch_1):page243_i74" )
			)
			( gate "C5G105"
				( objectStatus "@baseboard_fab2_lib.baseboard_fab2(sch_1):page243_i73" )
			)
			( gate "C5G104"
				( objectStatus "@baseboard_fab2_lib.baseboard_fab2(sch_1):page243_i72" )
			)
			( gate "C5G103"
				( objectStatus "@baseboard_fab2_lib.baseboard_fab2(sch_1):page243_i71" )
			)
			( gate "C5G88"
				( objectStatus "@baseboard_fab2_lib.baseboard_fab2(sch_1):page243_i70" )
			)
			( gate "C5G89"
				( objectStatus "@baseboard_fab2_lib.baseboard_fab2(sch_1):page243_i69" )
			)
			( gate "C5G90"
				( objectStatus "@baseboard_fab2_lib.baseboard_fab2(sch_1):page243_i68" )
			)
			( gate "C5G91"
				( objectStatus "@baseboard_fab2_lib.baseboard_fab2(sch_1):page243_i67" )
			)
			( gate "C5G92"
				( objectStatus "@baseboard_fab2_lib.baseboard_fab2(sch_1):page243_i66" )
			)
			( gate "C5G118"
				( objectStatus "@baseboard_fab2_lib.baseboard_fab2(sch_1):page243_i91" )
			)
			( gate "C5G93"
				( objectStatus "@baseboard_fab2_lib.baseboard_fab2(sch_1):page243_i65" )
			)
			( gate "C5G94"
				( objectStatus "@baseboard_fab2_lib.baseboard_fab2(sch_1):page243_i64" )
			)
			( gate "C5G95"
				( objectStatus "@baseboard_fab2_lib.baseboard_fab2(sch_1):page243_i63" )
			)
			( gate "C5G116"
				( objectStatus "@baseboard_fab2_lib.baseboard_fab2(sch_1):page243_i90" )
			)
			( gate "C5G96"
				( objectStatus "@baseboard_fab2_lib.baseboard_fab2(sch_1):page243_i62" )
			)
			( gate "C5G80"
				( objectStatus "@baseboard_fab2_lib.baseboard_fab2(sch_1):page243_i61" )
			)
			( gate "C5G81"
				( objectStatus "@baseboard_fab2_lib.baseboard_fab2(sch_1):page243_i60" )
			)
			( gate "C5G82"
				( objectStatus "@baseboard_fab2_lib.baseboard_fab2(sch_1):page243_i59" )
			)
			( gate "C5G83"
				( objectStatus "@baseboard_fab2_lib.baseboard_fab2(sch_1):page243_i58" )
			)
			( gate "C5G84"
				( objectStatus "@baseboard_fab2_lib.baseboard_fab2(sch_1):page243_i57" )
			)
			( gate "C5G85"
				( objectStatus "@baseboard_fab2_lib.baseboard_fab2(sch_1):page243_i56" )
			)
			( gate "C5G86"
				( objectStatus "@baseboard_fab2_lib.baseboard_fab2(sch_1):page243_i55" )
			)
			( gate "C5G87"
				( objectStatus "@baseboard_fab2_lib.baseboard_fab2(sch_1):page243_i54" )
			)
			( gate "C5G79"
				( objectStatus "@baseboard_fab2_lib.baseboard_fab2(sch_1):page243_i53" )
			)
			( gate "CT47"
				( objectStatus "@baseboard_fab2_lib.baseboard_fab2(sch_1):page219_i138" )
			)
			( gate "CT41"
				( objectStatus "@baseboard_fab2_lib.baseboard_fab2(sch_1):page203_i119" )
			)
			( gate "CT38"
				( objectStatus "@baseboard_fab2_lib.baseboard_fab2(sch_1):page203_i118" )
			)
			( gate "C5G41"
				( objectStatus "@baseboard_fab2_lib.baseboard_fab2(sch_1):page242_i53" )
			)
			( gate "C5G42"
				( objectStatus "@baseboard_fab2_lib.baseboard_fab2(sch_1):page242_i54" )
			)
			( gate "C5G44"
				( objectStatus "@baseboard_fab2_lib.baseboard_fab2(sch_1):page242_i55" )
			)
			( gate "C5G43"
				( objectStatus "@baseboard_fab2_lib.baseboard_fab2(sch_1):page242_i56" )
			)
			( gate "C5G48"
				( objectStatus "@baseboard_fab2_lib.baseboard_fab2(sch_1):page242_i57" )
			)
			( gate "C5G47"
				( objectStatus "@baseboard_fab2_lib.baseboard_fab2(sch_1):page242_i58" )
			)
			( gate "C5G46"
				( objectStatus "@baseboard_fab2_lib.baseboard_fab2(sch_1):page242_i59" )
			)
			( gate "C5G45"
				( objectStatus "@baseboard_fab2_lib.baseboard_fab2(sch_1):page242_i60" )
			)
			( gate "C5G49"
				( objectStatus "@baseboard_fab2_lib.baseboard_fab2(sch_1):page242_i61" )
			)
			( gate "C5G54"
				( objectStatus "@baseboard_fab2_lib.baseboard_fab2(sch_1):page242_i62" )
			)
			( gate "C5G58"
				( objectStatus "@baseboard_fab2_lib.baseboard_fab2(sch_1):page242_i63" )
			)
			( gate "C5G57"
				( objectStatus "@baseboard_fab2_lib.baseboard_fab2(sch_1):page242_i64" )
			)
			( gate "C5G56"
				( objectStatus "@baseboard_fab2_lib.baseboard_fab2(sch_1):page242_i65" )
			)
			( gate "C5G55"
				( objectStatus "@baseboard_fab2_lib.baseboard_fab2(sch_1):page242_i66" )
			)
			( gate "C5G53"
				( objectStatus "@baseboard_fab2_lib.baseboard_fab2(sch_1):page242_i67" )
			)
			( gate "C5G52"
				( objectStatus "@baseboard_fab2_lib.baseboard_fab2(sch_1):page242_i68" )
			)
			( gate "C5G51"
				( objectStatus "@baseboard_fab2_lib.baseboard_fab2(sch_1):page242_i69" )
			)
			( gate "C5G50"
				( objectStatus "@baseboard_fab2_lib.baseboard_fab2(sch_1):page242_i70" )
			)
			( gate "C5G67"
				( objectStatus "@baseboard_fab2_lib.baseboard_fab2(sch_1):page242_i71" )
			)
			( gate "C5G66"
				( objectStatus "@baseboard_fab2_lib.baseboard_fab2(sch_1):page242_i72" )
			)
			( gate "C5G65"
				( objectStatus "@baseboard_fab2_lib.baseboard_fab2(sch_1):page242_i73" )
			)
			( gate "C5G64"
				( objectStatus "@baseboard_fab2_lib.baseboard_fab2(sch_1):page242_i74" )
			)
			( gate "C5G63"
				( objectStatus "@baseboard_fab2_lib.baseboard_fab2(sch_1):page242_i75" )
			)
			( gate "C5G62"
				( objectStatus "@baseboard_fab2_lib.baseboard_fab2(sch_1):page242_i76" )
			)
			( gate "C5G61"
				( objectStatus "@baseboard_fab2_lib.baseboard_fab2(sch_1):page242_i77" )
			)
			( gate "C5G60"
				( objectStatus "@baseboard_fab2_lib.baseboard_fab2(sch_1):page242_i78" )
			)
			( gate "C5G59"
				( objectStatus "@baseboard_fab2_lib.baseboard_fab2(sch_1):page242_i79" )
			)
			( gate "C5G76"
				( objectStatus "@baseboard_fab2_lib.baseboard_fab2(sch_1):page242_i80" )
			)
			( gate "C5G75"
				( objectStatus "@baseboard_fab2_lib.baseboard_fab2(sch_1):page242_i81" )
			)
			( gate "C5G74"
				( objectStatus "@baseboard_fab2_lib.baseboard_fab2(sch_1):page242_i82" )
			)
			( gate "C5G73"
				( objectStatus "@baseboard_fab2_lib.baseboard_fab2(sch_1):page242_i83" )
			)
			( gate "C5G72"
				( objectStatus "@baseboard_fab2_lib.baseboard_fab2(sch_1):page242_i84" )
			)
			( gate "C5G71"
				( objectStatus "@baseboard_fab2_lib.baseboard_fab2(sch_1):page242_i85" )
			)
			( gate "C5G70"
				( objectStatus "@baseboard_fab2_lib.baseboard_fab2(sch_1):page242_i86" )
			)
			( gate "C5G69"
				( objectStatus "@baseboard_fab2_lib.baseboard_fab2(sch_1):page242_i87" )
			)
			( gate "C5G68"
				( objectStatus "@baseboard_fab2_lib.baseboard_fab2(sch_1):page242_i88" )
			)
			( gate "RT17"
				( objectStatus "@baseboard_fab2_lib.baseboard_fab2(sch_1):page207_i100" )
			)
			( gate "CT1"
				( objectStatus "@baseboard_fab2_lib.baseboard_fab2(sch_1):page202_i70" )
			)
			( gate "RT24"
				( objectStatus "@baseboard_fab2_lib.baseboard_fab2(sch_1):page204_i114" )
			)
			( gate "CT35"
				( objectStatus "@baseboard_fab2_lib.baseboard_fab2(sch_1):page204_i97" )
			)
			( gate "CT2"
				( objectStatus "@baseboard_fab2_lib.baseboard_fab2(sch_1):page202_i78" )
			)
			( gate "CT6"
				( objectStatus "@baseboard_fab2_lib.baseboard_fab2(sch_1):page202_i81" )
			)
			( gate "CT27"
				( objectStatus "@baseboard_fab2_lib.baseboard_fab2(sch_1):page207_i96" )
			)
			( gate "CT7"
				( objectStatus "@baseboard_fab2_lib.baseboard_fab2(sch_1):page227_i109" )
			)
			( gate "CT53"
				( objectStatus "@baseboard_fab2_lib.baseboard_fab2(sch_1):page216_i136" )
			)
			( gate "CT8"
				( objectStatus "@baseboard_fab2_lib.baseboard_fab2(sch_1):page227_i114" )
			)
			( gate "CT10"
				( objectStatus "@baseboard_fab2_lib.baseboard_fab2(sch_1):page227_i119" )
			)
			( gate "CT12"
				( objectStatus "@baseboard_fab2_lib.baseboard_fab2(sch_1):page227_i122" )
			)
			( gate "CT56"
				( objectStatus "@baseboard_fab2_lib.baseboard_fab2(sch_1):page210_i66" )
			)
			( gate "CT13"
				( objectStatus "@baseboard_fab2_lib.baseboard_fab2(sch_1):page209_i62" )
			)
			( gate "CT23"
				( objectStatus "@baseboard_fab2_lib.baseboard_fab2(sch_1):page207_i95" )
			)
			( gate "RT20"
				( objectStatus "@baseboard_fab2_lib.baseboard_fab2(sch_1):page224_i156" )
			)
			( gate "CT15"
				( objectStatus "@baseboard_fab2_lib.baseboard_fab2(sch_1):page209_i67" )
			)
			( gate "CT16"
				( objectStatus "@baseboard_fab2_lib.baseboard_fab2(sch_1):page208_i80" )
			)
			( gate "CTI7"
				( objectStatus "@baseboard_fab2_lib.baseboard_fab2(sch_1):page208_i82" )
			)
			( gate "CT21"
				( objectStatus "@baseboard_fab2_lib.baseboard_fab2(sch_1):page208_i87" )
			)
			( gate "CT19"
				( objectStatus "@baseboard_fab2_lib.baseboard_fab2(sch_1):page208_i90" )
			)
			( gate "RT48"
				( objectStatus "@baseboard_fab2_lib.baseboard_fab2(sch_1):page212_i144" )
			)
			( gate "CT24"
				( objectStatus "@baseboard_fab2_lib.baseboard_fab2(sch_1):page207_i71" )
			)
			( gate "CT22"
				( objectStatus "@baseboard_fab2_lib.baseboard_fab2(sch_1):page207_i74" )
			)
			( gate "RT34"
				( objectStatus "@baseboard_fab2_lib.baseboard_fab2(sch_1):page216_i151" )
			)
			( gate "CT62"
				( objectStatus "@baseboard_fab2_lib.baseboard_fab2(sch_1):page214_i143" )
			)
			( gate "CT30"
				( objectStatus "@baseboard_fab2_lib.baseboard_fab2(sch_1):page224_i117" )
			)
			( gate "CT65"
				( objectStatus "@baseboard_fab2_lib.baseboard_fab2(sch_1):page236_i149" )
			)
			( gate "CT28"
				( objectStatus "@baseboard_fab2_lib.baseboard_fab2(sch_1):page224_i122" )
			)
			( gate "CT31"
				( objectStatus "@baseboard_fab2_lib.baseboard_fab2(sch_1):page224_i124" )
			)
			( gate "CT68"
				( objectStatus "@baseboard_fab2_lib.baseboard_fab2(sch_1):page236_i150" )
			)
			( gate "CT32"
				( objectStatus "@baseboard_fab2_lib.baseboard_fab2(sch_1):page224_i130" )
			)
			( gate "CT36"
				( objectStatus "@baseboard_fab2_lib.baseboard_fab2(sch_1):page204_i85" )
			)
			( gate "RT11"
				( objectStatus "@baseboard_fab2_lib.baseboard_fab2(sch_1):page208_i108" )
			)
			( gate "CT34"
				( objectStatus "@baseboard_fab2_lib.baseboard_fab2(sch_1):page204_i88" )
			)
			( gate "C5G77"
				( objectStatus "@baseboard_fab2_lib.baseboard_fab2(sch_1):page242_i89" )
			)
			( gate "RT38"
				( objectStatus "@baseboard_fab2_lib.baseboard_fab2(sch_1):page210_i74" )
			)
			( gate "CT40"
				( objectStatus "@baseboard_fab2_lib.baseboard_fab2(sch_1):page203_i93" )
			)
			( gate "RT8"
				( objectStatus "@baseboard_fab2_lib.baseboard_fab2(sch_1):page227_i139" )
			)
			( gate "CT39"
				( objectStatus "@baseboard_fab2_lib.baseboard_fab2(sch_1):page203_i96" )
			)
			( gate "RT5"
				( objectStatus "@baseboard_fab2_lib.baseboard_fab2(sch_1):page227_i138" )
			)
			( gate "CT37"
				( objectStatus "@baseboard_fab2_lib.baseboard_fab2(sch_1):page203_i99" )
			)
			( gate "C5G22"
				( objectStatus "@baseboard_fab2_lib.baseboard_fab2(sch_1):page242_i90" )
			)
			( gate "RT22"
				( objectStatus "@baseboard_fab2_lib.baseboard_fab2(sch_1):page224_i157" )
			)
			( gate "RT10"
				( objectStatus "@baseboard_fab2_lib.baseboard_fab2(sch_1):page209_i90" )
			)
			( gate "CT59"
				( objectStatus "@baseboard_fab2_lib.baseboard_fab2(sch_1):page205_i76" )
			)
			( gate "CT42"
				( objectStatus "@baseboard_fab2_lib.baseboard_fab2(sch_1):page203_i108" )
			)
			( gate "CT46"
				( objectStatus "@baseboard_fab2_lib.baseboard_fab2(sch_1):page219_i113" )
			)
			( gate "RT21"
				( objectStatus "@baseboard_fab2_lib.baseboard_fab2(sch_1):page224_i145" )
			)
			( gate "CT45"
				( objectStatus "@baseboard_fab2_lib.baseboard_fab2(sch_1):page219_i116" )
			)
			( gate "RT19"
				( objectStatus "@baseboard_fab2_lib.baseboard_fab2(sch_1):page224_i144" )
			)
			( gate "CT48"
				( objectStatus "@baseboard_fab2_lib.baseboard_fab2(sch_1):page219_i119" )
			)
			( gate "CT9"
				( objectStatus "@baseboard_fab2_lib.baseboard_fab2(sch_1):page227_i134" )
			)
			( gate "CT43"
				( objectStatus "@baseboard_fab2_lib.baseboard_fab2(sch_1):page219_i124" )
			)
			( gate "CT11"
				( objectStatus "@baseboard_fab2_lib.baseboard_fab2(sch_1):page227_i135" )
			)
			( gate "CT51"
				( objectStatus "@baseboard_fab2_lib.baseboard_fab2(sch_1):page216_i108" )
			)
			( gate "C7G38"
				( objectStatus "@baseboard_fab2_lib.baseboard_fab2(sch_1):page216_i128" )
			)
			( gate "CT52"
				( objectStatus "@baseboard_fab2_lib.baseboard_fab2(sch_1):page216_i111" )
			)
			( gate "RT41"
				( objectStatus "@baseboard_fab2_lib.baseboard_fab2(sch_1):page214_i145" )
			)
			( gate "RT32"
				( objectStatus "@baseboard_fab2_lib.baseboard_fab2(sch_1):page219_i154" )
			)
			( gate "CT49"
				( objectStatus "@baseboard_fab2_lib.baseboard_fab2(sch_1):page216_i118" )
			)
			( gate "CT29"
				( objectStatus "@baseboard_fab2_lib.baseboard_fab2(sch_1):page224_i140" )
			)
			( gate "CT54"
				( objectStatus "@baseboard_fab2_lib.baseboard_fab2(sch_1):page216_i121" )
			)
			( gate "CT33"
				( objectStatus "@baseboard_fab2_lib.baseboard_fab2(sch_1):page224_i141" )
			)
			( gate "RT47"
				( objectStatus "@baseboard_fab2_lib.baseboard_fab2(sch_1):page212_i120" )
			)
			( gate "CT18"
				( objectStatus "@baseboard_fab2_lib.baseboard_fab2(sch_1):page208_i104" )
			)
			( gate "RT45"
				( objectStatus "@baseboard_fab2_lib.baseboard_fab2(sch_1):page236_i183" )
			)
			( gate "CT55"
				( objectStatus "@baseboard_fab2_lib.baseboard_fab2(sch_1):page210_i60" )
			)
			( gate "CT72"
				( objectStatus "@baseboard_fab2_lib.baseboard_fab2(sch_1):page212_i118" )
			)
			( gate "CT58"
				( objectStatus "@baseboard_fab2_lib.baseboard_fab2(sch_1):page205_i65" )
			)
			( gate "RT42"
				( objectStatus "@baseboard_fab2_lib.baseboard_fab2(sch_1):page214_i176" )
			)
			( gate "CT60"
				( objectStatus "@baseboard_fab2_lib.baseboard_fab2(sch_1):page205_i69" )
			)
			( gate "RT31"
				( objectStatus "@baseboard_fab2_lib.baseboard_fab2(sch_1):page219_i142" )
			)
			( gate "RT30"
				( objectStatus "@baseboard_fab2_lib.baseboard_fab2(sch_1):page219_i141" )
			)
			( gate "CT61"
				( objectStatus "@baseboard_fab2_lib.baseboard_fab2(sch_1):page214_i134" )
			)
			( gate "CT63"
				( objectStatus "@baseboard_fab2_lib.baseboard_fab2(sch_1):page214_i137" )
			)
			( gate "C5G78"
				( objectStatus "@baseboard_fab2_lib.baseboard_fab2(sch_1):page242_i91" )
			)
			( gate "CT67"
				( objectStatus "@baseboard_fab2_lib.baseboard_fab2(sch_1):page236_i124" )
			)
			( gate "CT66"
				( objectStatus "@baseboard_fab2_lib.baseboard_fab2(sch_1):page236_i127" )
			)
			( gate "RT33"
				( objectStatus "@baseboard_fab2_lib.baseboard_fab2(sch_1):page216_i139" )
			)
			( gate "RT7"
				( objectStatus "@baseboard_fab2_lib.baseboard_fab2(sch_1):page227_i150" )
			)
			( gate "CT69"
				( objectStatus "@baseboard_fab2_lib.baseboard_fab2(sch_1):page236_i134" )
			)
			( gate "CT64"
				( objectStatus "@baseboard_fab2_lib.baseboard_fab2(sch_1):page236_i136" )
			)
			( gate "C5G21"
				( objectStatus "@baseboard_fab2_lib.baseboard_fab2(sch_1):page242_i92" )
			)
			( gate "CT70"
				( objectStatus "@baseboard_fab2_lib.baseboard_fab2(sch_1):page212_i106" )
			)
			( gate "R9F65"
				( objectStatus "@baseboard_fab2_lib.baseboard_fab2(sch_1):page158_i148" )
			)
			( gate "CT71"
				( objectStatus "@baseboard_fab2_lib.baseboard_fab2(sch_1):page212_i109" )
			)
			( gate "CT50"
				( objectStatus "@baseboard_fab2_lib.baseboard_fab2(sch_1):page216_i135" )
			)
			( gate "C22W1"
				( objectStatus "@baseboard_fab2_lib.baseboard_fab2(sch_1):page225_i246" )
			)
			( gate "CT25"
				( objectStatus "@baseboard_fab2_lib.baseboard_fab2(sch_1):page207_i81" )
			)
			( gate "CT26"
				( objectStatus "@baseboard_fab2_lib.baseboard_fab2(sch_1):page207_i82" )
			)
			( gate "CT44"
				( objectStatus "@baseboard_fab2_lib.baseboard_fab2(sch_1):page219_i137" )
			)
			( gate "RT43"
				( objectStatus "@baseboard_fab2_lib.baseboard_fab2(sch_1):page236_i182" )
			)
			( gate "CT4"
				( objectStatus "@baseboard_fab2_lib.baseboard_fab2(sch_1):page202_i87" )
			)
			( gate "C831"
				( objectStatus "@baseboard_fab2_lib.baseboard_fab2(sch_1):page244_i2" )
			)
			( gate "C829"
				( objectStatus "@baseboard_fab2_lib.baseboard_fab2(sch_1):page244_i5" )
			)
			( gate "C833"
				( objectStatus "@baseboard_fab2_lib.baseboard_fab2(sch_1):page244_i8" )
			)
			( gate "C827"
				( objectStatus "@baseboard_fab2_lib.baseboard_fab2(sch_1):page244_i12" )
			)
			( gate "C841"
				( objectStatus "@baseboard_fab2_lib.baseboard_fab2(sch_1):page244_i17" )
			)
			( gate "C830"
				( objectStatus "@baseboard_fab2_lib.baseboard_fab2(sch_1):page244_i23" )
			)
			( gate "C826"
				( objectStatus "@baseboard_fab2_lib.baseboard_fab2(sch_1):page244_i24" )
			)
			( gate "C828"
				( objectStatus "@baseboard_fab2_lib.baseboard_fab2(sch_1):page244_i28" )
			)
			( gate "C840"
				( objectStatus "@baseboard_fab2_lib.baseboard_fab2(sch_1):page244_i29" )
			)
			( gate "C832"
				( objectStatus "@baseboard_fab2_lib.baseboard_fab2(sch_1):page244_i30" )
			)
			( gate "C845"
				( objectStatus "@baseboard_fab2_lib.baseboard_fab2(sch_1):page244_i35" )
			)
			( gate "R767"
				( objectStatus "@baseboard_fab2_lib.baseboard_fab2(sch_1):page244_i39" )
			)
			( gate "C835"
				( objectStatus "@baseboard_fab2_lib.baseboard_fab2(sch_1):page244_i41" )
			)
			( gate "C843"
				( objectStatus "@baseboard_fab2_lib.baseboard_fab2(sch_1):page244_i47" )
			)
			( gate "C834"
				( objectStatus "@baseboard_fab2_lib.baseboard_fab2(sch_1):page244_i50" )
			)
			( gate "C844"
				( objectStatus "@baseboard_fab2_lib.baseboard_fab2(sch_1):page244_i51" )
			)
			( gate "C842"
				( objectStatus "@baseboard_fab2_lib.baseboard_fab2(sch_1):page244_i52" )
			)
			( gate "R769"
				( objectStatus "@baseboard_fab2_lib.baseboard_fab2(sch_1):page244_i58" )
			)
			( gate "R760"
				( objectStatus "@baseboard_fab2_lib.baseboard_fab2(sch_1):page244_i64" )
			)
			( gate "R771"
				( objectStatus "@baseboard_fab2_lib.baseboard_fab2(sch_1):page244_i65" )
			)
			( gate "R768"
				( objectStatus "@baseboard_fab2_lib.baseboard_fab2(sch_1):page244_i66" )
			)
			( gate "R774"
				( objectStatus "@baseboard_fab2_lib.baseboard_fab2(sch_1):page244_i72" )
			)
			( gate "R779"
				( objectStatus "@baseboard_fab2_lib.baseboard_fab2(sch_1):page244_i74" )
			)
			( gate "R783"
				( objectStatus "@baseboard_fab2_lib.baseboard_fab2(sch_1):page244_i77" )
			)
			( gate "R777"
				( objectStatus "@baseboard_fab2_lib.baseboard_fab2(sch_1):page244_i80" )
			)
			( gate "R781"
				( objectStatus "@baseboard_fab2_lib.baseboard_fab2(sch_1):page244_i86" )
			)
			( gate "R775"
				( objectStatus "@baseboard_fab2_lib.baseboard_fab2(sch_1):page244_i93" )
			)
			( gate "R778"
				( objectStatus "@baseboard_fab2_lib.baseboard_fab2(sch_1):page244_i94" )
			)
			( gate "R780"
				( objectStatus "@baseboard_fab2_lib.baseboard_fab2(sch_1):page244_i97" )
			)
			( gate "R782"
				( objectStatus "@baseboard_fab2_lib.baseboard_fab2(sch_1):page244_i98" )
			)
			( gate "R784"
				( objectStatus "@baseboard_fab2_lib.baseboard_fab2(sch_1):page244_i99" )
			)
			( gate "R785"
				( objectStatus "@baseboard_fab2_lib.baseboard_fab2(sch_1):page244_i103" )
			)
			( gate "CONX8"
				( objectStatus "@baseboard_fab2_lib.baseboard_fab2(sch_1):page245_i48" )
			)
			( gate "J8G1"
				( objectStatus "@baseboard_fab2_lib.baseboard_fab2(sch_1):page109_i78" )
			)
			( gate "RN8F5"
				( objectStatus "@baseboard_fab2_lib.baseboard_fab2(sch_1):page246_i9" )
			)
			( gate "RN8F3"
				( objectStatus "@baseboard_fab2_lib.baseboard_fab2(sch_1):page246_i11" )
			)
			( gate "RN8F4"
				( objectStatus "@baseboard_fab2_lib.baseboard_fab2(sch_1):page246_i12" )
			)
			( gate "C25W12"
				( objectStatus "@baseboard_fab2_lib.baseboard_fab2(sch_1):page151_i212" )
			)
			( gate "C25W10"
				( objectStatus "@baseboard_fab2_lib.baseboard_fab2(sch_1):page151_i213" )
			)
			( gate "UN8F2"
				( objectStatus "@baseboard_fab2_lib.baseboard_fab2(sch_1):page246_i17" )
			)
			( gate "Q6W1"
				( objectStatus "@baseboard_fab2_lib.baseboard_fab2(sch_1):page200_i225" )
			)
			( gate "R6W10"
				( objectStatus "@baseboard_fab2_lib.baseboard_fab2(sch_1):page247_i1" )
			)
			( gate "R7F21"
				( objectStatus "@baseboard_fab2_lib.baseboard_fab2(sch_1):page215_i13" )
			)
			( gate "R7G9"
				( objectStatus "@baseboard_fab2_lib.baseboard_fab2(sch_1):page215_i12" )
			)
			( gate "C8W2"
				( objectStatus "@baseboard_fab2_lib.baseboard_fab2(sch_1):page249_i37" )
			)
			( gate "R10W7"
				( objectStatus "@baseboard_fab2_lib.baseboard_fab2(sch_1):page251_i31" )
			)
			( gate "C10W5"
				( objectStatus "@baseboard_fab2_lib.baseboard_fab2(sch_1):page251_i29" )
			)
			( gate "R10W6"
				( objectStatus "@baseboard_fab2_lib.baseboard_fab2(sch_1):page251_i27" )
			)
			( gate "J1B2"
				( objectStatus "@baseboard_fab2_lib.baseboard_fab2(sch_1):page251_i25" )
			)
			( gate "R25W63"
				( objectStatus "@baseboard_fab2_lib.baseboard_fab2(sch_1):page146_i65" )
			)
			( gate "Q6W2"
				( objectStatus "@baseboard_fab2_lib.baseboard_fab2(sch_1):page168_i47" )
			)
			( gate "U6W11"
				( objectStatus "@baseboard_fab2_lib.baseboard_fab2(sch_1):page164_i97" )
			)
			( gate "R25W58"
				( objectStatus "@baseboard_fab2_lib.baseboard_fab2(sch_1):page144_i150" )
			)
			( gate "R3W1"
				( objectStatus "@baseboard_fab2_lib.baseboard_fab2(sch_1):page249_i2" )
			)
			( gate "R3W9"
				( objectStatus "@baseboard_fab2_lib.baseboard_fab2(sch_1):page249_i7" )
			)
			( gate "R3W7"
				( objectStatus "@baseboard_fab2_lib.baseboard_fab2(sch_1):page249_i8" )
			)
			( gate "R3W4"
				( objectStatus "@baseboard_fab2_lib.baseboard_fab2(sch_1):page249_i31" )
			)
			( gate "Q9W4"
				( objectStatus "@baseboard_fab2_lib.baseboard_fab2(sch_1):page249_i15" )
			)
			( gate "R3P53"
				( objectStatus "@baseboard_fab2_lib.baseboard_fab2(sch_1):page133_i365" )
			)
			( gate "C25W13"
				( objectStatus "@baseboard_fab2_lib.baseboard_fab2(sch_1):page151_i217" )
			)
			( gate "R3W6"
				( objectStatus "@baseboard_fab2_lib.baseboard_fab2(sch_1):page249_i48" )
			)
			( gate "C3W2"
				( objectStatus "@baseboard_fab2_lib.baseboard_fab2(sch_1):page249_i57" )
			)
			( gate "Q9W2"
				( objectStatus "@baseboard_fab2_lib.baseboard_fab2(sch_1):page249_i29" )
			)
			( gate "U14E2"
				( objectStatus "@baseboard_fab2_lib.baseboard_fab2(sch_1):page248_i11" )
			)
			( gate "R6W17"
				( objectStatus "@baseboard_fab2_lib.baseboard_fab2(sch_1):page145_i120" )
			)
			( gate "R25W65"
				( objectStatus "@baseboard_fab2_lib.baseboard_fab2(sch_1):page145_i38" )
			)
			( gate "R25W64"
				( objectStatus "@baseboard_fab2_lib.baseboard_fab2(sch_1):page145_i36" )
			)
			( gate "R25W23"
				( objectStatus "@baseboard_fab2_lib.baseboard_fab2(sch_1):page151_i269" )
			)
			( gate "R9E24"
				( objectStatus "@baseboard_fab2_lib.baseboard_fab2(sch_1):page151_i138" )
			)
			( gate "C9F23"
				( objectStatus "@baseboard_fab2_lib.baseboard_fab2(sch_1):page145_i15" )
			)
			( gate "R9F33"
				( objectStatus "@baseboard_fab2_lib.baseboard_fab2(sch_1):page145_i20" )
			)
			( gate "R12W5"
				( objectStatus "@baseboard_fab2_lib.baseboard_fab2(sch_1):page197_i111" )
			)
			( gate "C25W8"
				( objectStatus "@baseboard_fab2_lib.baseboard_fab2(sch_1):page147_i162" )
			)
			( gate "R25W61"
				( objectStatus "@baseboard_fab2_lib.baseboard_fab2(sch_1):page145_i30" )
			)
			( gate "R25W62"
				( objectStatus "@baseboard_fab2_lib.baseboard_fab2(sch_1):page145_i31" )
			)
			( gate "R6W24"
				( objectStatus "@baseboard_fab2_lib.baseboard_fab2(sch_1):page247_i100" )
			)
			( gate "R25W107"
				( objectStatus "@baseboard_fab2_lib.baseboard_fab2(sch_1):page150_i190" )
			)
			( gate "R9E14"
				( objectStatus "@baseboard_fab2_lib.baseboard_fab2(sch_1):page157_i393" )
			)
			( gate "RT29"
				( objectStatus "@baseboard_fab2_lib.baseboard_fab2(sch_1):page219_i153" )
			)
			( gate "R9F29"
				( objectStatus "@baseboard_fab2_lib.baseboard_fab2(sch_1):page151_i55" )
			)
			( gate "R25W95"
				( objectStatus "@baseboard_fab2_lib.baseboard_fab2(sch_1):page150_i144" )
			)
			( gate "R25W96"
				( objectStatus "@baseboard_fab2_lib.baseboard_fab2(sch_1):page150_i145" )
			)
			( gate "R25W97"
				( objectStatus "@baseboard_fab2_lib.baseboard_fab2(sch_1):page150_i146" )
			)
			( gate "R25W151"
				( objectStatus "@baseboard_fab2_lib.baseboard_fab2(sch_1):page150_i232" )
			)
			( gate "R25W113"
				( objectStatus "@baseboard_fab2_lib.baseboard_fab2(sch_1):page150_i230" )
			)
			( gate "R25W112"
				( objectStatus "@baseboard_fab2_lib.baseboard_fab2(sch_1):page150_i228" )
			)
			( gate "R25W102"
				( objectStatus "@baseboard_fab2_lib.baseboard_fab2(sch_1):page150_i239" )
			)
			( gate "R25W142"
				( objectStatus "@baseboard_fab2_lib.baseboard_fab2(sch_1):page147_i156" )
			)
			( gate "R25W106"
				( objectStatus "@baseboard_fab2_lib.baseboard_fab2(sch_1):page150_i175" )
			)
			( gate "RT18"
				( objectStatus "@baseboard_fab2_lib.baseboard_fab2(sch_1):page207_i112" )
			)
			( gate "RT39"
				( objectStatus "@baseboard_fab2_lib.baseboard_fab2(sch_1):page205_i84" )
			)
			( gate "U25W5"
				( objectStatus "@baseboard_fab2_lib.baseboard_fab2(sch_1):page151_i49" )
			)
			( gate "R6W19"
				( objectStatus "@baseboard_fab2_lib.baseboard_fab2(sch_1):page155_i196" )
			)
			( gate "R25W82"
				( objectStatus "@baseboard_fab2_lib.baseboard_fab2(sch_1):page146_i68" )
			)
			( gate "C25W30"
				( objectStatus "@baseboard_fab2_lib.baseboard_fab2(sch_1):page149_i1" )
			)
			( gate "EU25F2"
				( objectStatus "@baseboard_fab2_lib.baseboard_fab2(sch_1):page239_i73" )
			)
			( gate "R1W9"
				( objectStatus "@baseboard_fab2_lib.baseboard_fab2(sch_1):page239_i77" )
			)
			( gate "R9W12"
				( objectStatus "@baseboard_fab2_lib.baseboard_fab2(sch_1):page239_i79" )
			)
			( gate "C9W13"
				( objectStatus "@baseboard_fab2_lib.baseboard_fab2(sch_1):page239_i81" )
			)
			( gate "C1W15"
				( objectStatus "@baseboard_fab2_lib.baseboard_fab2(sch_1):page239_i83" )
			)
			( gate "C9W10"
				( objectStatus "@baseboard_fab2_lib.baseboard_fab2(sch_1):page239_i84" )
			)
			( gate "C9W5"
				( objectStatus "@baseboard_fab2_lib.baseboard_fab2(sch_1):page239_i90" )
			)
			( gate "C9W6"
				( objectStatus "@baseboard_fab2_lib.baseboard_fab2(sch_1):page239_i91" )
			)
			( gate "C1W7"
				( objectStatus "@baseboard_fab2_lib.baseboard_fab2(sch_1):page239_i92" )
			)
			( gate "U25W4"
				( objectStatus "@baseboard_fab2_lib.baseboard_fab2(sch_1):page144_i95" )
			)
			( gate "Q9W1"
				( objectStatus "@baseboard_fab2_lib.baseboard_fab2(sch_1):page249_i30" )
			)
			( gate "R6W25"
				( objectStatus "@baseboard_fab2_lib.baseboard_fab2(sch_1):page247_i101" )
			)
			( gate "U25W4"
				( objectStatus "@baseboard_fab2_lib.baseboard_fab2(sch_1):page146_i104" )
			)
			( gate "C9W1"
				( objectStatus "@baseboard_fab2_lib.baseboard_fab2(sch_1):page200_i235" )
			)
			( gate "C9W2"
				( objectStatus "@baseboard_fab2_lib.baseboard_fab2(sch_1):page200_i236" )
			)
			( gate "R25W81"
				( objectStatus "@baseboard_fab2_lib.baseboard_fab2(sch_1):page146_i67" )
			)
			( gate "R25W111"
				( objectStatus "@baseboard_fab2_lib.baseboard_fab2(sch_1):page150_i180" )
			)
			( gate "RT23"
				( objectStatus "@baseboard_fab2_lib.baseboard_fab2(sch_1):page204_i99" )
			)
			( gate "R25W57"
				( objectStatus "@baseboard_fab2_lib.baseboard_fab2(sch_1):page147_i151" )
			)
			( gate "RT15"
				( objectStatus "@baseboard_fab2_lib.baseboard_fab2(sch_1):page207_i99" )
			)
			( gate "RT37"
				( objectStatus "@baseboard_fab2_lib.baseboard_fab2(sch_1):page210_i68" )
			)
			( gate "RT9"
				( objectStatus "@baseboard_fab2_lib.baseboard_fab2(sch_1):page209_i75" )
			)
			( gate "RT36"
				( objectStatus "@baseboard_fab2_lib.baseboard_fab2(sch_1):page216_i140" )
			)
			( gate "RT44"
				( objectStatus "@baseboard_fab2_lib.baseboard_fab2(sch_1):page236_i153" )
			)
			( gate "RT46"
				( objectStatus "@baseboard_fab2_lib.baseboard_fab2(sch_1):page236_i154" )
			)
			( gate "RT14"
				( objectStatus "@baseboard_fab2_lib.baseboard_fab2(sch_1):page208_i109" )
			)
			( gate "RT40"
				( objectStatus "@baseboard_fab2_lib.baseboard_fab2(sch_1):page205_i78" )
			)
			( gate "R25W94"
				( objectStatus "@baseboard_fab2_lib.baseboard_fab2(sch_1):page137_i140" )
			)
			( gate "R25W154"
				( objectStatus "@baseboard_fab2_lib.baseboard_fab2(sch_1):page137_i133" )
			)
			( gate "R9F66"
				( objectStatus "@baseboard_fab2_lib.baseboard_fab2(sch_1):page158_i152" )
			)
			( gate "R1U13"
				( objectStatus "@baseboard_fab2_lib.baseboard_fab2(sch_1):page144_i58" )
			)
			( gate "R1U14"
				( objectStatus "@baseboard_fab2_lib.baseboard_fab2(sch_1):page144_i57" )
			)
			( gate "U25W4"
				( objectStatus "@baseboard_fab2_lib.baseboard_fab2(sch_1):page148_i28" )
			)
			( gate "C25W49"
				( objectStatus "@baseboard_fab2_lib.baseboard_fab2(sch_1):page149_i123" )
			)
			( gate "C1T21"
				( objectStatus "@baseboard_fab2_lib.baseboard_fab2(sch_1):page148_i20" )
			)
			( gate "R1U12"
				( objectStatus "@baseboard_fab2_lib.baseboard_fab2(sch_1):page144_i59" )
			)
			( gate "R25W59"
				( objectStatus "@baseboard_fab2_lib.baseboard_fab2(sch_1):page148_i16" )
			)
			( gate "R1U2"
				( objectStatus "@baseboard_fab2_lib.baseboard_fab2(sch_1):page147_i62" )
			)
			( gate "R25W60"
				( objectStatus "@baseboard_fab2_lib.baseboard_fab2(sch_1):page145_i34" )
			)
			( gate "U25W4"
				( objectStatus "@baseboard_fab2_lib.baseboard_fab2(sch_1):page147_i106" )
			)
			( gate "R1U1"
				( objectStatus "@baseboard_fab2_lib.baseboard_fab2(sch_1):page147_i61" )
			)
			( gate "R1T26"
				( objectStatus "@baseboard_fab2_lib.baseboard_fab2(sch_1):page146_i37" )
			)
			( gate "R1T25"
				( objectStatus "@baseboard_fab2_lib.baseboard_fab2(sch_1):page146_i35" )
			)
			( gate "R25W83"
				( objectStatus "@baseboard_fab2_lib.baseboard_fab2(sch_1):page146_i26" )
			)
			( gate "C25W70"
				( objectStatus "@baseboard_fab2_lib.baseboard_fab2(sch_1):page149_i5" )
			)
			( gate "R25W90"
				( objectStatus "@baseboard_fab2_lib.baseboard_fab2(sch_1):page147_i21" )
			)
			( gate "C25W55"
				( objectStatus "@baseboard_fab2_lib.baseboard_fab2(sch_1):page149_i124" )
			)
			( gate "RT12"
				( objectStatus "@baseboard_fab2_lib.baseboard_fab2(sch_1):page208_i120" )
			)
			( gate "R9F61"
				( objectStatus "@baseboard_fab2_lib.baseboard_fab2(sch_1):page145_i14" )
			)
			( gate "R9F62"
				( objectStatus "@baseboard_fab2_lib.baseboard_fab2(sch_1):page145_i11" )
			)
			( gate "R9F60"
				( objectStatus "@baseboard_fab2_lib.baseboard_fab2(sch_1):page145_i10" )
			)
			( gate "Y9F2"
				( objectStatus "@baseboard_fab2_lib.baseboard_fab2(sch_1):page145_i8" )
			)
			( gate "R12W15"
				( objectStatus "@baseboard_fab2_lib.baseboard_fab2(sch_1):page197_i112" )
			)
			( gate "R25W33"
				( objectStatus "@baseboard_fab2_lib.baseboard_fab2(sch_1):page151_i228" )
			)
			( gate "C25W1"
				( objectStatus "@baseboard_fab2_lib.baseboard_fab2(sch_1):page151_i125" )
			)
			( gate "C25W19"
				( objectStatus "@baseboard_fab2_lib.baseboard_fab2(sch_1):page151_i123" )
			)
			( gate "C25W18"
				( objectStatus "@baseboard_fab2_lib.baseboard_fab2(sch_1):page151_i121" )
			)
			( gate "C25W17"
				( objectStatus "@baseboard_fab2_lib.baseboard_fab2(sch_1):page151_i120" )
			)
			( gate "C1W21"
				( objectStatus "@baseboard_fab2_lib.baseboard_fab2(sch_1):page146_i160" )
			)
			( gate "R6U14"
				( objectStatus "@baseboard_fab2_lib.baseboard_fab2(sch_1):page99_i115" )
			)
			( gate "R25W117"
				( objectStatus "@baseboard_fab2_lib.baseboard_fab2(sch_1):page151_i101" )
			)
			( gate "C25W31"
				( objectStatus "@baseboard_fab2_lib.baseboard_fab2(sch_1):page149_i119" )
			)
			( gate "C25W34"
				( objectStatus "@baseboard_fab2_lib.baseboard_fab2(sch_1):page149_i120" )
			)
			( gate "R25W1"
				( objectStatus "@baseboard_fab2_lib.baseboard_fab2(sch_1):page151_i248" )
			)
			( gate "U9F3"
				( objectStatus "@baseboard_fab2_lib.baseboard_fab2(sch_1):page151_i56" )
			)
			( gate "R1T24"
				( objectStatus "@baseboard_fab2_lib.baseboard_fab2(sch_1):page147_i129" )
			)
			( gate "R1U5"
				( objectStatus "@baseboard_fab2_lib.baseboard_fab2(sch_1):page147_i66" )
			)
			( gate "R1U4"
				( objectStatus "@baseboard_fab2_lib.baseboard_fab2(sch_1):page147_i65" )
			)
			( gate "R25W80"
				( objectStatus "@baseboard_fab2_lib.baseboard_fab2(sch_1):page147_i43" )
			)
			( gate "R25W79"
				( objectStatus "@baseboard_fab2_lib.baseboard_fab2(sch_1):page147_i42" )
			)
			( gate "C25W7"
				( objectStatus "@baseboard_fab2_lib.baseboard_fab2(sch_1):page147_i161" )
			)
			( gate "R25W87"
				( objectStatus "@baseboard_fab2_lib.baseboard_fab2(sch_1):page147_i25" )
			)
			( gate "R25W86"
				( objectStatus "@baseboard_fab2_lib.baseboard_fab2(sch_1):page147_i24" )
			)
			( gate "R25W85"
				( objectStatus "@baseboard_fab2_lib.baseboard_fab2(sch_1):page147_i23" )
			)
			( gate "R25W89"
				( objectStatus "@baseboard_fab2_lib.baseboard_fab2(sch_1):page147_i22" )
			)
			( gate "R25W88"
				( objectStatus "@baseboard_fab2_lib.baseboard_fab2(sch_1):page147_i8" )
			)
			( gate "R25W69"
				( objectStatus "@baseboard_fab2_lib.baseboard_fab2(sch_1):page146_i85" )
			)
			( gate "R25W68"
				( objectStatus "@baseboard_fab2_lib.baseboard_fab2(sch_1):page146_i84" )
			)
			( gate "R1U7"
				( objectStatus "@baseboard_fab2_lib.baseboard_fab2(sch_1):page146_i78" )
			)
			( gate "R25W66"
				( objectStatus "@baseboard_fab2_lib.baseboard_fab2(sch_1):page146_i76" )
			)
			( gate "R3N26"
				( objectStatus "@baseboard_fab2_lib.baseboard_fab2(sch_1):page146_i75" )
			)
			( gate "R3N24"
				( objectStatus "@baseboard_fab2_lib.baseboard_fab2(sch_1):page146_i74" )
			)
			( gate "R25W73"
				( objectStatus "@baseboard_fab2_lib.baseboard_fab2(sch_1):page146_i73" )
			)
			( gate "RF4"
				( objectStatus "@baseboard_fab2_lib.baseboard_fab2(sch_1):page201_i185" )
			)
			( gate "R25W72"
				( objectStatus "@baseboard_fab2_lib.baseboard_fab2(sch_1):page146_i71" )
			)
			( gate "R25W74"
				( objectStatus "@baseboard_fab2_lib.baseboard_fab2(sch_1):page146_i70" )
			)
			( gate "R9E21"
				( objectStatus "@baseboard_fab2_lib.baseboard_fab2(sch_1):page151_i173" )
			)
			( gate "R25W2"
				( objectStatus "@baseboard_fab2_lib.baseboard_fab2(sch_1):page151_i249" )
			)
			( gate "R25W3"
				( objectStatus "@baseboard_fab2_lib.baseboard_fab2(sch_1):page151_i250" )
			)
			( gate "R25W4"
				( objectStatus "@baseboard_fab2_lib.baseboard_fab2(sch_1):page151_i251" )
			)
			( gate "R25W5"
				( objectStatus "@baseboard_fab2_lib.baseboard_fab2(sch_1):page151_i252" )
			)
			( gate "R25W6"
				( objectStatus "@baseboard_fab2_lib.baseboard_fab2(sch_1):page151_i253" )
			)
			( gate "R25W7"
				( objectStatus "@baseboard_fab2_lib.baseboard_fab2(sch_1):page151_i254" )
			)
			( gate "R25W8"
				( objectStatus "@baseboard_fab2_lib.baseboard_fab2(sch_1):page151_i255" )
			)
			( gate "R25W12"
				( objectStatus "@baseboard_fab2_lib.baseboard_fab2(sch_1):page151_i256" )
			)
			( gate "R25W11"
				( objectStatus "@baseboard_fab2_lib.baseboard_fab2(sch_1):page151_i257" )
			)
			( gate "R25W9"
				( objectStatus "@baseboard_fab2_lib.baseboard_fab2(sch_1):page151_i258" )
			)
			( gate "R25W10"
				( objectStatus "@baseboard_fab2_lib.baseboard_fab2(sch_1):page151_i259" )
			)
			( gate "R25W13"
				( objectStatus "@baseboard_fab2_lib.baseboard_fab2(sch_1):page151_i260" )
			)
			( gate "R25W16"
				( objectStatus "@baseboard_fab2_lib.baseboard_fab2(sch_1):page151_i261" )
			)
			( gate "R25W15"
				( objectStatus "@baseboard_fab2_lib.baseboard_fab2(sch_1):page151_i262" )
			)
			( gate "R25W14"
				( objectStatus "@baseboard_fab2_lib.baseboard_fab2(sch_1):page151_i263" )
			)
			( gate "R25W17"
				( objectStatus "@baseboard_fab2_lib.baseboard_fab2(sch_1):page151_i264" )
			)
			( gate "R25W18"
				( objectStatus "@baseboard_fab2_lib.baseboard_fab2(sch_1):page151_i265" )
			)
			( gate "R25W20"
				( objectStatus "@baseboard_fab2_lib.baseboard_fab2(sch_1):page151_i266" )
			)
			( gate "R25W19"
				( objectStatus "@baseboard_fab2_lib.baseboard_fab2(sch_1):page151_i267" )
			)
			( gate "R25W24"
				( objectStatus "@baseboard_fab2_lib.baseboard_fab2(sch_1):page151_i268" )
			)
			( gate "R25W118"
				( objectStatus "@baseboard_fab2_lib.baseboard_fab2(sch_1):page151_i211" )
			)
			( gate "Q9E1"
				( objectStatus "@baseboard_fab2_lib.baseboard_fab2(sch_1):page151_i145" )
			)
			( gate "DS9E1"
				( objectStatus "@baseboard_fab2_lib.baseboard_fab2(sch_1):page151_i144" )
			)
			( gate "C25W16"
				( objectStatus "@baseboard_fab2_lib.baseboard_fab2(sch_1):page151_i58" )
			)
			( gate "R2N13"
				( objectStatus "@baseboard_fab2_lib.baseboard_fab2(sch_1):page147_i75" )
			)
			( gate "R25W78"
				( objectStatus "@baseboard_fab2_lib.baseboard_fab2(sch_1):page146_i123" )
			)
			( gate "R1T15"
				( objectStatus "@baseboard_fab2_lib.baseboard_fab2(sch_1):page145_i100" )
			)
			( gate "R1T23"
				( objectStatus "@baseboard_fab2_lib.baseboard_fab2(sch_1):page145_i101" )
			)
			( gate "C6W3"
				( objectStatus "@baseboard_fab2_lib.baseboard_fab2(sch_1):page247_i85" )
			)
			( gate "R6W20"
				( objectStatus "@baseboard_fab2_lib.baseboard_fab2(sch_1):page247_i87" )
			)
			( gate "U6W3"
				( objectStatus "@baseboard_fab2_lib.baseboard_fab2(sch_1):page247_i89" )
			)
			( gate "R6W21"
				( objectStatus "@baseboard_fab2_lib.baseboard_fab2(sch_1):page247_i90" )
			)
			( gate "R6W23"
				( objectStatus "@baseboard_fab2_lib.baseboard_fab2(sch_1):page247_i92" )
			)
			( gate "R6W22"
				( objectStatus "@baseboard_fab2_lib.baseboard_fab2(sch_1):page247_i94" )
			)
			( gate "U25W4"
				( objectStatus "@baseboard_fab2_lib.baseboard_fab2(sch_1):page143_i63" )
			)
			( gate "U25W4"
				( objectStatus "@baseboard_fab2_lib.baseboard_fab2(sch_1):page146_i105" )
			)
			( gate "F25W1"
				( objectStatus "@baseboard_fab2_lib.baseboard_fab2(sch_1):page255_i89" )
			)
			( gate "R6W11"
				( objectStatus "@baseboard_fab2_lib.baseboard_fab2(sch_1):page247_i98" )
			)
			( gate "C6W2"
				( objectStatus "@baseboard_fab2_lib.baseboard_fab2(sch_1):page247_i107" )
			)
			( gate "C7G19"
				( objectStatus "@baseboard_fab2_lib.baseboard_fab2(sch_1):page105_i257" )
			)
			( gate "C7G20"
				( objectStatus "@baseboard_fab2_lib.baseboard_fab2(sch_1):page105_i258" )
			)
			( gate "R25W67"
				( objectStatus "@baseboard_fab2_lib.baseboard_fab2(sch_1):page145_i118" )
			)
			( gate "R6W18"
				( objectStatus "@baseboard_fab2_lib.baseboard_fab2(sch_1):page145_i119" )
			)
			( gate "CF5"
				( objectStatus "@baseboard_fab2_lib.baseboard_fab2(sch_1):page201_i172" )
			)
			( gate "CF4"
				( objectStatus "@baseboard_fab2_lib.baseboard_fab2(sch_1):page201_i171" )
			)
			( gate "CF3"
				( objectStatus "@baseboard_fab2_lib.baseboard_fab2(sch_1):page201_i170" )
			)
			( gate "CF2"
				( objectStatus "@baseboard_fab2_lib.baseboard_fab2(sch_1):page201_i169" )
			)
			( gate "CF1"
				( objectStatus "@baseboard_fab2_lib.baseboard_fab2(sch_1):page201_i168" )
			)
			( gate "RF12"
				( objectStatus "@baseboard_fab2_lib.baseboard_fab2(sch_1):page206_i149" )
			)
			( gate "RF7"
				( objectStatus "@baseboard_fab2_lib.baseboard_fab2(sch_1):page206_i150" )
			)
			( gate "RF8"
				( objectStatus "@baseboard_fab2_lib.baseboard_fab2(sch_1):page206_i151" )
			)
			( gate "RF9"
				( objectStatus "@baseboard_fab2_lib.baseboard_fab2(sch_1):page206_i152" )
			)
			( gate "RF10"
				( objectStatus "@baseboard_fab2_lib.baseboard_fab2(sch_1):page206_i153" )
			)
			( gate "RF11"
				( objectStatus "@baseboard_fab2_lib.baseboard_fab2(sch_1):page206_i154" )
			)
			( gate "RF14"
				( objectStatus "@baseboard_fab2_lib.baseboard_fab2(sch_1):page213_i99" )
			)
			( gate "R4G23"
				( objectStatus "@baseboard_fab2_lib.baseboard_fab2(sch_1):page221_i4" )
			)
			( gate "C4A2"
				( objectStatus "@baseboard_fab2_lib.baseboard_fab2(sch_1):page222_i2" )
			)
			( gate "R4A2"
				( objectStatus "@baseboard_fab2_lib.baseboard_fab2(sch_1):page222_i4" )
			)
			( gate "C4G12"
				( objectStatus "@baseboard_fab2_lib.baseboard_fab2(sch_1):page229_i2" )
			)
			( gate "R4G16"
				( objectStatus "@baseboard_fab2_lib.baseboard_fab2(sch_1):page229_i4" )
			)
			( gate "C12W2"
				( objectStatus "@baseboard_fab2_lib.baseboard_fab2(sch_1):page197_i1" )
			)
			( gate "RF24"
				( objectStatus "@baseboard_fab2_lib.baseboard_fab2(sch_1):page235_i242" )
			)
			( gate "RF23"
				( objectStatus "@baseboard_fab2_lib.baseboard_fab2(sch_1):page235_i241" )
			)
			( gate "R6W12"
				( objectStatus "@baseboard_fab2_lib.baseboard_fab2(sch_1):page247_i99" )
			)
			( gate "C14W1"
				( objectStatus "@baseboard_fab2_lib.baseboard_fab2(sch_1):page248_i13" )
			)
			( gate "C14W2"
				( objectStatus "@baseboard_fab2_lib.baseboard_fab2(sch_1):page248_i17" )
			)
			( gate "S9A2"
				( objectStatus "@baseboard_fab2_lib.baseboard_fab2(sch_1):page175_i92" )
			)
			( gate "RF5"
				( objectStatus "@baseboard_fab2_lib.baseboard_fab2(sch_1):page201_i186" )
			)
			( gate "RF3"
				( objectStatus "@baseboard_fab2_lib.baseboard_fab2(sch_1):page201_i184" )
			)
			( gate "RF2"
				( objectStatus "@baseboard_fab2_lib.baseboard_fab2(sch_1):page201_i183" )
			)
			( gate "RF1"
				( objectStatus "@baseboard_fab2_lib.baseboard_fab2(sch_1):page201_i182" )
			)
			( gate "RF6"
				( objectStatus "@baseboard_fab2_lib.baseboard_fab2(sch_1):page201_i180" )
			)
			( gate "CF6"
				( objectStatus "@baseboard_fab2_lib.baseboard_fab2(sch_1):page201_i173" )
			)
			( gate "CF7"
				( objectStatus "@baseboard_fab2_lib.baseboard_fab2(sch_1):page206_i137" )
			)
			( gate "CF8"
				( objectStatus "@baseboard_fab2_lib.baseboard_fab2(sch_1):page206_i138" )
			)
			( gate "CF9"
				( objectStatus "@baseboard_fab2_lib.baseboard_fab2(sch_1):page206_i139" )
			)
			( gate "CF10"
				( objectStatus "@baseboard_fab2_lib.baseboard_fab2(sch_1):page206_i140" )
			)
			( gate "CF11"
				( objectStatus "@baseboard_fab2_lib.baseboard_fab2(sch_1):page206_i141" )
			)
			( gate "CF12"
				( objectStatus "@baseboard_fab2_lib.baseboard_fab2(sch_1):page206_i142" )
			)
			( gate "CF13"
				( objectStatus "@baseboard_fab2_lib.baseboard_fab2(sch_1):page211_i95" )
			)
			( gate "R6U5"
				( objectStatus "@baseboard_fab2_lib.baseboard_fab2(sch_1):page221_i6" )
			)
			( gate "R6U15"
				( objectStatus "@baseboard_fab2_lib.baseboard_fab2(sch_1):page221_i5" )
			)
			( gate "CF14"
				( objectStatus "@baseboard_fab2_lib.baseboard_fab2(sch_1):page213_i98" )
			)
			( gate "R6L10"
				( objectStatus "@baseboard_fab2_lib.baseboard_fab2(sch_1):page222_i6" )
			)
			( gate "R6L4"
				( objectStatus "@baseboard_fab2_lib.baseboard_fab2(sch_1):page222_i5" )
			)
			( gate "R6U6"
				( objectStatus "@baseboard_fab2_lib.baseboard_fab2(sch_1):page229_i6" )
			)
			( gate "R6U3"
				( objectStatus "@baseboard_fab2_lib.baseboard_fab2(sch_1):page229_i5" )
			)
			( gate "R12W13"
				( objectStatus "@baseboard_fab2_lib.baseboard_fab2(sch_1):page197_i116" )
			)
			( gate "CF23"
				( objectStatus "@baseboard_fab2_lib.baseboard_fab2(sch_1):page235_i239" )
			)
			( gate "CF24"
				( objectStatus "@baseboard_fab2_lib.baseboard_fab2(sch_1):page235_i240" )
			)
			( gate "R25W27"
				( objectStatus "@baseboard_fab2_lib.baseboard_fab2(sch_1):page151_i223" )
			)
			( gate "R25W70"
				( objectStatus "@baseboard_fab2_lib.baseboard_fab2(sch_1):page144_i114" )
			)
			( gate "R25W75"
				( objectStatus "@baseboard_fab2_lib.baseboard_fab2(sch_1):page144_i118" )
			)
			( gate "C2A16"
				( objectStatus "@baseboard_fab2_lib.baseboard_fab2(sch_1):page228_i313" )
			)
			( gate "C8P1"
				( objectStatus "@baseboard_fab2_lib.baseboard_fab2(sch_1):page228_i304" )
			)
			( gate "C25W69"
				( objectStatus "@baseboard_fab2_lib.baseboard_fab2(sch_1):page149_i17" )
			)
			( gate "C6W1"
				( objectStatus "@baseboard_fab2_lib.baseboard_fab2(sch_1):page247_i151" )
			)
			( gate "FB2T1"
				( objectStatus "@baseboard_fab2_lib.baseboard_fab2(sch_1):page149_i22" )
			)
			( gate "C25W39"
				( objectStatus "@baseboard_fab2_lib.baseboard_fab2(sch_1):page149_i25" )
			)
			( gate "C25W50"
				( objectStatus "@baseboard_fab2_lib.baseboard_fab2(sch_1):page149_i31" )
			)
			( gate "C25W62"
				( objectStatus "@baseboard_fab2_lib.baseboard_fab2(sch_1):page149_i40" )
			)
			( gate "FB2T7"
				( objectStatus "@baseboard_fab2_lib.baseboard_fab2(sch_1):page149_i42" )
			)
			( gate "C25W36"
				( objectStatus "@baseboard_fab2_lib.baseboard_fab2(sch_1):page149_i46" )
			)
			( gate "C25W61"
				( objectStatus "@baseboard_fab2_lib.baseboard_fab2(sch_1):page149_i126" )
			)
			( gate "C25W47"
				( objectStatus "@baseboard_fab2_lib.baseboard_fab2(sch_1):page149_i50" )
			)
			( gate "C25W46"
				( objectStatus "@baseboard_fab2_lib.baseboard_fab2(sch_1):page149_i51" )
			)
			( gate "C25W68"
				( objectStatus "@baseboard_fab2_lib.baseboard_fab2(sch_1):page149_i128" )
			)
			( gate "R25W183"
				( objectStatus "@baseboard_fab2_lib.baseboard_fab2(sch_1):page268_i36" )
			)
			( gate "C25W58"
				( objectStatus "@baseboard_fab2_lib.baseboard_fab2(sch_1):page149_i125" )
			)
			( gate "C25W59"
				( objectStatus "@baseboard_fab2_lib.baseboard_fab2(sch_1):page149_i79" )
			)
			( gate "C25W22"
				( objectStatus "@baseboard_fab2_lib.baseboard_fab2(sch_1):page143_i67" )
			)
			( gate "Q1W2"
				( objectStatus "@baseboard_fab2_lib.baseboard_fab2(sch_1):page250_i12" )
			)
			( gate "FB2T3"
				( objectStatus "@baseboard_fab2_lib.baseboard_fab2(sch_1):page149_i85" )
			)
			( gate "FB2T4"
				( objectStatus "@baseboard_fab2_lib.baseboard_fab2(sch_1):page149_i86" )
			)
			( gate "FB2T5"
				( objectStatus "@baseboard_fab2_lib.baseboard_fab2(sch_1):page149_i88" )
			)
			( gate "RT4"
				( objectStatus "@baseboard_fab2_lib.baseboard_fab2(sch_1):page202_i115" )
			)
			( gate "R9P13"
				( objectStatus "@baseboard_fab2_lib.baseboard_fab2(sch_1):page200_i249" )
			)
			( gate "Q9E1"
				( objectStatus "@baseboard_fab2_lib.baseboard_fab2(sch_1):page151_i198" )
			)
			( gate "R1T30"
				( objectStatus "@baseboard_fab2_lib.baseboard_fab2(sch_1):page151_i201" )
			)
			( gate "R1T29"
				( objectStatus "@baseboard_fab2_lib.baseboard_fab2(sch_1):page151_i202" )
			)
			( gate "CN8F2"
				( objectStatus "@baseboard_fab2_lib.baseboard_fab2(sch_1):page246_i22" )
			)
			( gate "C25W15"
				( objectStatus "@baseboard_fab2_lib.baseboard_fab2(sch_1):page151_i216" )
			)
			( gate "C25W14"
				( objectStatus "@baseboard_fab2_lib.baseboard_fab2(sch_1):page151_i215" )
			)
			( gate "U14E3"
				( objectStatus "@baseboard_fab2_lib.baseboard_fab2(sch_1):page248_i19" )
			)
			( gate "RT16"
				( objectStatus "@baseboard_fab2_lib.baseboard_fab2(sch_1):page207_i111" )
			)
			( gate "R6W26"
				( objectStatus "@baseboard_fab2_lib.baseboard_fab2(sch_1):page248_i24" )
			)
			( gate "R6W27"
				( objectStatus "@baseboard_fab2_lib.baseboard_fab2(sch_1):page248_i25" )
			)
			( gate "R9W19"
				( objectStatus "@baseboard_fab2_lib.baseboard_fab2(sch_1):page248_i26" )
			)
			( gate "R9W18"
				( objectStatus "@baseboard_fab2_lib.baseboard_fab2(sch_1):page248_i27" )
			)
			( gate "C9W8"
				( objectStatus "@baseboard_fab2_lib.baseboard_fab2(sch_1):page248_i30" )
			)
			( gate "C9W7"
				( objectStatus "@baseboard_fab2_lib.baseboard_fab2(sch_1):page248_i32" )
			)
			( gate "R9W16"
				( objectStatus "@baseboard_fab2_lib.baseboard_fab2(sch_1):page248_i34" )
			)
			( gate "R9W17"
				( objectStatus "@baseboard_fab2_lib.baseboard_fab2(sch_1):page248_i35" )
			)
			( gate "R9W14"
				( objectStatus "@baseboard_fab2_lib.baseboard_fab2(sch_1):page248_i37" )
			)
			( gate "R9W13"
				( objectStatus "@baseboard_fab2_lib.baseboard_fab2(sch_1):page248_i38" )
			)
			( gate "R8W1"
				( objectStatus "@baseboard_fab2_lib.baseboard_fab2(sch_1):page249_i34" )
			)
			( gate "RT35"
				( objectStatus "@baseboard_fab2_lib.baseboard_fab2(sch_1):page216_i152" )
			)
			( gate "R1W3"
				( objectStatus "@baseboard_fab2_lib.baseboard_fab2(sch_1):page250_i27" )
			)
			( gate "Q1W2"
				( objectStatus "@baseboard_fab2_lib.baseboard_fab2(sch_1):page250_i24" )
			)
			( gate "R1W4"
				( objectStatus "@baseboard_fab2_lib.baseboard_fab2(sch_1):page250_i22" )
			)
			( gate "Q1W5"
				( objectStatus "@baseboard_fab2_lib.baseboard_fab2(sch_1):page199_i130" )
			)
			( gate "R1W1"
				( objectStatus "@baseboard_fab2_lib.baseboard_fab2(sch_1):page250_i18" )
			)
			( gate "R1U23"
				( objectStatus "@baseboard_fab2_lib.baseboard_fab2(sch_1):page164_i34" )
			)
			( gate "R1U16"
				( objectStatus "@baseboard_fab2_lib.baseboard_fab2(sch_1):page164_i37" )
			)
			( gate "R6W28"
				( objectStatus "@baseboard_fab2_lib.baseboard_fab2(sch_1):page247_i112" )
			)
			( gate "R25W120"
				( objectStatus "@baseboard_fab2_lib.baseboard_fab2(sch_1):page149_i91" )
			)
			( gate "R2U28"
				( objectStatus "@baseboard_fab2_lib.baseboard_fab2(sch_1):page107_i500" )
			)
			( gate "R2U14"
				( objectStatus "@baseboard_fab2_lib.baseboard_fab2(sch_1):page107_i499" )
			)
			( gate "R2U26"
				( objectStatus "@baseboard_fab2_lib.baseboard_fab2(sch_1):page107_i498" )
			)
			( gate "C3P12"
				( objectStatus "@baseboard_fab2_lib.baseboard_fab2(sch_1):page107_i481" )
			)
			( gate "C3P21"
				( objectStatus "@baseboard_fab2_lib.baseboard_fab2(sch_1):page107_i480" )
			)
			( gate "C3P24"
				( objectStatus "@baseboard_fab2_lib.baseboard_fab2(sch_1):page107_i479" )
			)
			( gate "C3P29"
				( objectStatus "@baseboard_fab2_lib.baseboard_fab2(sch_1):page107_i478" )
			)
			( gate "C8F15"
				( objectStatus "@baseboard_fab2_lib.baseboard_fab2(sch_1):page185_i142" )
			)
			( gate "C8F13"
				( objectStatus "@baseboard_fab2_lib.baseboard_fab2(sch_1):page185_i141" )
			)
			( gate "C8F12"
				( objectStatus "@baseboard_fab2_lib.baseboard_fab2(sch_1):page185_i140" )
			)
			( gate "C8F6"
				( objectStatus "@baseboard_fab2_lib.baseboard_fab2(sch_1):page185_i138" )
			)
			( gate "Q1W4"
				( objectStatus "@baseboard_fab2_lib.baseboard_fab2(sch_1):page250_i8" )
			)
			( gate "R1W7"
				( objectStatus "@baseboard_fab2_lib.baseboard_fab2(sch_1):page250_i6" )
			)
			( gate "Q1W4"
				( objectStatus "@baseboard_fab2_lib.baseboard_fab2(sch_1):page250_i3" )
			)
			( gate "R1W6"
				( objectStatus "@baseboard_fab2_lib.baseboard_fab2(sch_1):page250_i2" )
			)
			( gate "R2U16"
				( objectStatus "@baseboard_fab2_lib.baseboard_fab2(sch_1):page107_i501" )
			)
			( gate "R2U18"
				( objectStatus "@baseboard_fab2_lib.baseboard_fab2(sch_1):page107_i502" )
			)
			( gate "R2U20"
				( objectStatus "@baseboard_fab2_lib.baseboard_fab2(sch_1):page107_i503" )
			)
			( gate "R2U22"
				( objectStatus "@baseboard_fab2_lib.baseboard_fab2(sch_1):page107_i504" )
			)
			( gate "R2U24"
				( objectStatus "@baseboard_fab2_lib.baseboard_fab2(sch_1):page107_i505" )
			)
			( gate "R1U33"
				( objectStatus "@baseboard_fab2_lib.baseboard_fab2(sch_1):page169_i171" )
			)
			( gate "R1U38"
				( objectStatus "@baseboard_fab2_lib.baseboard_fab2(sch_1):page169_i172" )
			)
			( gate "R1U27"
				( objectStatus "@baseboard_fab2_lib.baseboard_fab2(sch_1):page169_i173" )
			)
			( gate "R9B7"
				( objectStatus "@baseboard_fab2_lib.baseboard_fab2(sch_1):page186_i358" )
			)
			( gate "R2R8"
				( objectStatus "@baseboard_fab2_lib.baseboard_fab2(sch_1):page187_i175" )
			)
			( gate "CT20"
				( objectStatus "@baseboard_fab2_lib.baseboard_fab2(sch_1):page208_i105" )
			)
			( gate "C5G115"
				( objectStatus "@baseboard_fab2_lib.baseboard_fab2(sch_1):page243_i89" )
			)
			( gate "RT28"
				( objectStatus "@baseboard_fab2_lib.baseboard_fab2(sch_1):page203_i123" )
			)
			( gate "RT25"
				( objectStatus "@baseboard_fab2_lib.baseboard_fab2(sch_1):page203_i122" )
			)
			( gate "CT5"
				( objectStatus "@baseboard_fab2_lib.baseboard_fab2(sch_1):page202_i98" )
			)
			( gate "CT3"
				( objectStatus "@baseboard_fab2_lib.baseboard_fab2(sch_1):page202_i97" )
			)
			( gate "R9W1"
				( objectStatus "@baseboard_fab2_lib.baseboard_fab2(sch_1):page186_i356" )
			)
			( gate "R2W1"
				( objectStatus "@baseboard_fab2_lib.baseboard_fab2(sch_1):page187_i174" )
			)
			( gate "RT13"
				( objectStatus "@baseboard_fab2_lib.baseboard_fab2(sch_1):page208_i121" )
			)
			( gate "RT1"
				( objectStatus "@baseboard_fab2_lib.baseboard_fab2(sch_1):page202_i101" )
			)
			( gate "RT3"
				( objectStatus "@baseboard_fab2_lib.baseboard_fab2(sch_1):page202_i102" )
			)
			( gate "RT6"
				( objectStatus "@baseboard_fab2_lib.baseboard_fab2(sch_1):page227_i149" )
			)
			( gate "C25W53"
				( objectStatus "@baseboard_fab2_lib.baseboard_fab2(sch_1):page149_i92" )
			)
			( gate "C25W56"
				( objectStatus "@baseboard_fab2_lib.baseboard_fab2(sch_1):page149_i93" )
			)
			( gate "C25W54"
				( objectStatus "@baseboard_fab2_lib.baseboard_fab2(sch_1):page149_i95" )
			)
			( gate "C25W40"
				( objectStatus "@baseboard_fab2_lib.baseboard_fab2(sch_1):page149_i96" )
			)
			( gate "C25W41"
				( objectStatus "@baseboard_fab2_lib.baseboard_fab2(sch_1):page149_i97" )
			)
			( gate "C25W42"
				( objectStatus "@baseboard_fab2_lib.baseboard_fab2(sch_1):page149_i98" )
			)
			( gate "C25W32"
				( objectStatus "@baseboard_fab2_lib.baseboard_fab2(sch_1):page149_i99" )
			)
			( gate "C25W43"
				( objectStatus "@baseboard_fab2_lib.baseboard_fab2(sch_1):page149_i100" )
			)
			( gate "C25W44"
				( objectStatus "@baseboard_fab2_lib.baseboard_fab2(sch_1):page149_i101" )
			)
			( gate "C25W33"
				( objectStatus "@baseboard_fab2_lib.baseboard_fab2(sch_1):page149_i102" )
			)
			( gate "C25W23"
				( objectStatus "@baseboard_fab2_lib.baseboard_fab2(sch_1):page149_i103" )
			)
			( gate "C25W24"
				( objectStatus "@baseboard_fab2_lib.baseboard_fab2(sch_1):page149_i104" )
			)
			( gate "C25W25"
				( objectStatus "@baseboard_fab2_lib.baseboard_fab2(sch_1):page149_i105" )
			)
			( gate "C25W26"
				( objectStatus "@baseboard_fab2_lib.baseboard_fab2(sch_1):page149_i106" )
			)
			( gate "C25W27"
				( objectStatus "@baseboard_fab2_lib.baseboard_fab2(sch_1):page149_i107" )
			)
			( gate "C25W28"
				( objectStatus "@baseboard_fab2_lib.baseboard_fab2(sch_1):page149_i108" )
			)
			( gate "C25W60"
				( objectStatus "@baseboard_fab2_lib.baseboard_fab2(sch_1):page149_i109" )
			)
			( gate "C25W35"
				( objectStatus "@baseboard_fab2_lib.baseboard_fab2(sch_1):page149_i110" )
			)
			( gate "C25W48"
				( objectStatus "@baseboard_fab2_lib.baseboard_fab2(sch_1):page149_i112" )
			)
			( gate "C25W37"
				( objectStatus "@baseboard_fab2_lib.baseboard_fab2(sch_1):page149_i113" )
			)
			( gate "C25W51"
				( objectStatus "@baseboard_fab2_lib.baseboard_fab2(sch_1):page149_i114" )
			)
			( gate "C25W71"
				( objectStatus "@baseboard_fab2_lib.baseboard_fab2(sch_1):page149_i115" )
			)
			( gate "C25W66"
				( objectStatus "@baseboard_fab2_lib.baseboard_fab2(sch_1):page149_i116" )
			)
			( gate "C25W67"
				( objectStatus "@baseboard_fab2_lib.baseboard_fab2(sch_1):page149_i117" )
			)
			( gate "C25W52"
				( objectStatus "@baseboard_fab2_lib.baseboard_fab2(sch_1):page149_i118" )
			)
			( gate "R1W10"
				( objectStatus "@baseboard_fab2_lib.baseboard_fab2(sch_1):page176_i132" )
			)
			( gate "R1W11"
				( objectStatus "@baseboard_fab2_lib.baseboard_fab2(sch_1):page176_i133" )
			)
			( gate "R1W12"
				( objectStatus "@baseboard_fab2_lib.baseboard_fab2(sch_1):page176_i137" )
			)
			( gate "R1W13"
				( objectStatus "@baseboard_fab2_lib.baseboard_fab2(sch_1):page176_i138" )
			)
			( gate "R3W3"
				( objectStatus "@baseboard_fab2_lib.baseboard_fab2(sch_1):page249_i36" )
			)
			( gate "U10W1"
				( objectStatus "@baseboard_fab2_lib.baseboard_fab2(sch_1):page251_i19" )
			)
			( gate "C10W3"
				( objectStatus "@baseboard_fab2_lib.baseboard_fab2(sch_1):page251_i16" )
			)
			( gate "R10W2"
				( objectStatus "@baseboard_fab2_lib.baseboard_fab2(sch_1):page251_i15" )
			)
			( gate "R10W4"
				( objectStatus "@baseboard_fab2_lib.baseboard_fab2(sch_1):page251_i14" )
			)
			( gate "R10W1"
				( objectStatus "@baseboard_fab2_lib.baseboard_fab2(sch_1):page251_i13" )
			)
			( gate "CR10W1"
				( objectStatus "@baseboard_fab2_lib.baseboard_fab2(sch_1):page251_i12" )
			)
			( gate "R10W3"
				( objectStatus "@baseboard_fab2_lib.baseboard_fab2(sch_1):page251_i11" )
			)
			( gate "R10W5"
				( objectStatus "@baseboard_fab2_lib.baseboard_fab2(sch_1):page251_i5" )
			)
			( gate "C10W1"
				( objectStatus "@baseboard_fab2_lib.baseboard_fab2(sch_1):page251_i3" )
			)
			( gate "C10W2"
				( objectStatus "@baseboard_fab2_lib.baseboard_fab2(sch_1):page251_i1" )
			)
			( gate "U2R1"
				( objectStatus "@baseboard_fab2_lib.baseboard_fab2(sch_1):page157_i390" )
			)
			( gate "R2R10"
				( objectStatus "@baseboard_fab2_lib.baseboard_fab2(sch_1):page157_i391" )
			)
			( gate "R9A9"
				( objectStatus "@baseboard_fab2_lib.baseboard_fab2(sch_1):page175_i95" )
			)
			( gate "U9A4"
				( objectStatus "@baseboard_fab2_lib.baseboard_fab2(sch_1):page175_i97" )
			)
			( gate "R1U18"
				( objectStatus "@baseboard_fab2_lib.baseboard_fab2(sch_1):page164_i40" )
			)
			( gate "U8F3"
				( objectStatus "@baseboard_fab2_lib.baseboard_fab2(sch_1):page156_i340" )
			)
			( gate "U8G1"
				( objectStatus "@baseboard_fab2_lib.baseboard_fab2(sch_1):page156_i342" )
			)
			( gate "C25W57"
				( objectStatus "@baseboard_fab2_lib.baseboard_fab2(sch_1):page149_i130" )
			)
			( gate "R9F34"
				( objectStatus "@baseboard_fab2_lib.baseboard_fab2(sch_1):page151_i209" )
			)
			( gate "C10W4"
				( objectStatus "@baseboard_fab2_lib.baseboard_fab2(sch_1):page251_i21" )
			)
			( gate "R1W14"
				( objectStatus "@baseboard_fab2_lib.baseboard_fab2(sch_1):page115_i118" )
			)
			( gate "R1W15"
				( objectStatus "@baseboard_fab2_lib.baseboard_fab2(sch_1):page115_i119" )
			)
			( gate "R1W17"
				( objectStatus "@baseboard_fab2_lib.baseboard_fab2(sch_1):page115_i120" )
			)
			( gate "R1W16"
				( objectStatus "@baseboard_fab2_lib.baseboard_fab2(sch_1):page115_i121" )
			)
			( gate "R1W19"
				( objectStatus "@baseboard_fab2_lib.baseboard_fab2(sch_1):page115_i122" )
			)
			( gate "R1W18"
				( objectStatus "@baseboard_fab2_lib.baseboard_fab2(sch_1):page115_i123" )
			)
			( gate "R25W123"
				( objectStatus "@baseboard_fab2_lib.baseboard_fab2(sch_1):page144_i139" )
			)
			( gate "R25W124"
				( objectStatus "@baseboard_fab2_lib.baseboard_fab2(sch_1):page144_i140" )
			)
			( gate "R25W125"
				( objectStatus "@baseboard_fab2_lib.baseboard_fab2(sch_1):page144_i141" )
			)
			( gate "C25W72"
				( objectStatus "@baseboard_fab2_lib.baseboard_fab2(sch_1):page255_i7" )
			)
			( gate "C25W73"
				( objectStatus "@baseboard_fab2_lib.baseboard_fab2(sch_1):page255_i11" )
			)
			( gate "C25W74"
				( objectStatus "@baseboard_fab2_lib.baseboard_fab2(sch_1):page255_i12" )
			)
			( gate "C25W77"
				( objectStatus "@baseboard_fab2_lib.baseboard_fab2(sch_1):page255_i16" )
			)
			( gate "C25W76"
				( objectStatus "@baseboard_fab2_lib.baseboard_fab2(sch_1):page255_i18" )
			)
			( gate "C25W75"
				( objectStatus "@baseboard_fab2_lib.baseboard_fab2(sch_1):page255_i21" )
			)
			( gate "R25W128"
				( objectStatus "@baseboard_fab2_lib.baseboard_fab2(sch_1):page255_i22" )
			)
			( gate "R25W127"
				( objectStatus "@baseboard_fab2_lib.baseboard_fab2(sch_1):page255_i24" )
			)
			( gate "R25W126"
				( objectStatus "@baseboard_fab2_lib.baseboard_fab2(sch_1):page255_i26" )
			)
			( gate "R25W129"
				( objectStatus "@baseboard_fab2_lib.baseboard_fab2(sch_1):page146_i152" )
			)
			( gate "R25W130"
				( objectStatus "@baseboard_fab2_lib.baseboard_fab2(sch_1):page146_i153" )
			)
			( gate "R25W131"
				( objectStatus "@baseboard_fab2_lib.baseboard_fab2(sch_1):page255_i30" )
			)
			( gate "R25W132"
				( objectStatus "@baseboard_fab2_lib.baseboard_fab2(sch_1):page255_i31" )
			)
			( gate "R25W133"
				( objectStatus "@baseboard_fab2_lib.baseboard_fab2(sch_1):page255_i34" )
			)
			( gate "C25W78"
				( objectStatus "@baseboard_fab2_lib.baseboard_fab2(sch_1):page255_i35" )
			)
			( gate "R25W136"
				( objectStatus "@baseboard_fab2_lib.baseboard_fab2(sch_1):page255_i38" )
			)
			( gate "C25W79"
				( objectStatus "@baseboard_fab2_lib.baseboard_fab2(sch_1):page255_i39" )
			)
			( gate "R25W134"
				( objectStatus "@baseboard_fab2_lib.baseboard_fab2(sch_1):page255_i43" )
			)
			( gate "R25W135"
				( objectStatus "@baseboard_fab2_lib.baseboard_fab2(sch_1):page255_i44" )
			)
			( gate "R6W49"
				( objectStatus "@baseboard_fab2_lib.baseboard_fab2(sch_1):page168_i48" )
			)
			( gate "R9P15"
				( objectStatus "@baseboard_fab2_lib.baseboard_fab2(sch_1):page200_i243" )
			)
			( gate "R1D10"
				( objectStatus "@baseboard_fab2_lib.baseboard_fab2(sch_1):page200_i244" )
			)
			( gate "JA9G1"
				( objectStatus "@baseboard_fab2_lib.baseboard_fab2(sch_1):page141_i129" )
			)
			( gate "F9B1"
				( objectStatus "@baseboard_fab2_lib.baseboard_fab2(sch_1):page172_i66" )
			)
			( gate "R25W138"
				( objectStatus "@baseboard_fab2_lib.baseboard_fab2(sch_1):page255_i49" )
			)
			( gate "C25W81"
				( objectStatus "@baseboard_fab2_lib.baseboard_fab2(sch_1):page255_i60" )
			)
			( gate "R25W139"
				( objectStatus "@baseboard_fab2_lib.baseboard_fab2(sch_1):page255_i59" )
			)
			( gate "C25W82"
				( objectStatus "@baseboard_fab2_lib.baseboard_fab2(sch_1):page255_i62" )
			)
			( gate "C25P83"
				( objectStatus "@baseboard_fab2_lib.baseboard_fab2(sch_1):page255_i74" )
			)
			( gate "L25W1"
				( objectStatus "@baseboard_fab2_lib.baseboard_fab2(sch_1):page255_i76" )
			)
			( gate "L25W2"
				( objectStatus "@baseboard_fab2_lib.baseboard_fab2(sch_1):page255_i77" )
			)
			( gate "L25W3"
				( objectStatus "@baseboard_fab2_lib.baseboard_fab2(sch_1):page255_i78" )
			)
			( gate "U1B2"
				( objectStatus "@baseboard_fab2_lib.baseboard_fab2(sch_1):page163_i28" )
			)
			( gate "U6W2"
				( objectStatus "@baseboard_fab2_lib.baseboard_fab2(sch_1):page247_i118" )
			)
			( gate "U1W2"
				( objectStatus "@baseboard_fab2_lib.baseboard_fab2(sch_1):page248_i49" )
			)
			( gate "C2M4"
				( objectStatus "@baseboard_fab2_lib.baseboard_fab2(sch_1):page116_i238" )
			)
			( gate "C2M3"
				( objectStatus "@baseboard_fab2_lib.baseboard_fab2(sch_1):page116_i239" )
			)
			( gate "R7C4"
				( objectStatus "@baseboard_fab2_lib.baseboard_fab2(sch_1):page114_i191" )
			)
			( gate "R7C2"
				( objectStatus "@baseboard_fab2_lib.baseboard_fab2(sch_1):page114_i192" )
			)
			( gate "R8D16"
				( objectStatus "@baseboard_fab2_lib.baseboard_fab2(sch_1):page125_i85" )
			)
			( gate "R7D1"
				( objectStatus "@baseboard_fab2_lib.baseboard_fab2(sch_1):page125_i86" )
			)
			( gate "RT27"
				( objectStatus "@baseboard_fab2_lib.baseboard_fab2(sch_1):page203_i135" )
			)
			( gate "RT26"
				( objectStatus "@baseboard_fab2_lib.baseboard_fab2(sch_1):page203_i134" )
			)
			( gate "C22W2"
				( objectStatus "@baseboard_fab2_lib.baseboard_fab2(sch_1):page225_i247" )
			)
			( gate "C22W4"
				( objectStatus "@baseboard_fab2_lib.baseboard_fab2(sch_1):page225_i251" )
			)
			( gate "R6W50"
				( objectStatus "@baseboard_fab2_lib.baseboard_fab2(sch_1):page176_i178" )
			)
			( gate "C4G5"
				( objectStatus "@baseboard_fab2_lib.baseboard_fab2(sch_1):page233_i280" )
			)
			( gate "C22W7"
				( objectStatus "@baseboard_fab2_lib.baseboard_fab2(sch_1):page232_i311" )
			)
			( gate "C22W9"
				( objectStatus "@baseboard_fab2_lib.baseboard_fab2(sch_1):page241_i95" )
			)
			( gate "C22W8"
				( objectStatus "@baseboard_fab2_lib.baseboard_fab2(sch_1):page241_i96" )
			)
			( gate "C7E12"
				( objectStatus "@baseboard_fab2_lib.baseboard_fab2(sch_1):page241_i98" )
			)
			( gate "C9F1"
				( objectStatus "@baseboard_fab2_lib.baseboard_fab2(sch_1):page240_i181" )
			)
			( gate "C22W10"
				( objectStatus "@baseboard_fab2_lib.baseboard_fab2(sch_1):page231_i225" )
			)
			( gate "C7F7"
				( objectStatus "@baseboard_fab2_lib.baseboard_fab2(sch_1):page231_i226" )
			)
			( gate "C22W12"
				( objectStatus "@baseboard_fab2_lib.baseboard_fab2(sch_1):page240_i186" )
			)
			( gate "C22W14"
				( objectStatus "@baseboard_fab2_lib.baseboard_fab2(sch_1):page214_i152" )
			)
			( gate "C22W15"
				( objectStatus "@baseboard_fab2_lib.baseboard_fab2(sch_1):page214_i154" )
			)
			( gate "C22W18"
				( objectStatus "@baseboard_fab2_lib.baseboard_fab2(sch_1):page214_i156" )
			)
			( gate "C22W17"
				( objectStatus "@baseboard_fab2_lib.baseboard_fab2(sch_1):page214_i158" )
			)
			( gate "C22W16"
				( objectStatus "@baseboard_fab2_lib.baseboard_fab2(sch_1):page214_i160" )
			)
			( gate "C4E8"
				( objectStatus "@baseboard_fab2_lib.baseboard_fab2(sch_1):page214_i161" )
			)
			( gate "C4E9"
				( objectStatus "@baseboard_fab2_lib.baseboard_fab2(sch_1):page214_i164" )
			)
			( gate "C22W21"
				( objectStatus "@baseboard_fab2_lib.baseboard_fab2(sch_1):page214_i166" )
			)
			( gate "C22W20"
				( objectStatus "@baseboard_fab2_lib.baseboard_fab2(sch_1):page214_i168" )
			)
			( gate "C22W19"
				( objectStatus "@baseboard_fab2_lib.baseboard_fab2(sch_1):page214_i169" )
			)
			( gate "C22W25"
				( objectStatus "@baseboard_fab2_lib.baseboard_fab2(sch_1):page236_i162" )
			)
			( gate "C22W27"
				( objectStatus "@baseboard_fab2_lib.baseboard_fab2(sch_1):page236_i163" )
			)
			( gate "C22W26"
				( objectStatus "@baseboard_fab2_lib.baseboard_fab2(sch_1):page236_i165" )
			)
			( gate "C22W22"
				( objectStatus "@baseboard_fab2_lib.baseboard_fab2(sch_1):page236_i171" )
			)
			( gate "C7A14"
				( objectStatus "@baseboard_fab2_lib.baseboard_fab2(sch_1):page236_i172" )
			)
			( gate "C22W31"
				( objectStatus "@baseboard_fab2_lib.baseboard_fab2(sch_1):page212_i129" )
			)
			( gate "C7C8"
				( objectStatus "@baseboard_fab2_lib.baseboard_fab2(sch_1):page212_i130" )
			)
			( gate "C22W30"
				( objectStatus "@baseboard_fab2_lib.baseboard_fab2(sch_1):page212_i132" )
			)
			( gate "C22W29"
				( objectStatus "@baseboard_fab2_lib.baseboard_fab2(sch_1):page212_i134" )
			)
			( gate "C22W28"
				( objectStatus "@baseboard_fab2_lib.baseboard_fab2(sch_1):page212_i136" )
			)
			( gate "C7C7"
				( objectStatus "@baseboard_fab2_lib.baseboard_fab2(sch_1):page212_i138" )
			)
			( gate "R8D13"
				( objectStatus "@baseboard_fab2_lib.baseboard_fab2(sch_1):page125_i87" )
			)
			( gate "C22W34"
				( objectStatus "@baseboard_fab2_lib.baseboard_fab2(sch_1):page139_i244" )
			)
			( gate "C9F2"
				( objectStatus "@baseboard_fab2_lib.baseboard_fab2(sch_1):page139_i245" )
			)
			( gate "C22W35"
				( objectStatus "@baseboard_fab2_lib.baseboard_fab2(sch_1):page139_i246" )
			)
			( gate "C9E6"
				( objectStatus "@baseboard_fab2_lib.baseboard_fab2(sch_1):page139_i248" )
			)
			( gate "R2N10"
				( objectStatus "@baseboard_fab2_lib.baseboard_fab2(sch_1):page126_i27" )
			)
			( gate "Q1W1"
				( objectStatus "@baseboard_fab2_lib.baseboard_fab2(sch_1):page250_i29" )
			)
			( gate "R12W10"
				( objectStatus "@baseboard_fab2_lib.baseboard_fab2(sch_1):page197_i109" )
			)
			( gate "U6W1"
				( objectStatus "@baseboard_fab2_lib.baseboard_fab2(sch_1):page247_i120" )
			)
			( gate "C6W10"
				( objectStatus "@baseboard_fab2_lib.baseboard_fab2(sch_1):page176_i139" )
			)
			( gate "R7P14"
				( objectStatus "@baseboard_fab2_lib.baseboard_fab2(sch_1):page90_i100" )
			)
			( gate "R5D4"
				( objectStatus "@baseboard_fab2_lib.baseboard_fab2(sch_1):page90_i96" )
			)
			( gate "R1D14"
				( objectStatus "@baseboard_fab2_lib.baseboard_fab2(sch_1):page200_i246" )
			)
			( gate "Q25W4"
				( objectStatus "@baseboard_fab2_lib.baseboard_fab2(sch_1):page255_i95" )
			)
			( gate "Q25W4"
				( objectStatus "@baseboard_fab2_lib.baseboard_fab2(sch_1):page255_i96" )
			)
			( gate "R5W2"
				( objectStatus "@baseboard_fab2_lib.baseboard_fab2(sch_1):page113_i273" )
			)
			( gate "R5W1"
				( objectStatus "@baseboard_fab2_lib.baseboard_fab2(sch_1):page113_i272" )
			)
			( gate "R6M8"
				( objectStatus "@baseboard_fab2_lib.baseboard_fab2(sch_1):page113_i271" )
			)
			( gate "R4R6"
				( objectStatus "@baseboard_fab2_lib.baseboard_fab2(sch_1):page113_i270" )
			)
			( gate "R7W1"
				( objectStatus "@baseboard_fab2_lib.baseboard_fab2(sch_1):page118_i167" )
			)
			( gate "J1B4"
				( objectStatus "@baseboard_fab2_lib.baseboard_fab2(sch_1):page199_i131" )
			)
			( gate "CR30W1"
				( objectStatus "@baseboard_fab2_lib.baseboard_fab2(sch_1):page253_i5" )
			)
			( gate "L30W2"
				( objectStatus "@baseboard_fab2_lib.baseboard_fab2(sch_1):page253_i11" )
			)
			( gate "R30W2"
				( objectStatus "@baseboard_fab2_lib.baseboard_fab2(sch_1):page253_i12" )
			)
			( gate "R30W1"
				( objectStatus "@baseboard_fab2_lib.baseboard_fab2(sch_1):page253_i13" )
			)
			( gate "R30W4"
				( objectStatus "@baseboard_fab2_lib.baseboard_fab2(sch_1):page253_i14" )
			)
			( gate "R30W3"
				( objectStatus "@baseboard_fab2_lib.baseboard_fab2(sch_1):page253_i15" )
			)
			( gate "L30W1"
				( objectStatus "@baseboard_fab2_lib.baseboard_fab2(sch_1):page253_i16" )
			)
			( gate "C30W2"
				( objectStatus "@baseboard_fab2_lib.baseboard_fab2(sch_1):page253_i19" )
			)
			( gate "C30W1"
				( objectStatus "@baseboard_fab2_lib.baseboard_fab2(sch_1):page253_i20" )
			)
			( gate "U25W7"
				( objectStatus "@baseboard_fab2_lib.baseboard_fab2(sch_1):page255_i111" )
			)
			( gate "U25W8"
				( objectStatus "@baseboard_fab2_lib.baseboard_fab2(sch_1):page255_i112" )
			)
			( gate "C25W90"
				( objectStatus "@baseboard_fab2_lib.baseboard_fab2(sch_1):page255_i118" )
			)
			( gate "D25W8"
				( objectStatus "@baseboard_fab2_lib.baseboard_fab2(sch_1):page255_i128" )
			)
			( gate "CR25W1"
				( objectStatus "@baseboard_fab2_lib.baseboard_fab2(sch_1):page255_i129" )
			)
			( gate "CR25W2"
				( objectStatus "@baseboard_fab2_lib.baseboard_fab2(sch_1):page255_i131" )
			)
			( gate "C25P80"
				( objectStatus "@baseboard_fab2_lib.baseboard_fab2(sch_1):page255_i134" )
			)
			( gate "C1W16"
				( objectStatus "@baseboard_fab2_lib.baseboard_fab2(sch_1):page199_i132" )
			)
			( gate "R1W20"
				( objectStatus "@baseboard_fab2_lib.baseboard_fab2(sch_1):page199_i134" )
			)
			( gate "R1W21"
				( objectStatus "@baseboard_fab2_lib.baseboard_fab2(sch_1):page199_i135" )
			)
			( gate "R9F55"
				( objectStatus "@baseboard_fab2_lib.baseboard_fab2(sch_1):page183_i3" )
			)
			( gate "R25W121"
				( objectStatus "@baseboard_fab2_lib.baseboard_fab2(sch_1):page145_i163" )
			)
			( gate "R25W122"
				( objectStatus "@baseboard_fab2_lib.baseboard_fab2(sch_1):page145_i164" )
			)
			( gate "J2W1"
				( objectStatus "@baseboard_fab2_lib.baseboard_fab2(sch_1):page172_i67" )
			)
			( gate "J2W2"
				( objectStatus "@baseboard_fab2_lib.baseboard_fab2(sch_1):page172_i68" )
			)
			( gate "R9G2"
				( objectStatus "@baseboard_fab2_lib.baseboard_fab2(sch_1):page141_i134" )
			)
			( gate "R9G3"
				( objectStatus "@baseboard_fab2_lib.baseboard_fab2(sch_1):page141_i135" )
			)
			( gate "C9G3"
				( objectStatus "@baseboard_fab2_lib.baseboard_fab2(sch_1):page141_i138" )
			)
			( gate "C9G1"
				( objectStatus "@baseboard_fab2_lib.baseboard_fab2(sch_1):page141_i140" )
			)
			( gate "C9G2"
				( objectStatus "@baseboard_fab2_lib.baseboard_fab2(sch_1):page141_i152" )
			)
			( gate "R9G4"
				( objectStatus "@baseboard_fab2_lib.baseboard_fab2(sch_1):page141_i156" )
			)
			( gate "R9G1"
				( objectStatus "@baseboard_fab2_lib.baseboard_fab2(sch_1):page141_i157" )
			)
			( gate "C9F22"
				( objectStatus "@baseboard_fab2_lib.baseboard_fab2(sch_1):page141_i159" )
			)
			( gate "L4E1"
				( objectStatus "@baseboard_fab2_lib.baseboard_fab2(sch_1):page202_i109" )
			)
			( gate "L4D1"
				( objectStatus "@baseboard_fab2_lib.baseboard_fab2(sch_1):page203_i131" )
			)
			( gate "L1D2"
				( objectStatus "@baseboard_fab2_lib.baseboard_fab2(sch_1):page208_i116" )
			)
			( gate "L1D1"
				( objectStatus "@baseboard_fab2_lib.baseboard_fab2(sch_1):page208_i117" )
			)
			( gate "C4A14"
				( objectStatus "@baseboard_fab2_lib.baseboard_fab2(sch_1):page230_i36" )
			)
			( gate "C6L5"
				( objectStatus "@baseboard_fab2_lib.baseboard_fab2(sch_1):page230_i35" )
			)
			( gate "R4A4"
				( objectStatus "@baseboard_fab2_lib.baseboard_fab2(sch_1):page230_i32" )
			)
			( gate "C8M12"
				( objectStatus "@baseboard_fab2_lib.baseboard_fab2(sch_1):page230_i24" )
			)
			( gate "C4A3"
				( objectStatus "@baseboard_fab2_lib.baseboard_fab2(sch_1):page230_i23" )
			)
			( gate "J25W1"
				( objectStatus "@baseboard_fab2_lib.baseboard_fab2(sch_1):page255_i136" )
			)
			( gate "F8B1"
				( objectStatus "@baseboard_fab2_lib.baseboard_fab2(sch_1):page172_i71" )
			)
			( gate "C8F14"
				( objectStatus "@baseboard_fab2_lib.baseboard_fab2(sch_1):page240_i189" )
			)
			( gate "R25W143"
				( objectStatus "@baseboard_fab2_lib.baseboard_fab2(sch_1):page147_i159" )
			)
			( gate "L8F1"
				( objectStatus "@baseboard_fab2_lib.baseboard_fab2(sch_1):page240_i188" )
			)
			( gate "C8F8"
				( objectStatus "@baseboard_fab2_lib.baseboard_fab2(sch_1):page240_i190" )
			)
			( gate "J8F1"
				( objectStatus "@baseboard_fab2_lib.baseboard_fab2(sch_1):page185_i143" )
			)
			( gate "C2T11"
				( objectStatus "@baseboard_fab2_lib.baseboard_fab2(sch_1):page185_i167" )
			)
			( gate "C2T10"
				( objectStatus "@baseboard_fab2_lib.baseboard_fab2(sch_1):page185_i168" )
			)
			( gate "R1W22"
				( objectStatus "@baseboard_fab2_lib.baseboard_fab2(sch_1):page101_i134" )
			)
			( gate "R1W23"
				( objectStatus "@baseboard_fab2_lib.baseboard_fab2(sch_1):page101_i135" )
			)
			( gate "R1W24"
				( objectStatus "@baseboard_fab2_lib.baseboard_fab2(sch_1):page101_i138" )
			)
			( gate "C1W17"
				( objectStatus "@baseboard_fab2_lib.baseboard_fab2(sch_1):page101_i139" )
			)
			( gate "R1W25"
				( objectStatus "@baseboard_fab2_lib.baseboard_fab2(sch_1):page101_i140" )
			)
			( gate "CR10W3"
				( objectStatus "@baseboard_fab2_lib.baseboard_fab2(sch_1):page251_i26" )
			)
			( gate "R8F27"
				( objectStatus "@baseboard_fab2_lib.baseboard_fab2(sch_1):page101_i142" )
			)
			( gate "R8G25"
				( objectStatus "@baseboard_fab2_lib.baseboard_fab2(sch_1):page101_i144" )
			)
			( gate "R8G1"
				( objectStatus "@baseboard_fab2_lib.baseboard_fab2(sch_1):page101_i145" )
			)
			( gate "R25W148"
				( objectStatus "@baseboard_fab2_lib.baseboard_fab2(sch_1):page150_i216" )
			)
			( gate "R1W26"
				( objectStatus "@baseboard_fab2_lib.baseboard_fab2(sch_1):page190_i349" )
			)
			( gate "R4E4"
				( objectStatus "@baseboard_fab2_lib.baseboard_fab2(sch_1):page201_i187" )
			)
			( gate "R8W2"
				( objectStatus "@baseboard_fab2_lib.baseboard_fab2(sch_1):page235_i247" )
			)
			( gate "R8W3"
				( objectStatus "@baseboard_fab2_lib.baseboard_fab2(sch_1):page235_i248" )
			)
			( gate "R7F8"
				( objectStatus "@baseboard_fab2_lib.baseboard_fab2(sch_1):page231_i229" )
			)
			( gate "R1W27"
				( objectStatus "@baseboard_fab2_lib.baseboard_fab2(sch_1):page190_i351" )
			)
			( gate "R25W144"
				( objectStatus "@baseboard_fab2_lib.baseboard_fab2(sch_1):page145_i173" )
			)
			( gate "R1W28"
				( objectStatus "@baseboard_fab2_lib.baseboard_fab2(sch_1):page191_i197" )
			)
			( gate "R25W145"
				( objectStatus "@baseboard_fab2_lib.baseboard_fab2(sch_1):page145_i175" )
			)
			( gate "R1W29"
				( objectStatus "@baseboard_fab2_lib.baseboard_fab2(sch_1):page191_i198" )
			)
			( gate "R1W30"
				( objectStatus "@baseboard_fab2_lib.baseboard_fab2(sch_1):page118_i168" )
			)
			( gate "R25W105"
				( objectStatus "@baseboard_fab2_lib.baseboard_fab2(sch_1):page150_i196" )
			)
			( gate "R8F13"
				( objectStatus "@baseboard_fab2_lib.baseboard_fab2(sch_1):page162_i35" )
			)
			( gate "R25W146"
				( objectStatus "@baseboard_fab2_lib.baseboard_fab2(sch_1):page150_i199" )
			)
			( gate "R25W98"
				( objectStatus "@baseboard_fab2_lib.baseboard_fab2(sch_1):page150_i209" )
			)
			( gate "R25W99"
				( objectStatus "@baseboard_fab2_lib.baseboard_fab2(sch_1):page150_i210" )
			)
			( gate "R25W100"
				( objectStatus "@baseboard_fab2_lib.baseboard_fab2(sch_1):page150_i211" )
			)
			( gate "R25W140"
				( objectStatus "@baseboard_fab2_lib.baseboard_fab2(sch_1):page144_i148" )
			)
			( gate "R25W103"
				( objectStatus "@baseboard_fab2_lib.baseboard_fab2(sch_1):page150_i214" )
			)
			( gate "R25W104"
				( objectStatus "@baseboard_fab2_lib.baseboard_fab2(sch_1):page150_i215" )
			)
			( gate "R25W114"
				( objectStatus "@baseboard_fab2_lib.baseboard_fab2(sch_1):page150_i218" )
			)
			( gate "R25W149"
				( objectStatus "@baseboard_fab2_lib.baseboard_fab2(sch_1):page150_i219" )
			)
			( gate "R9P28"
				( objectStatus "@baseboard_fab2_lib.baseboard_fab2(sch_1):page199_i138" )
			)
			( gate "R25W150"
				( objectStatus "@baseboard_fab2_lib.baseboard_fab2(sch_1):page150_i229" )
			)
			( gate "R25W110"
				( objectStatus "@baseboard_fab2_lib.baseboard_fab2(sch_1):page150_i233" )
			)
			( gate "R25W152"
				( objectStatus "@baseboard_fab2_lib.baseboard_fab2(sch_1):page150_i234" )
			)
			( gate "R25W109"
				( objectStatus "@baseboard_fab2_lib.baseboard_fab2(sch_1):page150_i236" )
			)
			( gate "R25W119"
				( objectStatus "@baseboard_fab2_lib.baseboard_fab2(sch_1):page151_i210" )
			)
			( gate "U25W9"
				( objectStatus "@baseboard_fab2_lib.baseboard_fab2(sch_1):page157_i394" )
			)
			( gate "R25W153"
				( objectStatus "@baseboard_fab2_lib.baseboard_fab2(sch_1):page157_i396" )
			)
			( gate "R8B24"
				( objectStatus "@baseboard_fab2_lib.baseboard_fab2(sch_1):page138_i186" )
			)
			( gate "R8B26"
				( objectStatus "@baseboard_fab2_lib.baseboard_fab2(sch_1):page138_i187" )
			)
			( gate "J1E1"
				( objectStatus "@baseboard_fab2_lib.baseboard_fab2(sch_1):page195_i114" )
			)
			( gate "J1D1"
				( objectStatus "@baseboard_fab2_lib.baseboard_fab2(sch_1):page195_i115" )
			)
			( gate "J30W1"
				( objectStatus "@baseboard_fab2_lib.baseboard_fab2(sch_1):page253_i26" )
			)
			( gate "C4A13"
				( objectStatus "@baseboard_fab2_lib.baseboard_fab2(sch_1):page230_i20" )
			)
			( gate "R6L8"
				( objectStatus "@baseboard_fab2_lib.baseboard_fab2(sch_1):page230_i13" )
			)
			( gate "C4A8"
				( objectStatus "@baseboard_fab2_lib.baseboard_fab2(sch_1):page230_i12" )
			)
			( gate "C4A7"
				( objectStatus "@baseboard_fab2_lib.baseboard_fab2(sch_1):page230_i10" )
			)
			( gate "R6L6"
				( objectStatus "@baseboard_fab2_lib.baseboard_fab2(sch_1):page230_i6" )
			)
			( gate "R6L5"
				( objectStatus "@baseboard_fab2_lib.baseboard_fab2(sch_1):page230_i5" )
			)
			( gate "R4A3"
				( objectStatus "@baseboard_fab2_lib.baseboard_fab2(sch_1):page230_i4" )
			)
			( gate "C4A6"
				( objectStatus "@baseboard_fab2_lib.baseboard_fab2(sch_1):page230_i2" )
			)
			( gate "R4E9"
				( objectStatus "@baseboard_fab2_lib.baseboard_fab2(sch_1):page201_i189" )
			)
			( gate "R3N15"
				( objectStatus "@baseboard_fab2_lib.baseboard_fab2(sch_1):page133_i368" )
			)
			( gate "R3N16"
				( objectStatus "@baseboard_fab2_lib.baseboard_fab2(sch_1):page133_i369" )
			)
			( gate "R3P5"
				( objectStatus "@baseboard_fab2_lib.baseboard_fab2(sch_1):page133_i366" )
			)
			( gate "R3P6"
				( objectStatus "@baseboard_fab2_lib.baseboard_fab2(sch_1):page133_i367" )
			)
			( gate "C9N12"
				( objectStatus "@baseboard_fab2_lib.baseboard_fab2(sch_1):page182_i37" )
			)
			( gate "C9N2"
				( objectStatus "@baseboard_fab2_lib.baseboard_fab2(sch_1):page182_i36" )
			)
			( gate "R1C11"
				( objectStatus "@baseboard_fab2_lib.baseboard_fab2(sch_1):page182_i10" )
			)
			( gate "R1C10"
				( objectStatus "@baseboard_fab2_lib.baseboard_fab2(sch_1):page182_i9" )
			)
			( gate "R1C9"
				( objectStatus "@baseboard_fab2_lib.baseboard_fab2(sch_1):page182_i8" )
			)
			( gate "R1F9"
				( objectStatus "@baseboard_fab2_lib.baseboard_fab2(sch_1):page182_i7" )
			)
			( gate "R1C31"
				( objectStatus "@baseboard_fab2_lib.baseboard_fab2(sch_1):page182_i6" )
			)
			( gate "RN8F1"
				( objectStatus "@baseboard_fab2_lib.baseboard_fab2(sch_1):page137_i142" )
			)
			( gate "R6W2"
				( objectStatus "@baseboard_fab2_lib.baseboard_fab2(sch_1):page137_i144" )
			)
			( gate "C7G4"
				( objectStatus "@baseboard_fab2_lib.baseboard_fab2(sch_1):page215_i14" )
			)
			( gate "RF15"
				( objectStatus "@baseboard_fab2_lib.baseboard_fab2(sch_1):page215_i15" )
			)
			( gate "CF15"
				( objectStatus "@baseboard_fab2_lib.baseboard_fab2(sch_1):page215_i16" )
			)
			( gate "R9M6"
				( objectStatus "@baseboard_fab2_lib.baseboard_fab2(sch_1):page226_i70" )
			)
			( gate "R2L25"
				( objectStatus "@baseboard_fab2_lib.baseboard_fab2(sch_1):page235_i252" )
			)
			( gate "C7G3"
				( objectStatus "@baseboard_fab2_lib.baseboard_fab2(sch_1):page215_i22" )
			)
			( gate "R7A10"
				( objectStatus "@baseboard_fab2_lib.baseboard_fab2(sch_1):page218_i73" )
			)
			( gate "CF16"
				( objectStatus "@baseboard_fab2_lib.baseboard_fab2(sch_1):page215_i26" )
			)
			( gate "RF16"
				( objectStatus "@baseboard_fab2_lib.baseboard_fab2(sch_1):page215_i27" )
			)
			( gate "R7G24"
				( objectStatus "@baseboard_fab2_lib.baseboard_fab2(sch_1):page215_i28" )
			)
			( gate "R7F20"
				( objectStatus "@baseboard_fab2_lib.baseboard_fab2(sch_1):page215_i29" )
			)
			( gate "R3T13"
				( objectStatus "@baseboard_fab2_lib.baseboard_fab2(sch_1):page215_i33" )
			)
			( gate "C7F17"
				( objectStatus "@baseboard_fab2_lib.baseboard_fab2(sch_1):page215_i34" )
			)
			( gate "C7F18"
				( objectStatus "@baseboard_fab2_lib.baseboard_fab2(sch_1):page215_i35" )
			)
			( gate "C7F15"
				( objectStatus "@baseboard_fab2_lib.baseboard_fab2(sch_1):page215_i38" )
			)
			( gate "C7F16"
				( objectStatus "@baseboard_fab2_lib.baseboard_fab2(sch_1):page215_i40" )
			)
			( gate "R7G2"
				( objectStatus "@baseboard_fab2_lib.baseboard_fab2(sch_1):page215_i41" )
			)
			( gate "C7F14"
				( objectStatus "@baseboard_fab2_lib.baseboard_fab2(sch_1):page215_i44" )
			)
			( gate "R12W26"
				( objectStatus "@baseboard_fab2_lib.baseboard_fab2(sch_1):page215_i45" )
			)
			( gate "R12W28"
				( objectStatus "@baseboard_fab2_lib.baseboard_fab2(sch_1):page218_i75" )
			)
			( gate "R7G4"
				( objectStatus "@baseboard_fab2_lib.baseboard_fab2(sch_1):page215_i49" )
			)
			( gate "R7F27"
				( objectStatus "@baseboard_fab2_lib.baseboard_fab2(sch_1):page215_i50" )
			)
			( gate "R7F22"
				( objectStatus "@baseboard_fab2_lib.baseboard_fab2(sch_1):page215_i51" )
			)
			( gate "R7F23"
				( objectStatus "@baseboard_fab2_lib.baseboard_fab2(sch_1):page215_i53" )
			)
			( gate "R12W27"
				( objectStatus "@baseboard_fab2_lib.baseboard_fab2(sch_1):page215_i54" )
			)
			( gate "R7F24"
				( objectStatus "@baseboard_fab2_lib.baseboard_fab2(sch_1):page215_i56" )
			)
			( gate "R7A9"
				( objectStatus "@baseboard_fab2_lib.baseboard_fab2(sch_1):page218_i76" )
			)
			( gate "R3U2"
				( objectStatus "@baseboard_fab2_lib.baseboard_fab2(sch_1):page215_i58" )
			)
			( gate "EU7G1"
				( objectStatus "@baseboard_fab2_lib.baseboard_fab2(sch_1):page215_i69" )
			)
			( gate "R12W19"
				( objectStatus "@baseboard_fab2_lib.baseboard_fab2(sch_1):page197_i37" )
			)
			( gate "C12W3"
				( objectStatus "@baseboard_fab2_lib.baseboard_fab2(sch_1):page197_i42" )
			)
			( gate "Q12W1"
				( objectStatus "@baseboard_fab2_lib.baseboard_fab2(sch_1):page197_i43" )
			)
			( gate "R12W4"
				( objectStatus "@baseboard_fab2_lib.baseboard_fab2(sch_1):page197_i45" )
			)
			( gate "R12W8"
				( objectStatus "@baseboard_fab2_lib.baseboard_fab2(sch_1):page197_i113" )
			)
			( gate "C8F18"
				( objectStatus "@baseboard_fab2_lib.baseboard_fab2(sch_1):page101_i147" )
			)
			( gate "R1F3"
				( objectStatus "@baseboard_fab2_lib.baseboard_fab2(sch_1):page197_i50" )
			)
			( gate "R12W14"
				( objectStatus "@baseboard_fab2_lib.baseboard_fab2(sch_1):page197_i53" )
			)
			( gate "C9T8"
				( objectStatus "@baseboard_fab2_lib.baseboard_fab2(sch_1):page197_i56" )
			)
			( gate "C1A4"
				( objectStatus "@baseboard_fab2_lib.baseboard_fab2(sch_1):page197_i60" )
			)
			( gate "C9U11"
				( objectStatus "@baseboard_fab2_lib.baseboard_fab2(sch_1):page197_i63" )
			)
			( gate "C9U8"
				( objectStatus "@baseboard_fab2_lib.baseboard_fab2(sch_1):page197_i66" )
			)
			( gate "C6U18"
				( objectStatus "@baseboard_fab2_lib.baseboard_fab2(sch_1):page197_i69" )
			)
			( gate "C6T2"
				( objectStatus "@baseboard_fab2_lib.baseboard_fab2(sch_1):page197_i71" )
			)
			( gate "C1B7"
				( objectStatus "@baseboard_fab2_lib.baseboard_fab2(sch_1):page197_i72" )
			)
			( gate "C1A16"
				( objectStatus "@baseboard_fab2_lib.baseboard_fab2(sch_1):page197_i75" )
			)
			( gate "C4B11"
				( objectStatus "@baseboard_fab2_lib.baseboard_fab2(sch_1):page197_i78" )
			)
			( gate "C4A4"
				( objectStatus "@baseboard_fab2_lib.baseboard_fab2(sch_1):page197_i81" )
			)
			( gate "C6U10"
				( objectStatus "@baseboard_fab2_lib.baseboard_fab2(sch_1):page197_i84" )
			)
			( gate "C4A17"
				( objectStatus "@baseboard_fab2_lib.baseboard_fab2(sch_1):page197_i88" )
			)
			( gate "Q12W3"
				( objectStatus "@baseboard_fab2_lib.baseboard_fab2(sch_1):page197_i91" )
			)
			( gate "R9T9"
				( objectStatus "@baseboard_fab2_lib.baseboard_fab2(sch_1):page181_i4" )
			)
			( gate "CR1F4"
				( objectStatus "@baseboard_fab2_lib.baseboard_fab2(sch_1):page181_i5" )
			)
			( gate "R1F8"
				( objectStatus "@baseboard_fab2_lib.baseboard_fab2(sch_1):page181_i22" )
			)
			( gate "R9T1"
				( objectStatus "@baseboard_fab2_lib.baseboard_fab2(sch_1):page181_i26" )
			)
			( gate "R9R12"
				( objectStatus "@baseboard_fab2_lib.baseboard_fab2(sch_1):page181_i27" )
			)
			( gate "R9F63"
				( objectStatus "@baseboard_fab2_lib.baseboard_fab2(sch_1):page181_i28" )
			)
			( gate "R9F64"
				( objectStatus "@baseboard_fab2_lib.baseboard_fab2(sch_1):page181_i29" )
			)
			( gate "R9F70"
				( objectStatus "@baseboard_fab2_lib.baseboard_fab2(sch_1):page181_i30" )
			)
			( gate "R9R10"
				( objectStatus "@baseboard_fab2_lib.baseboard_fab2(sch_1):page181_i31" )
			)
			( gate "R9R9"
				( objectStatus "@baseboard_fab2_lib.baseboard_fab2(sch_1):page181_i32" )
			)
			( gate "R9F67"
				( objectStatus "@baseboard_fab2_lib.baseboard_fab2(sch_1):page181_i33" )
			)
			( gate "C8E1"
				( objectStatus "@baseboard_fab2_lib.baseboard_fab2(sch_1):page181_i34" )
			)
			( gate "CR1F3"
				( objectStatus "@baseboard_fab2_lib.baseboard_fab2(sch_1):page181_i37" )
			)
			( gate "C2R6"
				( objectStatus "@baseboard_fab2_lib.baseboard_fab2(sch_1):page181_i40" )
			)
			( gate "Q9T1"
				( objectStatus "@baseboard_fab2_lib.baseboard_fab2(sch_1):page181_i42" )
			)
			( gate "U8E1"
				( objectStatus "@baseboard_fab2_lib.baseboard_fab2(sch_1):page181_i60" )
			)
			( gate "R8E5"
				( objectStatus "@baseboard_fab2_lib.baseboard_fab2(sch_1):page181_i63" )
			)
			( gate "R9T3"
				( objectStatus "@baseboard_fab2_lib.baseboard_fab2(sch_1):page181_i64" )
			)
			( gate "R9T6"
				( objectStatus "@baseboard_fab2_lib.baseboard_fab2(sch_1):page181_i68" )
			)
			( gate "C1F14"
				( objectStatus "@baseboard_fab2_lib.baseboard_fab2(sch_1):page181_i70" )
			)
			( gate "C1F17"
				( objectStatus "@baseboard_fab2_lib.baseboard_fab2(sch_1):page181_i71" )
			)
			( gate "C1F18"
				( objectStatus "@baseboard_fab2_lib.baseboard_fab2(sch_1):page181_i72" )
			)
			( gate "C1F8"
				( objectStatus "@baseboard_fab2_lib.baseboard_fab2(sch_1):page181_i73" )
			)
			( gate "C1F11"
				( objectStatus "@baseboard_fab2_lib.baseboard_fab2(sch_1):page181_i74" )
			)
			( gate "C1F12"
				( objectStatus "@baseboard_fab2_lib.baseboard_fab2(sch_1):page181_i75" )
			)
			( gate "C1F3"
				( objectStatus "@baseboard_fab2_lib.baseboard_fab2(sch_1):page181_i76" )
			)
			( gate "C1F5"
				( objectStatus "@baseboard_fab2_lib.baseboard_fab2(sch_1):page181_i77" )
			)
			( gate "C1F15"
				( objectStatus "@baseboard_fab2_lib.baseboard_fab2(sch_1):page181_i78" )
			)
			( gate "C1F16"
				( objectStatus "@baseboard_fab2_lib.baseboard_fab2(sch_1):page181_i79" )
			)
			( gate "R7D9"
				( objectStatus "@baseboard_fab2_lib.baseboard_fab2(sch_1):page181_i80" )
			)
			( gate "R3P61"
				( objectStatus "@baseboard_fab2_lib.baseboard_fab2(sch_1):page181_i81" )
			)
			( gate "R7D5"
				( objectStatus "@baseboard_fab2_lib.baseboard_fab2(sch_1):page181_i82" )
			)
			( gate "C1F20"
				( objectStatus "@baseboard_fab2_lib.baseboard_fab2(sch_1):page181_i86" )
			)
			( gate "C1F10"
				( objectStatus "@baseboard_fab2_lib.baseboard_fab2(sch_1):page181_i87" )
			)
			( gate "C1F6"
				( objectStatus "@baseboard_fab2_lib.baseboard_fab2(sch_1):page181_i88" )
			)
			( gate "C1F13"
				( objectStatus "@baseboard_fab2_lib.baseboard_fab2(sch_1):page181_i89" )
			)
			( gate "C1F2"
				( objectStatus "@baseboard_fab2_lib.baseboard_fab2(sch_1):page181_i90" )
			)
			( gate "C1F4"
				( objectStatus "@baseboard_fab2_lib.baseboard_fab2(sch_1):page181_i91" )
			)
			( gate "J1F3"
				( objectStatus "@baseboard_fab2_lib.baseboard_fab2(sch_1):page181_i106" )
			)
			( gate "J1C1"
				( objectStatus "@baseboard_fab2_lib.baseboard_fab2(sch_1):page182_i79" )
			)
			( gate "C8E4"
				( objectStatus "@baseboard_fab2_lib.baseboard_fab2(sch_1):page241_i100" )
			)
			( gate "J1F1"
				( objectStatus "@baseboard_fab2_lib.baseboard_fab2(sch_1):page181_i134" )
			)
			( gate "R2U35"
				( objectStatus "@baseboard_fab2_lib.baseboard_fab2(sch_1):page108_i350" )
			)
			( gate "R2U36"
				( objectStatus "@baseboard_fab2_lib.baseboard_fab2(sch_1):page108_i351" )
			)
			( gate "R24W1"
				( objectStatus "@baseboard_fab2_lib.baseboard_fab2(sch_1):page138_i198" )
			)
			( gate "R24W2"
				( objectStatus "@baseboard_fab2_lib.baseboard_fab2(sch_1):page138_i199" )
			)
			( gate "R1U21"
				( objectStatus "@baseboard_fab2_lib.baseboard_fab2(sch_1):page164_i41" )
			)
			( gate "R1U22"
				( objectStatus "@baseboard_fab2_lib.baseboard_fab2(sch_1):page164_i43" )
			)
			( gate "CN8F1"
				( objectStatus "@baseboard_fab2_lib.baseboard_fab2(sch_1):page246_i21" )
			)
			( gate "C25W11"
				( objectStatus "@baseboard_fab2_lib.baseboard_fab2(sch_1):page151_i214" )
			)
			( gate "C25W38"
				( objectStatus "@baseboard_fab2_lib.baseboard_fab2(sch_1):page149_i121" )
			)
			( gate "C25W45"
				( objectStatus "@baseboard_fab2_lib.baseboard_fab2(sch_1):page149_i122" )
			)
			( gate "C5L3"
				( objectStatus "@baseboard_fab2_lib.baseboard_fab2(sch_1):page220_i310" )
			)
			( gate "C5L1"
				( objectStatus "@baseboard_fab2_lib.baseboard_fab2(sch_1):page220_i309" )
			)
			( gate "C5G20"
				( objectStatus "@baseboard_fab2_lib.baseboard_fab2(sch_1):page217_i329" )
			)
			( gate "C8P2"
				( objectStatus "@baseboard_fab2_lib.baseboard_fab2(sch_1):page228_i303" )
			)
			( gate "C5P1"
				( objectStatus "@baseboard_fab2_lib.baseboard_fab2(sch_1):page220_i320" )
			)
			( gate "C5P2"
				( objectStatus "@baseboard_fab2_lib.baseboard_fab2(sch_1):page220_i319" )
			)
			( gate "R25W155"
				( objectStatus "@baseboard_fab2_lib.baseboard_fab2(sch_1):page148_i29" )
			)
			( gate "R8W7"
				( objectStatus "@baseboard_fab2_lib.baseboard_fab2(sch_1):page138_i202" )
			)
			( gate "R8W6"
				( objectStatus "@baseboard_fab2_lib.baseboard_fab2(sch_1):page138_i205" )
			)
			( gate "R8C15"
				( objectStatus "@baseboard_fab2_lib.baseboard_fab2(sch_1):page159_i235" )
			)
			( gate "R8C16"
				( objectStatus "@baseboard_fab2_lib.baseboard_fab2(sch_1):page159_i237" )
			)
			( gate "C2D45"
				( objectStatus "@baseboard_fab2_lib.baseboard_fab2(sch_1):page225_i261" )
			)
			( gate "C2D3"
				( objectStatus "@baseboard_fab2_lib.baseboard_fab2(sch_1):page228_i256" )
			)
			( gate "C3D1"
				( objectStatus "@baseboard_fab2_lib.baseboard_fab2(sch_1):page228_i255" )
			)
			( gate "RM1G1"
				( objectStatus "@baseboard_fab2_lib.baseboard_fab2(sch_1):page195_i117" )
			)
			( gate "R4E10"
				( objectStatus "@baseboard_fab2_lib.baseboard_fab2(sch_1):page201_i190" )
			)
			( gate "R8W8"
				( objectStatus "@baseboard_fab2_lib.baseboard_fab2(sch_1):page235_i249" )
			)
			( gate "R4W2"
				( objectStatus "@baseboard_fab2_lib.baseboard_fab2(sch_1):page102_i103" )
			)
			( gate "Q4W1"
				( objectStatus "@baseboard_fab2_lib.baseboard_fab2(sch_1):page102_i101" )
			)
			( gate "R4W4"
				( objectStatus "@baseboard_fab2_lib.baseboard_fab2(sch_1):page102_i106" )
			)
			( gate "Q4W2"
				( objectStatus "@baseboard_fab2_lib.baseboard_fab2(sch_1):page102_i112" )
			)
			( gate "R4W6"
				( objectStatus "@baseboard_fab2_lib.baseboard_fab2(sch_1):page102_i109" )
			)
			( gate "R4W5"
				( objectStatus "@baseboard_fab2_lib.baseboard_fab2(sch_1):page102_i114" )
			)
			( gate "R12W1"
				( objectStatus "@baseboard_fab2_lib.baseboard_fab2(sch_1):page197_i101" )
			)
			( gate "R12W11"
				( objectStatus "@baseboard_fab2_lib.baseboard_fab2(sch_1):page197_i118" )
			)
			( gate "C8U1"
				( objectStatus "@baseboard_fab2_lib.baseboard_fab2(sch_1):page225_i319" )
			)
			( gate "C2A8"
				( objectStatus "@baseboard_fab2_lib.baseboard_fab2(sch_1):page228_i309" )
			)
			( gate "C5P44"
				( objectStatus "@baseboard_fab2_lib.baseboard_fab2(sch_1):page217_i324" )
			)
			( gate "C5D54"
				( objectStatus "@baseboard_fab2_lib.baseboard_fab2(sch_1):page217_i279" )
			)
			( gate "C5D55"
				( objectStatus "@baseboard_fab2_lib.baseboard_fab2(sch_1):page217_i280" )
			)
			( gate "C5D56"
				( objectStatus "@baseboard_fab2_lib.baseboard_fab2(sch_1):page217_i281" )
			)
			( gate "C5D57"
				( objectStatus "@baseboard_fab2_lib.baseboard_fab2(sch_1):page217_i282" )
			)
			( gate "C5U6"
				( objectStatus "@baseboard_fab2_lib.baseboard_fab2(sch_1):page217_i287" )
			)
			( gate "C5U7"
				( objectStatus "@baseboard_fab2_lib.baseboard_fab2(sch_1):page217_i288" )
			)
			( gate "C5U8"
				( objectStatus "@baseboard_fab2_lib.baseboard_fab2(sch_1):page217_i289" )
			)
			( gate "C5U9"
				( objectStatus "@baseboard_fab2_lib.baseboard_fab2(sch_1):page217_i290" )
			)
			( gate "C5T12"
				( objectStatus "@baseboard_fab2_lib.baseboard_fab2(sch_1):page217_i291" )
			)
			( gate "C5T11"
				( objectStatus "@baseboard_fab2_lib.baseboard_fab2(sch_1):page217_i292" )
			)
			( gate "C5T10"
				( objectStatus "@baseboard_fab2_lib.baseboard_fab2(sch_1):page217_i293" )
			)
			( gate "C5T9"
				( objectStatus "@baseboard_fab2_lib.baseboard_fab2(sch_1):page217_i294" )
			)
			( gate "C5T8"
				( objectStatus "@baseboard_fab2_lib.baseboard_fab2(sch_1):page217_i295" )
			)
			( gate "C5T7"
				( objectStatus "@baseboard_fab2_lib.baseboard_fab2(sch_1):page217_i296" )
			)
			( gate "C5T6"
				( objectStatus "@baseboard_fab2_lib.baseboard_fab2(sch_1):page217_i297" )
			)
			( gate "C5T5"
				( objectStatus "@baseboard_fab2_lib.baseboard_fab2(sch_1):page217_i298" )
			)
			( gate "C3G5"
				( objectStatus "@baseboard_fab2_lib.baseboard_fab2(sch_1):page225_i288" )
			)
			( gate "C3G6"
				( objectStatus "@baseboard_fab2_lib.baseboard_fab2(sch_1):page225_i289" )
			)
			( gate "C8U7"
				( objectStatus "@baseboard_fab2_lib.baseboard_fab2(sch_1):page225_i290" )
			)
			( gate "C8U2"
				( objectStatus "@baseboard_fab2_lib.baseboard_fab2(sch_1):page225_i291" )
			)
			( gate "C7U2"
				( objectStatus "@baseboard_fab2_lib.baseboard_fab2(sch_1):page225_i292" )
			)
			( gate "C7U1"
				( objectStatus "@baseboard_fab2_lib.baseboard_fab2(sch_1):page225_i293" )
			)
			( gate "C8U3"
				( objectStatus "@baseboard_fab2_lib.baseboard_fab2(sch_1):page225_i294" )
			)
			( gate "C7T4"
				( objectStatus "@baseboard_fab2_lib.baseboard_fab2(sch_1):page225_i295" )
			)
			( gate "C7T5"
				( objectStatus "@baseboard_fab2_lib.baseboard_fab2(sch_1):page225_i296" )
			)
			( gate "C8T5"
				( objectStatus "@baseboard_fab2_lib.baseboard_fab2(sch_1):page225_i297" )
			)
			( gate "C8U6"
				( objectStatus "@baseboard_fab2_lib.baseboard_fab2(sch_1):page225_i298" )
			)
			( gate "C8T6"
				( objectStatus "@baseboard_fab2_lib.baseboard_fab2(sch_1):page225_i299" )
			)
			( gate "C8T7"
				( objectStatus "@baseboard_fab2_lib.baseboard_fab2(sch_1):page225_i300" )
			)
			( gate "C8T8"
				( objectStatus "@baseboard_fab2_lib.baseboard_fab2(sch_1):page225_i301" )
			)
			( gate "C8U5"
				( objectStatus "@baseboard_fab2_lib.baseboard_fab2(sch_1):page225_i302" )
			)
			( gate "C8T9"
				( objectStatus "@baseboard_fab2_lib.baseboard_fab2(sch_1):page225_i303" )
			)
			( gate "C8T10"
				( objectStatus "@baseboard_fab2_lib.baseboard_fab2(sch_1):page225_i304" )
			)
			( gate "C8U4"
				( objectStatus "@baseboard_fab2_lib.baseboard_fab2(sch_1):page225_i305" )
			)
			( gate "C5P6"
				( objectStatus "@baseboard_fab2_lib.baseboard_fab2(sch_1):page220_i316" )
			)
			( gate "C7W5"
				( objectStatus "@baseboard_fab2_lib.baseboard_fab2(sch_1):page220_i298" )
			)
			( gate "C7W9"
				( objectStatus "@baseboard_fab2_lib.baseboard_fab2(sch_1):page220_i299" )
			)
			( gate "C7W8"
				( objectStatus "@baseboard_fab2_lib.baseboard_fab2(sch_1):page220_i300" )
			)
			( gate "C7W7"
				( objectStatus "@baseboard_fab2_lib.baseboard_fab2(sch_1):page220_i301" )
			)
			( gate "C7W6"
				( objectStatus "@baseboard_fab2_lib.baseboard_fab2(sch_1):page220_i302" )
			)
			( gate "C7W13"
				( objectStatus "@baseboard_fab2_lib.baseboard_fab2(sch_1):page220_i303" )
			)
			( gate "C7W12"
				( objectStatus "@baseboard_fab2_lib.baseboard_fab2(sch_1):page220_i304" )
			)
			( gate "C7W11"
				( objectStatus "@baseboard_fab2_lib.baseboard_fab2(sch_1):page220_i305" )
			)
			( gate "C7W10"
				( objectStatus "@baseboard_fab2_lib.baseboard_fab2(sch_1):page220_i306" )
			)
			( gate "J8D4"
				( objectStatus "@baseboard_fab2_lib.baseboard_fab2(sch_1):page201_i191" )
			)
			( gate "C25W9"
				( objectStatus "@baseboard_fab2_lib.baseboard_fab2(sch_1):page147_i160" )
			)
			( gate "C8E7"
				( objectStatus "@baseboard_fab2_lib.baseboard_fab2(sch_1):page241_i103" )
			)
			( gate "C8E9"
				( objectStatus "@baseboard_fab2_lib.baseboard_fab2(sch_1):page241_i104" )
			)
			( gate "R6W29"
				( objectStatus "@baseboard_fab2_lib.baseboard_fab2(sch_1):page89_i40" )
			)
			( gate "WR8D30"
				( objectStatus "@baseboard_fab2_lib.baseboard_fab2(sch_1):page89_i45" )
			)
			( gate "Q8D1"
				( objectStatus "@baseboard_fab2_lib.baseboard_fab2(sch_1):page89_i46" )
			)
			( gate "R8W9"
				( objectStatus "@baseboard_fab2_lib.baseboard_fab2(sch_1):page89_i49" )
			)
			( gate "Q8W1"
				( objectStatus "@baseboard_fab2_lib.baseboard_fab2(sch_1):page89_i51" )
			)
			( gate "Q8W1"
				( objectStatus "@baseboard_fab2_lib.baseboard_fab2(sch_1):page89_i52" )
			)
			( gate "Q1F1"
				( objectStatus "@baseboard_fab2_lib.baseboard_fab2(sch_1):page89_i53" )
			)
			( gate "R1W32"
				( objectStatus "@baseboard_fab2_lib.baseboard_fab2(sch_1):page89_i54" )
			)
			( gate "Q1W6"
				( objectStatus "@baseboard_fab2_lib.baseboard_fab2(sch_1):page89_i55" )
			)
			( gate "R1W31"
				( objectStatus "@baseboard_fab2_lib.baseboard_fab2(sch_1):page89_i56" )
			)
			( gate "C30W3"
				( objectStatus "@baseboard_fab2_lib.baseboard_fab2(sch_1):page253_i35" )
			)
			( gate "C30W4"
				( objectStatus "@baseboard_fab2_lib.baseboard_fab2(sch_1):page253_i36" )
			)
			( gate "C30W6"
				( objectStatus "@baseboard_fab2_lib.baseboard_fab2(sch_1):page253_i37" )
			)
			( gate "C30W5"
				( objectStatus "@baseboard_fab2_lib.baseboard_fab2(sch_1):page253_i38" )
			)
			( gate "C30W9"
				( objectStatus "@baseboard_fab2_lib.baseboard_fab2(sch_1):page253_i40" )
			)
			( gate "C30W8"
				( objectStatus "@baseboard_fab2_lib.baseboard_fab2(sch_1):page253_i41" )
			)
			( gate "C30W7"
				( objectStatus "@baseboard_fab2_lib.baseboard_fab2(sch_1):page253_i42" )
			)
			( gate "R4E2"
				( objectStatus "@baseboard_fab2_lib.baseboard_fab2(sch_1):page213_i103" )
			)
			( gate "R4P1"
				( objectStatus "@baseboard_fab2_lib.baseboard_fab2(sch_1):page90_i98" )
			)
			( gate "R3D13"
				( objectStatus "@baseboard_fab2_lib.baseboard_fab2(sch_1):page90_i99" )
			)
			( gate "R1U15"
				( objectStatus "@baseboard_fab2_lib.baseboard_fab2(sch_1):page164_i48" )
			)
			( gate "R6D6"
				( objectStatus "@baseboard_fab2_lib.baseboard_fab2(sch_1):page90_i101" )
			)
			( gate "R3D12"
				( objectStatus "@baseboard_fab2_lib.baseboard_fab2(sch_1):page90_i102" )
			)
			( gate "R2T1"
				( objectStatus "@baseboard_fab2_lib.baseboard_fab2(sch_1):page125_i89" )
			)
			( gate "R9F32"
				( objectStatus "@baseboard_fab2_lib.baseboard_fab2(sch_1):page239_i100" )
			)
			( gate "R9W32"
				( objectStatus "@baseboard_fab2_lib.baseboard_fab2(sch_1):page239_i101" )
			)
			( gate "R7G8"
				( objectStatus "@baseboard_fab2_lib.baseboard_fab2(sch_1):page215_i72" )
			)
			( gate "R2L26"
				( objectStatus "@baseboard_fab2_lib.baseboard_fab2(sch_1):page235_i253" )
			)
			( gate "R7F11"
				( objectStatus "@baseboard_fab2_lib.baseboard_fab2(sch_1):page231_i230" )
			)
			( gate "U6W5"
				( objectStatus "@baseboard_fab2_lib.baseboard_fab2(sch_1):page176_i148" )
			)
			( gate "R25W156"
				( objectStatus "@baseboard_fab2_lib.baseboard_fab2(sch_1):page150_i240" )
			)
			( gate "R6W1"
				( objectStatus "@baseboard_fab2_lib.baseboard_fab2(sch_1):page137_i149" )
			)
			( gate "R1W33"
				( objectStatus "@baseboard_fab2_lib.baseboard_fab2(sch_1):page176_i142" )
			)
			( gate "R1W34"
				( objectStatus "@baseboard_fab2_lib.baseboard_fab2(sch_1):page176_i143" )
			)
			( gate "U6W4"
				( objectStatus "@baseboard_fab2_lib.baseboard_fab2(sch_1):page176_i146" )
			)
			( gate "R6W30"
				( objectStatus "@baseboard_fab2_lib.baseboard_fab2(sch_1):page176_i147" )
			)
			( gate "U6W6"
				( objectStatus "@baseboard_fab2_lib.baseboard_fab2(sch_1):page176_i157" )
			)
			( gate "C5M13"
				( objectStatus "@baseboard_fab2_lib.baseboard_fab2(sch_1):page222_i41" )
			)
			( gate "C8L4"
				( objectStatus "@baseboard_fab2_lib.baseboard_fab2(sch_1):page230_i42" )
			)
			( gate "R9A5"
				( objectStatus "@baseboard_fab2_lib.baseboard_fab2(sch_1):page155_i198" )
			)
			( gate "CR6W1"
				( objectStatus "@baseboard_fab2_lib.baseboard_fab2(sch_1):page247_i157" )
			)
			( gate "CR6W2"
				( objectStatus "@baseboard_fab2_lib.baseboard_fab2(sch_1):page247_i158" )
			)
			( gate "R6W38"
				( objectStatus "@baseboard_fab2_lib.baseboard_fab2(sch_1):page176_i156" )
			)
			( gate "R6W39"
				( objectStatus "@baseboard_fab2_lib.baseboard_fab2(sch_1):page176_i158" )
			)
			( gate "R7W4"
				( objectStatus "@baseboard_fab2_lib.baseboard_fab2(sch_1):page92_i106" )
			)
			( gate "R3W10"
				( objectStatus "@baseboard_fab2_lib.baseboard_fab2(sch_1):page92_i108" )
			)
			( gate "R2W2"
				( objectStatus "@baseboard_fab2_lib.baseboard_fab2(sch_1):page93_i147" )
			)
			( gate "R1W35"
				( objectStatus "@baseboard_fab2_lib.baseboard_fab2(sch_1):page152_i105" )
			)
			( gate "R6W37"
				( objectStatus "@baseboard_fab2_lib.baseboard_fab2(sch_1):page176_i160" )
			)
			( gate "R6W36"
				( objectStatus "@baseboard_fab2_lib.baseboard_fab2(sch_1):page176_i161" )
			)
			( gate "C5L5"
				( objectStatus "@baseboard_fab2_lib.baseboard_fab2(sch_1):page222_i44" )
			)
			( gate "C1W18"
				( objectStatus "@baseboard_fab2_lib.baseboard_fab2(sch_1):page176_i163" )
			)
			( gate "C1W19"
				( objectStatus "@baseboard_fab2_lib.baseboard_fab2(sch_1):page176_i166" )
			)
			( gate "R1W36"
				( objectStatus "@baseboard_fab2_lib.baseboard_fab2(sch_1):page176_i172" )
			)
			( gate "R1W37"
				( objectStatus "@baseboard_fab2_lib.baseboard_fab2(sch_1):page176_i173" )
			)
			( gate "R8E36"
				( objectStatus "@baseboard_fab2_lib.baseboard_fab2(sch_1):page142_i34" )
			)
			( gate "R8E30"
				( objectStatus "@baseboard_fab2_lib.baseboard_fab2(sch_1):page142_i35" )
			)
			( gate "R1W38"
				( objectStatus "@baseboard_fab2_lib.baseboard_fab2(sch_1):page176_i176" )
			)
			( gate "R6W3"
				( objectStatus "@baseboard_fab2_lib.baseboard_fab2(sch_1):page200_i250" )
			)
			( gate "C1W20"
				( objectStatus "@baseboard_fab2_lib.baseboard_fab2(sch_1):page151_i220" )
			)
			( gate "FB9E1"
				( objectStatus "@baseboard_fab2_lib.baseboard_fab2(sch_1):page240_i193" )
			)
			( gate "R6W40"
				( objectStatus "@baseboard_fab2_lib.baseboard_fab2(sch_1):page155_i201" )
			)
			( gate "R25W30"
				( objectStatus "@baseboard_fab2_lib.baseboard_fab2(sch_1):page151_i222" )
			)
			( gate "R1D29"
				( objectStatus "@baseboard_fab2_lib.baseboard_fab2(sch_1):page199_i137" )
			)
			( gate "R1T10"
				( objectStatus "@baseboard_fab2_lib.baseboard_fab2(sch_1):page164_i101" )
			)
			( gate "R1T6"
				( objectStatus "@baseboard_fab2_lib.baseboard_fab2(sch_1):page164_i51" )
			)
			( gate "R1T12"
				( objectStatus "@baseboard_fab2_lib.baseboard_fab2(sch_1):page164_i53" )
			)
			( gate "R3N22"
				( objectStatus "@baseboard_fab2_lib.baseboard_fab2(sch_1):page211_i102" )
			)
			( gate "R4D64"
				( objectStatus "@baseboard_fab2_lib.baseboard_fab2(sch_1):page213_i104" )
			)
			( gate "R9W31"
				( objectStatus "@baseboard_fab2_lib.baseboard_fab2(sch_1):page239_i102" )
			)
			( gate "R25W28"
				( objectStatus "@baseboard_fab2_lib.baseboard_fab2(sch_1):page151_i224" )
			)
			( gate "R25W29"
				( objectStatus "@baseboard_fab2_lib.baseboard_fab2(sch_1):page151_i225" )
			)
			( gate "R25W34"
				( objectStatus "@baseboard_fab2_lib.baseboard_fab2(sch_1):page151_i229" )
			)
			( gate "R25W35"
				( objectStatus "@baseboard_fab2_lib.baseboard_fab2(sch_1):page151_i230" )
			)
			( gate "R25W36"
				( objectStatus "@baseboard_fab2_lib.baseboard_fab2(sch_1):page151_i231" )
			)
			( gate "R25W37"
				( objectStatus "@baseboard_fab2_lib.baseboard_fab2(sch_1):page151_i232" )
			)
			( gate "R25W38"
				( objectStatus "@baseboard_fab2_lib.baseboard_fab2(sch_1):page151_i233" )
			)
			( gate "R25W39"
				( objectStatus "@baseboard_fab2_lib.baseboard_fab2(sch_1):page151_i234" )
			)
			( gate "R25W41"
				( objectStatus "@baseboard_fab2_lib.baseboard_fab2(sch_1):page151_i235" )
			)
			( gate "R25W42"
				( objectStatus "@baseboard_fab2_lib.baseboard_fab2(sch_1):page151_i236" )
			)
			( gate "R25W44"
				( objectStatus "@baseboard_fab2_lib.baseboard_fab2(sch_1):page151_i237" )
			)
			( gate "R25W43"
				( objectStatus "@baseboard_fab2_lib.baseboard_fab2(sch_1):page151_i238" )
			)
			( gate "R25W47"
				( objectStatus "@baseboard_fab2_lib.baseboard_fab2(sch_1):page151_i239" )
			)
			( gate "R25W48"
				( objectStatus "@baseboard_fab2_lib.baseboard_fab2(sch_1):page151_i240" )
			)
			( gate "R25W46"
				( objectStatus "@baseboard_fab2_lib.baseboard_fab2(sch_1):page151_i241" )
			)
			( gate "R25W45"
				( objectStatus "@baseboard_fab2_lib.baseboard_fab2(sch_1):page151_i242" )
			)
			( gate "R25W49"
				( objectStatus "@baseboard_fab2_lib.baseboard_fab2(sch_1):page151_i243" )
			)
			( gate "R25W50"
				( objectStatus "@baseboard_fab2_lib.baseboard_fab2(sch_1):page151_i244" )
			)
			( gate "R25W51"
				( objectStatus "@baseboard_fab2_lib.baseboard_fab2(sch_1):page151_i245" )
			)
			( gate "R25W52"
				( objectStatus "@baseboard_fab2_lib.baseboard_fab2(sch_1):page151_i246" )
			)
			( gate "R25W40"
				( objectStatus "@baseboard_fab2_lib.baseboard_fab2(sch_1):page151_i247" )
			)
			( gate "R25W22"
				( objectStatus "@baseboard_fab2_lib.baseboard_fab2(sch_1):page151_i270" )
			)
			( gate "R25W21"
				( objectStatus "@baseboard_fab2_lib.baseboard_fab2(sch_1):page151_i271" )
			)
			( gate "R25W26"
				( objectStatus "@baseboard_fab2_lib.baseboard_fab2(sch_1):page151_i274" )
			)
			( gate "R25W25"
				( objectStatus "@baseboard_fab2_lib.baseboard_fab2(sch_1):page151_i275" )
			)
			( gate "R1B15"
				( objectStatus "@baseboard_fab2_lib.baseboard_fab2(sch_1):page226_i73" )
			)
			( gate "R6W4"
				( objectStatus "@baseboard_fab2_lib.baseboard_fab2(sch_1):page247_i159" )
			)
			( gate "R6W5"
				( objectStatus "@baseboard_fab2_lib.baseboard_fab2(sch_1):page247_i160" )
			)
			( gate "R6W6"
				( objectStatus "@baseboard_fab2_lib.baseboard_fab2(sch_1):page247_i161" )
			)
			( gate "R6W9"
				( objectStatus "@baseboard_fab2_lib.baseboard_fab2(sch_1):page247_i162" )
			)
			( gate "R6W8"
				( objectStatus "@baseboard_fab2_lib.baseboard_fab2(sch_1):page247_i163" )
			)
			( gate "R6W7"
				( objectStatus "@baseboard_fab2_lib.baseboard_fab2(sch_1):page247_i164" )
			)
			( gate "R1T40"
				( objectStatus "@baseboard_fab2_lib.baseboard_fab2(sch_1):page151_i278" )
			)
			( gate "R1T28"
				( objectStatus "@baseboard_fab2_lib.baseboard_fab2(sch_1):page151_i279" )
			)
			( gate "R8F9"
				( objectStatus "@baseboard_fab2_lib.baseboard_fab2(sch_1):page240_i195" )
			)
			( gate "L1G1"
				( objectStatus "@baseboard_fab2_lib.baseboard_fab2(sch_1):page224_i160" )
			)
			( gate "C8W4"
				( objectStatus "@baseboard_fab2_lib.baseboard_fab2(sch_1):page76_i245" )
			)
			( gate "C5U10"
				( objectStatus "@baseboard_fab2_lib.baseboard_fab2(sch_1):page217_i317" )
			)
			( gate "C5U15"
				( objectStatus "@baseboard_fab2_lib.baseboard_fab2(sch_1):page217_i320" )
			)
			( gate "C5P38"
				( objectStatus "@baseboard_fab2_lib.baseboard_fab2(sch_1):page217_i327" )
			)
			( gate "C5P39"
				( objectStatus "@baseboard_fab2_lib.baseboard_fab2(sch_1):page217_i328" )
			)
			( gate "R6W35"
				( objectStatus "@baseboard_fab2_lib.baseboard_fab2(sch_1):page247_i165" )
			)
			( gate "C7C13"
				( objectStatus "@baseboard_fab2_lib.baseboard_fab2(sch_1):page114_i195" )
			)
			( gate "C7C15"
				( objectStatus "@baseboard_fab2_lib.baseboard_fab2(sch_1):page114_i196" )
			)
			( gate "C5P8"
				( objectStatus "@baseboard_fab2_lib.baseboard_fab2(sch_1):page42_i214" )
			)
			( gate "C8P6"
				( objectStatus "@baseboard_fab2_lib.baseboard_fab2(sch_1):page76_i247" )
			)
			( gate "C8P7"
				( objectStatus "@baseboard_fab2_lib.baseboard_fab2(sch_1):page76_i248" )
			)
			( gate "C8P17"
				( objectStatus "@baseboard_fab2_lib.baseboard_fab2(sch_1):page76_i252" )
			)
			( gate "R25W157"
				( objectStatus "@baseboard_fab2_lib.baseboard_fab2(sch_1):page147_i164" )
			)
			( gate "R32W10"
				( objectStatus "@baseboard_fab2_lib.baseboard_fab2(sch_1):page185_i183" )
			)
			( gate "R32W11"
				( objectStatus "@baseboard_fab2_lib.baseboard_fab2(sch_1):page185_i184" )
			)
			( gate "R32W12"
				( objectStatus "@baseboard_fab2_lib.baseboard_fab2(sch_1):page185_i187" )
			)
			( gate "C32W1"
				( objectStatus "@baseboard_fab2_lib.baseboard_fab2(sch_1):page185_i188" )
			)
			( gate "C32W3"
				( objectStatus "@baseboard_fab2_lib.baseboard_fab2(sch_1):page185_i190" )
			)
			( gate "U32W1"
				( objectStatus "@baseboard_fab2_lib.baseboard_fab2(sch_1):page185_i191" )
			)
			( gate "C32W2"
				( objectStatus "@baseboard_fab2_lib.baseboard_fab2(sch_1):page185_i193" )
			)
			( gate "C32W4"
				( objectStatus "@baseboard_fab2_lib.baseboard_fab2(sch_1):page185_i196" )
			)
			( gate "R32W9"
				( objectStatus "@baseboard_fab2_lib.baseboard_fab2(sch_1):page185_i200" )
			)
			( gate "U32W2"
				( objectStatus "@baseboard_fab2_lib.baseboard_fab2(sch_1):page185_i204" )
			)
			( gate "R32W3"
				( objectStatus "@baseboard_fab2_lib.baseboard_fab2(sch_1):page185_i206" )
			)
			( gate "R32W2"
				( objectStatus "@baseboard_fab2_lib.baseboard_fab2(sch_1):page185_i207" )
			)
			( gate "R32W1"
				( objectStatus "@baseboard_fab2_lib.baseboard_fab2(sch_1):page185_i208" )
			)
			( gate "R32W4"
				( objectStatus "@baseboard_fab2_lib.baseboard_fab2(sch_1):page185_i211" )
			)
			( gate "VR32W1"
				( objectStatus "@baseboard_fab2_lib.baseboard_fab2(sch_1):page185_i213" )
			)
			( gate "R32W6"
				( objectStatus "@baseboard_fab2_lib.baseboard_fab2(sch_1):page185_i214" )
			)
			( gate "R32W7"
				( objectStatus "@baseboard_fab2_lib.baseboard_fab2(sch_1):page185_i215" )
			)
			( gate "R32W5"
				( objectStatus "@baseboard_fab2_lib.baseboard_fab2(sch_1):page185_i216" )
			)
			( gate "C8W1"
				( objectStatus "@baseboard_fab2_lib.baseboard_fab2(sch_1):page249_i52" )
			)
			( gate "R12W2"
				( objectStatus "@baseboard_fab2_lib.baseboard_fab2(sch_1):page197_i117" )
			)
			( gate "R12W12"
				( objectStatus "@baseboard_fab2_lib.baseboard_fab2(sch_1):page197_i119" )
			)
			( gate "R12W6"
				( objectStatus "@baseboard_fab2_lib.baseboard_fab2(sch_1):page197_i120" )
			)
			( gate "R12W7"
				( objectStatus "@baseboard_fab2_lib.baseboard_fab2(sch_1):page197_i121" )
			)
			( gate "R12W16"
				( objectStatus "@baseboard_fab2_lib.baseboard_fab2(sch_1):page197_i122" )
			)
			( gate "R12W17"
				( objectStatus "@baseboard_fab2_lib.baseboard_fab2(sch_1):page197_i123" )
			)
			( gate "Q9W3"
				( objectStatus "@baseboard_fab2_lib.baseboard_fab2(sch_1):page249_i49" )
			)
			( gate "C9E8"
				( objectStatus "@baseboard_fab2_lib.baseboard_fab2(sch_1):page139_i250" )
			)
			( gate "R9W36"
				( objectStatus "@baseboard_fab2_lib.baseboard_fab2(sch_1):page139_i252" )
			)
			( gate "Q9B1"
				( objectStatus "@baseboard_fab2_lib.baseboard_fab2(sch_1):page167_i93" )
			)
			( gate "Q1E1"
				( objectStatus "@baseboard_fab2_lib.baseboard_fab2(sch_1):page167_i94" )
			)
			( gate "R3W2"
				( objectStatus "@baseboard_fab2_lib.baseboard_fab2(sch_1):page249_i56" )
			)
			( gate "C4D20"
				( objectStatus "@baseboard_fab2_lib.baseboard_fab2(sch_1):page201_i192" )
			)
			( gate "CR3W1"
				( objectStatus "@baseboard_fab2_lib.baseboard_fab2(sch_1):page249_i55" )
			)
			( gate "R3W5"
				( objectStatus "@baseboard_fab2_lib.baseboard_fab2(sch_1):page249_i58" )
			)
			( gate "C5W1"
				( objectStatus "@baseboard_fab2_lib.baseboard_fab2(sch_1):page42_i217" )
			)
			( gate "C5W2"
				( objectStatus "@baseboard_fab2_lib.baseboard_fab2(sch_1):page42_i218" )
			)
			( gate "C3W4"
				( objectStatus "@baseboard_fab2_lib.baseboard_fab2(sch_1):page76_i254" )
			)
			( gate "C3W3"
				( objectStatus "@baseboard_fab2_lib.baseboard_fab2(sch_1):page76_i256" )
			)
			( gate "R12W25"
				( objectStatus "@baseboard_fab2_lib.baseboard_fab2(sch_1):page215_i74" )
			)
			( gate "R2W3"
				( objectStatus "@baseboard_fab2_lib.baseboard_fab2(sch_1):page119_i223" )
			)
			( gate "R2W4"
				( objectStatus "@baseboard_fab2_lib.baseboard_fab2(sch_1):page119_i224" )
			)
			( gate "R2W5"
				( objectStatus "@baseboard_fab2_lib.baseboard_fab2(sch_1):page145_i176" )
			)
			( gate "U25W19"
				( objectStatus "@baseboard_fab2_lib.baseboard_fab2(sch_1):page269_i76" )
			)
			( gate "R25W174"
				( objectStatus "@baseboard_fab2_lib.baseboard_fab2(sch_1):page269_i4" )
			)
			( gate "R6W16"
				( objectStatus "@baseboard_fab2_lib.baseboard_fab2(sch_1):page168_i46" )
			)
			( gate "R25W167"
				( objectStatus "@baseboard_fab2_lib.baseboard_fab2(sch_1):page269_i10" )
			)
			( gate "R25W168"
				( objectStatus "@baseboard_fab2_lib.baseboard_fab2(sch_1):page269_i11" )
			)
			( gate "R25W169"
				( objectStatus "@baseboard_fab2_lib.baseboard_fab2(sch_1):page269_i12" )
			)
			( gate "R25W170"
				( objectStatus "@baseboard_fab2_lib.baseboard_fab2(sch_1):page269_i13" )
			)
			( gate "R25W177"
				( objectStatus "@baseboard_fab2_lib.baseboard_fab2(sch_1):page269_i18" )
			)
			( gate "R25W178"
				( objectStatus "@baseboard_fab2_lib.baseboard_fab2(sch_1):page269_i19" )
			)
			( gate "R25W160"
				( objectStatus "@baseboard_fab2_lib.baseboard_fab2(sch_1):page269_i20" )
			)
			( gate "R25W161"
				( objectStatus "@baseboard_fab2_lib.baseboard_fab2(sch_1):page269_i21" )
			)
			( gate "R25W158"
				( objectStatus "@baseboard_fab2_lib.baseboard_fab2(sch_1):page269_i22" )
			)
			( gate "R25W159"
				( objectStatus "@baseboard_fab2_lib.baseboard_fab2(sch_1):page269_i24" )
			)
			( gate "C25W91"
				( objectStatus "@baseboard_fab2_lib.baseboard_fab2(sch_1):page269_i26" )
			)
			( gate "C25W94"
				( objectStatus "@baseboard_fab2_lib.baseboard_fab2(sch_1):page269_i32" )
			)
			( gate "U25W12"
				( objectStatus "@baseboard_fab2_lib.baseboard_fab2(sch_1):page269_i33" )
			)
			( gate "U25W10"
				( objectStatus "@baseboard_fab2_lib.baseboard_fab2(sch_1):page269_i49" )
			)
			( gate "R25W180"
				( objectStatus "@baseboard_fab2_lib.baseboard_fab2(sch_1):page268_i2" )
			)
			( gate "C25W97"
				( objectStatus "@baseboard_fab2_lib.baseboard_fab2(sch_1):page268_i4" )
			)
			( gate "R25W179"
				( objectStatus "@baseboard_fab2_lib.baseboard_fab2(sch_1):page268_i7" )
			)
			( gate "C25W96"
				( objectStatus "@baseboard_fab2_lib.baseboard_fab2(sch_1):page268_i9" )
			)
			( gate "U25W15"
				( objectStatus "@baseboard_fab2_lib.baseboard_fab2(sch_1):page268_i12" )
			)
			( gate "U25W14"
				( objectStatus "@baseboard_fab2_lib.baseboard_fab2(sch_1):page268_i13" )
			)
			( gate "R25W176"
				( objectStatus "@baseboard_fab2_lib.baseboard_fab2(sch_1):page268_i14" )
			)
			( gate "R25W175"
				( objectStatus "@baseboard_fab2_lib.baseboard_fab2(sch_1):page268_i17" )
			)
			( gate "C25W92"
				( objectStatus "@baseboard_fab2_lib.baseboard_fab2(sch_1):page268_i23" )
			)
			( gate "R25W166"
				( objectStatus "@baseboard_fab2_lib.baseboard_fab2(sch_1):page268_i26" )
			)
			( gate "C25W93"
				( objectStatus "@baseboard_fab2_lib.baseboard_fab2(sch_1):page268_i27" )
			)
			( gate "R25W165"
				( objectStatus "@baseboard_fab2_lib.baseboard_fab2(sch_1):page268_i28" )
			)
			( gate "R25W164"
				( objectStatus "@baseboard_fab2_lib.baseboard_fab2(sch_1):page268_i29" )
			)
			( gate "U25W11"
				( objectStatus "@baseboard_fab2_lib.baseboard_fab2(sch_1):page268_i33" )
			)
			( gate "U25W13"
				( objectStatus "@baseboard_fab2_lib.baseboard_fab2(sch_1):page269_i53" )
			)
			( gate "C25W95"
				( objectStatus "@baseboard_fab2_lib.baseboard_fab2(sch_1):page269_i56" )
			)
			( gate "R6W46"
				( objectStatus "@baseboard_fab2_lib.baseboard_fab2(sch_1):page164_i93" )
			)
			( gate "R25W182"
				( objectStatus "@baseboard_fab2_lib.baseboard_fab2(sch_1):page144_i151" )
			)
			( gate "R25W181"
				( objectStatus "@baseboard_fab2_lib.baseboard_fab2(sch_1):page147_i173" )
			)
			( gate "R6W45"
				( objectStatus "@baseboard_fab2_lib.baseboard_fab2(sch_1):page164_i94" )
			)
			( gate "R6W42"
				( objectStatus "@baseboard_fab2_lib.baseboard_fab2(sch_1):page164_i95" )
			)
			( gate "R6W43"
				( objectStatus "@baseboard_fab2_lib.baseboard_fab2(sch_1):page164_i96" )
			)
			( gate "U1L10"
				( objectStatus "@baseboard_fab2_lib.baseboard_fab2(sch_1):page189_i67" )
			)
			( gate "C1L119"
				( objectStatus "@baseboard_fab2_lib.baseboard_fab2(sch_1):page189_i69" )
			)
			( gate "R7G114"
				( objectStatus "@baseboard_fab2_lib.baseboard_fab2(sch_1):page189_i76" )
			)
			( gate "C4E29"
				( objectStatus "@baseboard_fab2_lib.baseboard_fab2(sch_1):page193_i175" )
			)
			( gate "R25W184"
				( objectStatus "@baseboard_fab2_lib.baseboard_fab2(sch_1):page146_i166" )
			)
			( gate "R8E3"
				( objectStatus "@baseboard_fab2_lib.baseboard_fab2(sch_1):page133_i371" )
			)
			( gate "C5P30"
				( objectStatus "@baseboard_fab2_lib.baseboard_fab2(sch_1):page42_i221" )
			)
			( gate "C5P19"
				( objectStatus "@baseboard_fab2_lib.baseboard_fab2(sch_1):page42_i222" )
			)
			( gate "C4P4"
				( objectStatus "@baseboard_fab2_lib.baseboard_fab2(sch_1):page42_i223" )
			)
			( gate "C4P7"
				( objectStatus "@baseboard_fab2_lib.baseboard_fab2(sch_1):page42_i224" )
			)
			( gate "C4P3"
				( objectStatus "@baseboard_fab2_lib.baseboard_fab2(sch_1):page42_i225" )
			)
			( gate "C5P10"
				( objectStatus "@baseboard_fab2_lib.baseboard_fab2(sch_1):page42_i226" )
			)
			( gate "C5P11"
				( objectStatus "@baseboard_fab2_lib.baseboard_fab2(sch_1):page42_i227" )
			)
			( gate "C5P18"
				( objectStatus "@baseboard_fab2_lib.baseboard_fab2(sch_1):page42_i228" )
			)
			( gate "C5P28"
				( objectStatus "@baseboard_fab2_lib.baseboard_fab2(sch_1):page42_i229" )
			)
			( gate "C4P2"
				( objectStatus "@baseboard_fab2_lib.baseboard_fab2(sch_1):page42_i230" )
			)
			( gate "C5P31"
				( objectStatus "@baseboard_fab2_lib.baseboard_fab2(sch_1):page42_i231" )
			)
			( gate "C5P13"
				( objectStatus "@baseboard_fab2_lib.baseboard_fab2(sch_1):page42_i232" )
			)
			( gate "C4P5"
				( objectStatus "@baseboard_fab2_lib.baseboard_fab2(sch_1):page42_i233" )
			)
			( gate "C5P20"
				( objectStatus "@baseboard_fab2_lib.baseboard_fab2(sch_1):page42_i234" )
			)
			( gate "C5P21"
				( objectStatus "@baseboard_fab2_lib.baseboard_fab2(sch_1):page42_i235" )
			)
			( gate "C5P12"
				( objectStatus "@baseboard_fab2_lib.baseboard_fab2(sch_1):page42_i236" )
			)
			( gate "C7P9"
				( objectStatus "@baseboard_fab2_lib.baseboard_fab2(sch_1):page76_i258" )
			)
			( gate "C7P5"
				( objectStatus "@baseboard_fab2_lib.baseboard_fab2(sch_1):page76_i259" )
			)
			( gate "C7P10"
				( objectStatus "@baseboard_fab2_lib.baseboard_fab2(sch_1):page76_i266" )
			)
			( gate "C7P7"
				( objectStatus "@baseboard_fab2_lib.baseboard_fab2(sch_1):page76_i267" )
			)
			( gate "C8P14"
				( objectStatus "@baseboard_fab2_lib.baseboard_fab2(sch_1):page76_i272" )
			)
			( gate "C8P9"
				( objectStatus "@baseboard_fab2_lib.baseboard_fab2(sch_1):page76_i273" )
			)
			( gate "C8P8"
				( objectStatus "@baseboard_fab2_lib.baseboard_fab2(sch_1):page76_i274" )
			)
			( gate "R7F36"
				( objectStatus "@baseboard_fab2_lib.baseboard_fab2(sch_1):page215_i75" )
			)
			( gate "C25W98"
				( objectStatus "@baseboard_fab2_lib.baseboard_fab2(sch_1):page268_i40" )
			)
			( gate "Q25W5"
				( objectStatus "@baseboard_fab2_lib.baseboard_fab2(sch_1):page268_i51" )
			)
			( gate "R25W185"
				( objectStatus "@baseboard_fab2_lib.baseboard_fab2(sch_1):page268_i54" )
			)
			( gate "R25W186"
				( objectStatus "@baseboard_fab2_lib.baseboard_fab2(sch_1):page189_i77" )
			)
			( gate "R7W5"
				( objectStatus "@baseboard_fab2_lib.baseboard_fab2(sch_1):page153_i187" )
			)
			( gate "EU1D4"
				( objectStatus "@baseboard_fab2_lib.baseboard_fab2(sch_1):page207_i113" )
			)
			( gate "U25W17"
				( objectStatus "@baseboard_fab2_lib.baseboard_fab2(sch_1):page269_i61" )
			)
			( gate "C25W99"
				( objectStatus "@baseboard_fab2_lib.baseboard_fab2(sch_1):page269_i62" )
			)
			( gate "U25W18"
				( objectStatus "@baseboard_fab2_lib.baseboard_fab2(sch_1):page268_i57" )
			)
			( gate "C25W100"
				( objectStatus "@baseboard_fab2_lib.baseboard_fab2(sch_1):page268_i60" )
			)
			( gate "R9W33"
				( objectStatus "@baseboard_fab2_lib.baseboard_fab2(sch_1):page158_i153" )
			)
			( gate "R9W34"
				( objectStatus "@baseboard_fab2_lib.baseboard_fab2(sch_1):page158_i154" )
			)
			( gate "R9W35"
				( objectStatus "@baseboard_fab2_lib.baseboard_fab2(sch_1):page158_i155" )
			)
			( gate "CR9W1"
				( objectStatus "@baseboard_fab2_lib.baseboard_fab2(sch_1):page155_i202" )
			)
			( gate "C9W14"
				( objectStatus "@baseboard_fab2_lib.baseboard_fab2(sch_1):page238_i46" )
			)
			( gate "C9W17"
				( objectStatus "@baseboard_fab2_lib.baseboard_fab2(sch_1):page239_i104" )
			)
			( gate "C9W16"
				( objectStatus "@baseboard_fab2_lib.baseboard_fab2(sch_1):page238_i50" )
			)
			( gate "C9W19"
				( objectStatus "@baseboard_fab2_lib.baseboard_fab2(sch_1):page239_i111" )
			)
			( gate "R7D39"
				( objectStatus "@baseboard_fab2_lib.baseboard_fab2(sch_1):page104_i103" )
			)
			( gate "R7D37"
				( objectStatus "@baseboard_fab2_lib.baseboard_fab2(sch_1):page104_i104" )
			)
			( gate "S9W1"
				( objectStatus "@baseboard_fab2_lib.baseboard_fab2(sch_1):page268_i63" )
			)
			( gate "FB25W1"
				( objectStatus "@baseboard_fab2_lib.baseboard_fab2(sch_1):page269_i71" )
			)
			( gate "FB25W2"
				( objectStatus "@baseboard_fab2_lib.baseboard_fab2(sch_1):page269_i72" )
			)
			( gate "FB25W3"
				( objectStatus "@baseboard_fab2_lib.baseboard_fab2(sch_1):page269_i73" )
			)
			( gate "FB25W5"
				( objectStatus "@baseboard_fab2_lib.baseboard_fab2(sch_1):page269_i74" )
			)
			( gate "FB25W4"
				( objectStatus "@baseboard_fab2_lib.baseboard_fab2(sch_1):page269_i75" )
			)
			( gate "C1G15"
				( objectStatus "@baseboard_fab2_lib.baseboard_fab2(sch_1):page225_i327" )
			)
			( gate "C1G12"
				( objectStatus "@baseboard_fab2_lib.baseboard_fab2(sch_1):page225_i328" )
			)
			( gate "C1G7"
				( objectStatus "@baseboard_fab2_lib.baseboard_fab2(sch_1):page225_i329" )
			)
			( gate "C7W2"
				( objectStatus "@baseboard_fab2_lib.baseboard_fab2(sch_1):page220_i324" )
			)
			( gate "T1P14"
				( objectStatus "@baseboard_fab2_lib.baseboard_fab2(sch_1):page271_i30" )
			)
			( gate "T1P1"
				( objectStatus "@baseboard_fab2_lib.baseboard_fab2(sch_1):page271_i3" )
			)
			( gate "T1D10"
				( objectStatus "@baseboard_fab2_lib.baseboard_fab2(sch_1):page270_i17" )
			)
			( gate "T1D1"
				( objectStatus "@baseboard_fab2_lib.baseboard_fab2(sch_1):page270_i1" )
			)
			( gate "T1D2"
				( objectStatus "@baseboard_fab2_lib.baseboard_fab2(sch_1):page270_i3" )
			)
			( gate "T1D3"
				( objectStatus "@baseboard_fab2_lib.baseboard_fab2(sch_1):page270_i5" )
			)
			( gate "T1D4"
				( objectStatus "@baseboard_fab2_lib.baseboard_fab2(sch_1):page270_i6" )
			)
			( gate "T1D6"
				( objectStatus "@baseboard_fab2_lib.baseboard_fab2(sch_1):page270_i9" )
			)
			( gate "T1D5"
				( objectStatus "@baseboard_fab2_lib.baseboard_fab2(sch_1):page270_i12" )
			)
			( gate "T1D8"
				( objectStatus "@baseboard_fab2_lib.baseboard_fab2(sch_1):page270_i13" )
			)
			( gate "T1D7"
				( objectStatus "@baseboard_fab2_lib.baseboard_fab2(sch_1):page270_i16" )
			)
			( gate "T1D9"
				( objectStatus "@baseboard_fab2_lib.baseboard_fab2(sch_1):page270_i18" )
			)
			( gate "T1D12"
				( objectStatus "@baseboard_fab2_lib.baseboard_fab2(sch_1):page270_i21" )
			)
			( gate "T1D11"
				( objectStatus "@baseboard_fab2_lib.baseboard_fab2(sch_1):page270_i24" )
			)
			( gate "T1D17"
				( objectStatus "@baseboard_fab2_lib.baseboard_fab2(sch_1):page272_i1" )
			)
			( gate "T1D15"
				( objectStatus "@baseboard_fab2_lib.baseboard_fab2(sch_1):page272_i3" )
			)
			( gate "T1D13"
				( objectStatus "@baseboard_fab2_lib.baseboard_fab2(sch_1):page272_i5" )
			)
			( gate "T1D18"
				( objectStatus "@baseboard_fab2_lib.baseboard_fab2(sch_1):page272_i8" )
			)
			( gate "T1D23"
				( objectStatus "@baseboard_fab2_lib.baseboard_fab2(sch_1):page272_i9" )
			)
			( gate "T1D24"
				( objectStatus "@baseboard_fab2_lib.baseboard_fab2(sch_1):page272_i12" )
			)
			( gate "T1D16"
				( objectStatus "@baseboard_fab2_lib.baseboard_fab2(sch_1):page272_i14" )
			)
			( gate "T1D21"
				( objectStatus "@baseboard_fab2_lib.baseboard_fab2(sch_1):page272_i16" )
			)
			( gate "T1D22"
				( objectStatus "@baseboard_fab2_lib.baseboard_fab2(sch_1):page272_i21" )
			)
			( gate "T1D14"
				( objectStatus "@baseboard_fab2_lib.baseboard_fab2(sch_1):page272_i22" )
			)
			( gate "T1D19"
				( objectStatus "@baseboard_fab2_lib.baseboard_fab2(sch_1):page272_i23" )
			)
			( gate "T1D20"
				( objectStatus "@baseboard_fab2_lib.baseboard_fab2(sch_1):page272_i24" )
			)
			( gate "T1P2"
				( objectStatus "@baseboard_fab2_lib.baseboard_fab2(sch_1):page271_i5" )
			)
			( gate "T1P4"
				( objectStatus "@baseboard_fab2_lib.baseboard_fab2(sch_1):page271_i7" )
			)
			( gate "T1P3"
				( objectStatus "@baseboard_fab2_lib.baseboard_fab2(sch_1):page271_i8" )
			)
			( gate "T1P5"
				( objectStatus "@baseboard_fab2_lib.baseboard_fab2(sch_1):page271_i11" )
			)
			( gate "T1P6"
				( objectStatus "@baseboard_fab2_lib.baseboard_fab2(sch_1):page271_i13" )
			)
			( gate "T1P10"
				( objectStatus "@baseboard_fab2_lib.baseboard_fab2(sch_1):page271_i15" )
			)
			( gate "T1P8"
				( objectStatus "@baseboard_fab2_lib.baseboard_fab2(sch_1):page271_i16" )
			)
			( gate "T1P7"
				( objectStatus "@baseboard_fab2_lib.baseboard_fab2(sch_1):page271_i17" )
			)
			( gate "T1P9"
				( objectStatus "@baseboard_fab2_lib.baseboard_fab2(sch_1):page271_i19" )
			)
			( gate "T1P11"
				( objectStatus "@baseboard_fab2_lib.baseboard_fab2(sch_1):page271_i23" )
			)
			( gate "T1P12"
				( objectStatus "@baseboard_fab2_lib.baseboard_fab2(sch_1):page271_i24" )
			)
			( gate "T1P17"
				( objectStatus "@baseboard_fab2_lib.baseboard_fab2(sch_1):page271_i36" )
			)
			( gate "T1P24"
				( objectStatus "@baseboard_fab2_lib.baseboard_fab2(sch_1):page271_i38" )
			)
			( gate "T1P19"
				( objectStatus "@baseboard_fab2_lib.baseboard_fab2(sch_1):page271_i39" )
			)
			( gate "T1P22"
				( objectStatus "@baseboard_fab2_lib.baseboard_fab2(sch_1):page271_i45" )
			)
			( gate "T1P23"
				( objectStatus "@baseboard_fab2_lib.baseboard_fab2(sch_1):page271_i47" )
			)
			( gate "T1P25"
				( objectStatus "@baseboard_fab2_lib.baseboard_fab2(sch_1):page271_i50" )
			)
			( gate "T1P26"
				( objectStatus "@baseboard_fab2_lib.baseboard_fab2(sch_1):page271_i52" )
			)
			( gate "T1P27"
				( objectStatus "@baseboard_fab2_lib.baseboard_fab2(sch_1):page271_i54" )
			)
			( gate "T1P29"
				( objectStatus "@baseboard_fab2_lib.baseboard_fab2(sch_1):page271_i56" )
			)
			( gate "T1P28"
				( objectStatus "@baseboard_fab2_lib.baseboard_fab2(sch_1):page271_i60" )
			)
			( gate "T1P30"
				( objectStatus "@baseboard_fab2_lib.baseboard_fab2(sch_1):page271_i61" )
			)
			( gate "T1P34"
				( objectStatus "@baseboard_fab2_lib.baseboard_fab2(sch_1):page271_i62" )
			)
			( gate "T1P36"
				( objectStatus "@baseboard_fab2_lib.baseboard_fab2(sch_1):page271_i63" )
			)
			( gate "T1P35"
				( objectStatus "@baseboard_fab2_lib.baseboard_fab2(sch_1):page271_i67" )
			)
			( gate "T1P31"
				( objectStatus "@baseboard_fab2_lib.baseboard_fab2(sch_1):page271_i71" )
			)
			( gate "T1P32"
				( objectStatus "@baseboard_fab2_lib.baseboard_fab2(sch_1):page271_i72" )
			)
			( gate "T1P33"
				( objectStatus "@baseboard_fab2_lib.baseboard_fab2(sch_1):page271_i73" )
			)
			( gate "R7W6"
				( objectStatus "@baseboard_fab2_lib.baseboard_fab2(sch_1):page118_i176" )
			)
			( gate "R7W8"
				( objectStatus "@baseboard_fab2_lib.baseboard_fab2(sch_1):page120_i269" )
			)
			( gate "R7W9"
				( objectStatus "@baseboard_fab2_lib.baseboard_fab2(sch_1):page118_i177" )
			)
			( gate "R7W10"
				( objectStatus "@baseboard_fab2_lib.baseboard_fab2(sch_1):page120_i270" )
			)
			( gate "R7W12"
				( objectStatus "@baseboard_fab2_lib.baseboard_fab2(sch_1):page120_i271" )
			)
			( gate "R7W11"
				( objectStatus "@baseboard_fab2_lib.baseboard_fab2(sch_1):page120_i273" )
			)
			( gate "R25W187"
				( objectStatus "@baseboard_fab2_lib.baseboard_fab2(sch_1):page268_i66" )
			)
			( gate "R1W40"
				( objectStatus "@baseboard_fab2_lib.baseboard_fab2(sch_1):page188_i128" )
			)
			( gate "R1W41"
				( objectStatus "@baseboard_fab2_lib.baseboard_fab2(sch_1):page188_i129" )
			)
			( gate "R7W13"
				( objectStatus "@baseboard_fab2_lib.baseboard_fab2(sch_1):page119_i226" )
			)
			( gate "R7W14"
				( objectStatus "@baseboard_fab2_lib.baseboard_fab2(sch_1):page120_i274" )
			)
			( gate "R7W15"
				( objectStatus "@baseboard_fab2_lib.baseboard_fab2(sch_1):page119_i227" )
			)
			( gate "R8C21"
				( objectStatus "@baseboard_fab2_lib.baseboard_fab2(sch_1):page120_i275" )
			)
			( gate "R2U50"
				( objectStatus "@baseboard_fab2_lib.baseboard_fab2(sch_1):page119_i228" )
			)
			( gate "R1W42"
				( objectStatus "@baseboard_fab2_lib.baseboard_fab2(sch_1):page188_i131" )
			)
			( gate "R1W43"
				( objectStatus "@baseboard_fab2_lib.baseboard_fab2(sch_1):page188_i132" )
			)
			( gate "R1W44"
				( objectStatus "@baseboard_fab2_lib.baseboard_fab2(sch_1):page188_i133" )
			)
			( gate "R1W45"
				( objectStatus "@baseboard_fab2_lib.baseboard_fab2(sch_1):page188_i134" )
			)
			( gate "R7W18"
				( objectStatus "@baseboard_fab2_lib.baseboard_fab2(sch_1):page120_i277" )
			)
			( gate "R9P7"
				( objectStatus "@baseboard_fab2_lib.baseboard_fab2(sch_1):page200_i252" )
			)
			( gate "L1M2"
				( objectStatus "@baseboard_fab2_lib.baseboard_fab2(sch_1):page176_i181" )
			)
			( gate "L7G2"
				( objectStatus "@baseboard_fab2_lib.baseboard_fab2(sch_1):page216_i155" )
			)
			( gate "R1D20"
				( objectStatus "@baseboard_fab2_lib.baseboard_fab2(sch_1):page200_i253" )
			)
			( gate "R9L9"
				( objectStatus "@baseboard_fab2_lib.baseboard_fab2(sch_1):page227_i154" )
			)
			( gate "R9L4"
				( objectStatus "@baseboard_fab2_lib.baseboard_fab2(sch_1):page227_i155" )
			)
			( gate "C8C1"
				( objectStatus "@baseboard_fab2_lib.baseboard_fab2(sch_1):page118_i178" )
			)
			( gate "C8C2"
				( objectStatus "@baseboard_fab2_lib.baseboard_fab2(sch_1):page118_i179" )
			)
			( gate "R9T8"
				( objectStatus "@baseboard_fab2_lib.baseboard_fab2(sch_1):page181_i137" )
			)
			( gate "C25W101"
				( objectStatus "@baseboard_fab2_lib.baseboard_fab2(sch_1):page269_i79" )
			)
			( gate "R8W10"
				( objectStatus "@baseboard_fab2_lib.baseboard_fab2(sch_1):page245_i56" )
			)
			( gate "R8W11"
				( objectStatus "@baseboard_fab2_lib.baseboard_fab2(sch_1):page245_i57" )
			)
			( gate "R8W12"
				( objectStatus "@baseboard_fab2_lib.baseboard_fab2(sch_1):page245_i58" )
			)
			( gate "R8W13"
				( objectStatus "@baseboard_fab2_lib.baseboard_fab2(sch_1):page245_i59" )
			)
			( gate "R8W14"
				( objectStatus "@baseboard_fab2_lib.baseboard_fab2(sch_1):page245_i60" )
			)
			( gate "U8W1"
				( objectStatus "@baseboard_fab2_lib.baseboard_fab2(sch_1):page245_i64" )
			)
			( gate "U8W2"
				( objectStatus "@baseboard_fab2_lib.baseboard_fab2(sch_1):page245_i66" )
			)
			( gate "C8W6"
				( objectStatus "@baseboard_fab2_lib.baseboard_fab2(sch_1):page245_i71" )
			)
			( gate "C8W5"
				( objectStatus "@baseboard_fab2_lib.baseboard_fab2(sch_1):page245_i74" )
			)
			( gate "R8W15"
				( objectStatus "@baseboard_fab2_lib.baseboard_fab2(sch_1):page245_i78" )
			)
			( gate "R7W19"
				( objectStatus "@baseboard_fab2_lib.baseboard_fab2(sch_1):page118_i180" )
			)
			( gate "R7W20"
				( objectStatus "@baseboard_fab2_lib.baseboard_fab2(sch_1):page120_i278" )
			)
			( gate "R1T4"
				( objectStatus "@baseboard_fab2_lib.baseboard_fab2(sch_1):page164_i100" )
			)
			( gate "R25W101"
				( objectStatus "@baseboard_fab2_lib.baseboard_fab2(sch_1):page150_i241" )
			)
			( gate "U6W12"
				( objectStatus "@baseboard_fab2_lib.baseboard_fab2(sch_1):page176_i182" )
			)
			( gate "F30W1"
				( objectStatus "@baseboard_fab2_lib.baseboard_fab2(sch_1):page253_i44" )
			)
			( gate "R7W22"
				( objectStatus "@baseboard_fab2_lib.baseboard_fab2(sch_1):page119_i230" )
			)
			( gate "R7W21"
				( objectStatus "@baseboard_fab2_lib.baseboard_fab2(sch_1):page118_i183" )
			)
			( gate "R25W115"
				( objectStatus "@baseboard_fab2_lib.baseboard_fab2(sch_1):page150_i242" )
			)
			( gate "R6P48"
				( objectStatus "@baseboard_fab2_lib.baseboard_fab2(sch_1):page102_i115" )
			)
			( pin "R6N10.1"
				( objectStatus "@baseboard_fab2_lib.baseboard_fab2(sch_1):page21_i149:a" )
			)
			( pin "R6N10.2"
				( objectStatus "@baseboard_fab2_lib.baseboard_fab2(sch_1):page21_i149:b" )
			)
			( pin "R6N12.1"
				( objectStatus "@baseboard_fab2_lib.baseboard_fab2(sch_1):page21_i150:a" )
			)
			( pin "R6N12.2"
				( objectStatus "@baseboard_fab2_lib.baseboard_fab2(sch_1):page21_i150:b" )
			)
			( pin "R6N11.1"
				( objectStatus "@baseboard_fab2_lib.baseboard_fab2(sch_1):page21_i151:a" )
			)
			( pin "R6N11.2"
				( objectStatus "@baseboard_fab2_lib.baseboard_fab2(sch_1):page21_i151:b" )
			)
			( pin "R6B3.1"
				( objectStatus "@baseboard_fab2_lib.baseboard_fab2(sch_1):page21_i152:a" )
			)
			( pin "R6B3.2"
				( objectStatus "@baseboard_fab2_lib.baseboard_fab2(sch_1):page21_i152:b" )
			)
			( pin "R6B5.1"
				( objectStatus "@baseboard_fab2_lib.baseboard_fab2(sch_1):page21_i153:a" )
			)
			( pin "R6B5.2"
				( objectStatus "@baseboard_fab2_lib.baseboard_fab2(sch_1):page21_i153:b" )
			)
			( pin "R6B4.1"
				( objectStatus "@baseboard_fab2_lib.baseboard_fab2(sch_1):page21_i154:a" )
			)
			( pin "R6B4.2"
				( objectStatus "@baseboard_fab2_lib.baseboard_fab2(sch_1):page21_i154:b" )
			)
			( pin "R6B2.1"
				( objectStatus "@baseboard_fab2_lib.baseboard_fab2(sch_1):page21_i159:a" )
			)
			( pin "R6B2.2"
				( objectStatus "@baseboard_fab2_lib.baseboard_fab2(sch_1):page21_i159:b" )
			)
			( pin "R6B1.1"
				( objectStatus "@baseboard_fab2_lib.baseboard_fab2(sch_1):page21_i161:a" )
			)
			( pin "R6B1.2"
				( objectStatus "@baseboard_fab2_lib.baseboard_fab2(sch_1):page21_i161:b" )
			)
			( pin "R6N2.1"
				( objectStatus "@baseboard_fab2_lib.baseboard_fab2(sch_1):page21_i163:a" )
			)
			( pin "R6N2.2"
				( objectStatus "@baseboard_fab2_lib.baseboard_fab2(sch_1):page21_i163:b" )
			)
			( pin "R6N1.1"
				( objectStatus "@baseboard_fab2_lib.baseboard_fab2(sch_1):page21_i164:a" )
			)
			( pin "R6N1.2"
				( objectStatus "@baseboard_fab2_lib.baseboard_fab2(sch_1):page21_i164:b" )
			)
			( pin "R5D1.1"
				( objectStatus "@baseboard_fab2_lib.baseboard_fab2(sch_1):page21_i177:a" )
			)
			( pin "R5D1.2"
				( objectStatus "@baseboard_fab2_lib.baseboard_fab2(sch_1):page21_i177:b" )
			)
			( pin "R5D2.1"
				( objectStatus "@baseboard_fab2_lib.baseboard_fab2(sch_1):page21_i178:a" )
			)
			( pin "R5D2.2"
				( objectStatus "@baseboard_fab2_lib.baseboard_fab2(sch_1):page21_i178:b" )
			)
			( pin "R6D1.1"
				( objectStatus "@baseboard_fab2_lib.baseboard_fab2(sch_1):page21_i179:a" )
			)
			( pin "R6D1.2"
				( objectStatus "@baseboard_fab2_lib.baseboard_fab2(sch_1):page21_i179:b" )
			)
			( pin "R4P8.1"
				( objectStatus "@baseboard_fab2_lib.baseboard_fab2(sch_1):page21_i180:a" )
			)
			( pin "R4P8.2"
				( objectStatus "@baseboard_fab2_lib.baseboard_fab2(sch_1):page21_i180:b" )
			)
			( pin "R4P10.1"
				( objectStatus "@baseboard_fab2_lib.baseboard_fab2(sch_1):page21_i181:a" )
			)
			( pin "R4P10.2"
				( objectStatus "@baseboard_fab2_lib.baseboard_fab2(sch_1):page21_i181:b" )
			)
			( pin "R4P11.1"
				( objectStatus "@baseboard_fab2_lib.baseboard_fab2(sch_1):page21_i182:a" )
			)
			( pin "R4P11.2"
				( objectStatus "@baseboard_fab2_lib.baseboard_fab2(sch_1):page21_i182:b" )
			)
			( pin "R6D11.1"
				( objectStatus "@baseboard_fab2_lib.baseboard_fab2(sch_1):page21_i184:a" )
			)
			( pin "R6D11.2"
				( objectStatus "@baseboard_fab2_lib.baseboard_fab2(sch_1):page21_i184:b" )
			)
			( pin "R4P3.1"
				( objectStatus "@baseboard_fab2_lib.baseboard_fab2(sch_1):page21_i186:a" )
			)
			( pin "R4P3.2"
				( objectStatus "@baseboard_fab2_lib.baseboard_fab2(sch_1):page21_i186:b" )
			)
			( pin "R4P2.1"
				( objectStatus "@baseboard_fab2_lib.baseboard_fab2(sch_1):page21_i188:a" )
			)
			( pin "R4P2.2"
				( objectStatus "@baseboard_fab2_lib.baseboard_fab2(sch_1):page21_i188:b" )
			)
			( pin "R4P4.1"
				( objectStatus "@baseboard_fab2_lib.baseboard_fab2(sch_1):page21_i189:a" )
			)
			( pin "R4P4.2"
				( objectStatus "@baseboard_fab2_lib.baseboard_fab2(sch_1):page21_i189:b" )
			)
			( pin "R6D2.1"
				( objectStatus "@baseboard_fab2_lib.baseboard_fab2(sch_1):page21_i204:a" )
			)
			( pin "R6D2.2"
				( objectStatus "@baseboard_fab2_lib.baseboard_fab2(sch_1):page21_i204:b" )
			)
			( pin "R4P19.1"
				( objectStatus "@baseboard_fab2_lib.baseboard_fab2(sch_1):page21_i219:a" )
			)
			( pin "R4P19.2"
				( objectStatus "@baseboard_fab2_lib.baseboard_fab2(sch_1):page21_i219:b" )
			)
			( pin "R5N2.1"
				( objectStatus "@baseboard_fab2_lib.baseboard_fab2(sch_1):page21_i227:a" )
			)
			( pin "R5N2.2"
				( objectStatus "@baseboard_fab2_lib.baseboard_fab2(sch_1):page21_i227:b" )
			)
			( pin "R5N1.1"
				( objectStatus "@baseboard_fab2_lib.baseboard_fab2(sch_1):page21_i238:a" )
			)
			( pin "R5N1.2"
				( objectStatus "@baseboard_fab2_lib.baseboard_fab2(sch_1):page21_i238:b" )
			)
			( pin "R5N5.1"
				( objectStatus "@baseboard_fab2_lib.baseboard_fab2(sch_1):page21_i239:a" )
			)
			( pin "R5N5.2"
				( objectStatus "@baseboard_fab2_lib.baseboard_fab2(sch_1):page21_i239:b" )
			)
			( pin "R5N3.1"
				( objectStatus "@baseboard_fab2_lib.baseboard_fab2(sch_1):page21_i240:a" )
			)
			( pin "R5N3.2"
				( objectStatus "@baseboard_fab2_lib.baseboard_fab2(sch_1):page21_i240:b" )
			)
			( pin "R5N4.1"
				( objectStatus "@baseboard_fab2_lib.baseboard_fab2(sch_1):page21_i241:a" )
			)
			( pin "R5N4.2"
				( objectStatus "@baseboard_fab2_lib.baseboard_fab2(sch_1):page21_i241:b" )
			)
			( pin "R4P18.1"
				( objectStatus "@baseboard_fab2_lib.baseboard_fab2(sch_1):page21_i244:a" )
			)
			( pin "R4P18.2"
				( objectStatus "@baseboard_fab2_lib.baseboard_fab2(sch_1):page21_i244:b" )
			)
			( pin "R4R5.1"
				( objectStatus "@baseboard_fab2_lib.baseboard_fab2(sch_1):page21_i258:a" )
			)
			( pin "R4R5.2"
				( objectStatus "@baseboard_fab2_lib.baseboard_fab2(sch_1):page21_i258:b" )
			)
			( pin "U5D1.AU24"
				( objectStatus "@baseboard_fab2_lib.baseboard_fab2(sch_1):page21_i259:bclk0_dn" )
			)
			( pin "U5D1.AW24"
				( objectStatus "@baseboard_fab2_lib.baseboard_fab2(sch_1):page21_i259:bclk0_dp" )
			)
			( pin "U5D1.CR26"
				( objectStatus "@baseboard_fab2_lib.baseboard_fab2(sch_1):page21_i259:bclk1_dn" )
			)
			( pin "U5D1.CP27"
				( objectStatus "@baseboard_fab2_lib.baseboard_fab2(sch_1):page21_i259:bclk1_dp" )
			)
			( pin "U5D1.CT25"
				( objectStatus "@baseboard_fab2_lib.baseboard_fab2(sch_1):page21_i259:bclk2_dn" )
			)
			( pin "U5D1.CU26"
				( objectStatus "@baseboard_fab2_lib.baseboard_fab2(sch_1):page21_i259:bclk2_dp" )
			)
			( pin "U5D1.BA20"
				( objectStatus "@baseboard_fab2_lib.baseboard_fab2(sch_1):page21_i259:bist_enable" )
			)
			( pin "U5D1.BD23"
				( objectStatus "@baseboard_fab2_lib.baseboard_fab2(sch_1):page21_i259:bmcinit" )
			)
			( pin "U5D1.AJ10"
				( objectStatus "@baseboard_fab2_lib.baseboard_fab2(sch_1):page21_i259:bpm_n(0)" )
			)
			( pin "U5D1.AH11"
				( objectStatus "@baseboard_fab2_lib.baseboard_fab2(sch_1):page21_i259:bpm_n(1)" )
			)
			( pin "U5D1.AG10"
				( objectStatus "@baseboard_fab2_lib.baseboard_fab2(sch_1):page21_i259:bpm_n(2)" )
			)
			( pin "U5D1.AF11"
				( objectStatus "@baseboard_fab2_lib.baseboard_fab2(sch_1):page21_i259:bpm_n(3)" )
			)
			( pin "U5D1.AA12"
				( objectStatus "@baseboard_fab2_lib.baseboard_fab2(sch_1):page21_i259:bpm_n(4)" )
			)
			( pin "U5D1.Y11"
				( objectStatus "@baseboard_fab2_lib.baseboard_fab2(sch_1):page21_i259:bpm_n(5)" )
			)
			( pin "U5D1.AE12"
				( objectStatus "@baseboard_fab2_lib.baseboard_fab2(sch_1):page21_i259:bpm_n(6)" )
			)
			( pin "U5D1.AC12"
				( objectStatus "@baseboard_fab2_lib.baseboard_fab2(sch_1):page21_i259:bpm_n(7)" )
			)
			( pin "U5D1.AL14"
				( objectStatus "@baseboard_fab2_lib.baseboard_fab2(sch_1):page21_i259:caterr_n" )
			)
			( pin "U5D1.AJ64"
				( objectStatus "@baseboard_fab2_lib.baseboard_fab2(sch_1):page21_i259:ddr0_cavref" )
			)
			( pin "U5D1.AK63"
				( objectStatus "@baseboard_fab2_lib.baseboard_fab2(sch_1):page21_i259:ddr1_cavref" )
			)
			( pin "U5D1.AH63"
				( objectStatus "@baseboard_fab2_lib.baseboard_fab2(sch_1):page21_i259:ddr2_cavref" )
			)
			( pin "U5D1.CP61"
				( objectStatus "@baseboard_fab2_lib.baseboard_fab2(sch_1):page21_i259:ddr3_cavref" )
			)
			( pin "U5D1.CT61"
				( objectStatus "@baseboard_fab2_lib.baseboard_fab2(sch_1):page21_i259:ddr4_cavref" )
			)
			( pin "U5D1.CV61"
				( objectStatus "@baseboard_fab2_lib.baseboard_fab2(sch_1):page21_i259:ddr5_cavref" )
			)
			( pin "U5D1.AN30"
				( objectStatus "@baseboard_fab2_lib.baseboard_fab2(sch_1):page21_i259:ddr012_dram_pwr_ok" )
			)
			( pin "U5D1.Y43"
				( objectStatus "@baseboard_fab2_lib.baseboard_fab2(sch_1):page21_i259:ddr012_rcomp(0)" )
			)
			( pin "U5D1.AB43"
				( objectStatus "@baseboard_fab2_lib.baseboard_fab2(sch_1):page21_i259:ddr012_rcomp(1)" )
			)
			( pin "U5D1.AC42"
				( objectStatus "@baseboard_fab2_lib.baseboard_fab2(sch_1):page21_i259:ddr012_rcomp(2)" )
			)
			( pin "U5D1.U64"
				( objectStatus "@baseboard_fab2_lib.baseboard_fab2(sch_1):page21_i259:ddr012_reset_n" )
			)
			( pin "U5D1.AJ18"
				( objectStatus "@baseboard_fab2_lib.baseboard_fab2(sch_1):page21_i259:ddr012_spdscl" )
			)
			( pin "U5D1.AF17"
				( objectStatus "@baseboard_fab2_lib.baseboard_fab2(sch_1):page21_i259:ddr012_spdsda" )
			)
			( pin "U5D1.CR28"
				( objectStatus "@baseboard_fab2_lib.baseboard_fab2(sch_1):page21_i259:ddr345_dram_pwr_ok" )
			)
			( pin "U5D1.DC48"
				( objectStatus "@baseboard_fab2_lib.baseboard_fab2(sch_1):page21_i259:ddr345_rcomp(0)" )
			)
			( pin "U5D1.DD47"
				( objectStatus "@baseboard_fab2_lib.baseboard_fab2(sch_1):page21_i259:ddr345_rcomp(1)" )
			)
			( pin "U5D1.DD49"
				( objectStatus "@baseboard_fab2_lib.baseboard_fab2(sch_1):page21_i259:ddr345_rcomp(2)" )
			)
			( pin "U5D1.DV63"
				( objectStatus "@baseboard_fab2_lib.baseboard_fab2(sch_1):page21_i259:ddr345_reset_n" )
			)
			( pin "U5D1.AE18"
				( objectStatus "@baseboard_fab2_lib.baseboard_fab2(sch_1):page21_i259:ddr345_spdscl" )
			)
			( pin "U5D1.AD17"
				( objectStatus "@baseboard_fab2_lib.baseboard_fab2(sch_1):page21_i259:ddr345_spdsda" )
			)
			( pin "U5D1.AJ14"
				( objectStatus "@baseboard_fab2_lib.baseboard_fab2(sch_1):page21_i259:ear_n" )
			)
			( pin "U5D1.AJ12"
				( objectStatus "@baseboard_fab2_lib.baseboard_fab2(sch_1):page21_i259:error_n(0)" )
			)
			( pin "U5D1.AK11"
				( objectStatus "@baseboard_fab2_lib.baseboard_fab2(sch_1):page21_i259:error_n(1)" )
			)
			( pin "U5D1.AL12"
				( objectStatus "@baseboard_fab2_lib.baseboard_fab2(sch_1):page21_i259:error_n(2)" )
			)
			( pin "U5D1.AV17"
				( objectStatus "@baseboard_fab2_lib.baseboard_fab2(sch_1):page21_i259:frmagent" )
			)
			( pin "U5D1.AE20"
				( objectStatus "@baseboard_fab2_lib.baseboard_fab2(sch_1):page21_i259:legacy_skt" )
			)
			( pin "U5D1.CU32"
				( objectStatus "@baseboard_fab2_lib.baseboard_fab2(sch_1):page21_i259:mcp01_rbias(0)" )
			)
			( pin "U5D1.CT31"
				( objectStatus "@baseboard_fab2_lib.baseboard_fab2(sch_1):page21_i259:mcp01_rbias(1)" )
			)
			( pin "U5D1.AH13"
				( objectStatus "@baseboard_fab2_lib.baseboard_fab2(sch_1):page21_i259:mem_hot_c012_n" )
			)
			( pin "U5D1.AF13"
				( objectStatus "@baseboard_fab2_lib.baseboard_fab2(sch_1):page21_i259:mem_hot_c345_n" )
			)
			( pin "U5D1.AN20"
				( objectStatus "@baseboard_fab2_lib.baseboard_fab2(sch_1):page21_i259:msmi_n" )
			)
			( pin "U5D1.AP11"
				( objectStatus "@baseboard_fab2_lib.baseboard_fab2(sch_1):page21_i259:nmi" )
			)
			( pin "U5D1.CP29"
				( objectStatus "@baseboard_fab2_lib.baseboard_fab2(sch_1):page21_i259:pe3_rbias(0)" )
			)
			( pin "U5D1.CR30"
				( objectStatus "@baseboard_fab2_lib.baseboard_fab2(sch_1):page21_i259:pe3_rbias(1)" )
			)
			( pin "U5D1.CN30"
				( objectStatus "@baseboard_fab2_lib.baseboard_fab2(sch_1):page21_i259:pe012_rbias(0)" )
			)
			( pin "U5D1.CL30"
				( objectStatus "@baseboard_fab2_lib.baseboard_fab2(sch_1):page21_i259:pe012_rbias(1)" )
			)
			( pin "U5D1.AM19"
				( objectStatus "@baseboard_fab2_lib.baseboard_fab2(sch_1):page21_i259:pe_hp_scl" )
			)
			( pin "U5D1.AL18"
				( objectStatus "@baseboard_fab2_lib.baseboard_fab2(sch_1):page21_i259:pe_hp_sda" )
			)
			( pin "U5D1.AU12"
				( objectStatus "@baseboard_fab2_lib.baseboard_fab2(sch_1):page21_i259:peci" )
			)
			( pin "U5D1.CU58"
				( objectStatus "@baseboard_fab2_lib.baseboard_fab2(sch_1):page21_i259:pirom_addr(0)" )
			)
			( pin "U5D1.CV57"
				( objectStatus "@baseboard_fab2_lib.baseboard_fab2(sch_1):page21_i259:pirom_addr(1)" )
			)
			( pin "U5D1.CW56"
				( objectStatus "@baseboard_fab2_lib.baseboard_fab2(sch_1):page21_i259:pirom_addr(2)" )
			)
			( pin "U5D1.DC72"
				( objectStatus "@baseboard_fab2_lib.baseboard_fab2(sch_1):page21_i259:pkgid(0)" )
			)
			( pin "U5D1.CW72"
				( objectStatus "@baseboard_fab2_lib.baseboard_fab2(sch_1):page21_i259:pkgid(1)" )
			)
			( pin "U5D1.DA72"
				( objectStatus "@baseboard_fab2_lib.baseboard_fab2(sch_1):page21_i259:pkgid(2)" )
			)
			( pin "U5D1.AF15"
				( objectStatus "@baseboard_fab2_lib.baseboard_fab2(sch_1):page21_i259:pm_fast_wake_n" )
			)
			( pin "U5D1.AR14"
				( objectStatus "@baseboard_fab2_lib.baseboard_fab2(sch_1):page21_i259:pmsync" )
			)
			( pin "U5D1.AT19"
				( objectStatus "@baseboard_fab2_lib.baseboard_fab2(sch_1):page21_i259:pmsync_clk" )
			)
			( pin "U5D1.AG16"
				( objectStatus "@baseboard_fab2_lib.baseboard_fab2(sch_1):page21_i259:prdy_n" )
			)
			( pin "U5D1.AR12"
				( objectStatus "@baseboard_fab2_lib.baseboard_fab2(sch_1):page21_i259:preq_n" )
			)
			( pin "U5D1.CY71"
				( objectStatus "@baseboard_fab2_lib.baseboard_fab2(sch_1):page21_i259:proc_id(0)" )
			)
			( pin "U5D1.DB71"
				( objectStatus "@baseboard_fab2_lib.baseboard_fab2(sch_1):page21_i259:proc_id(1)" )
			)
			( pin "U5D1.AB17"
				( objectStatus "@baseboard_fab2_lib.baseboard_fab2(sch_1):page21_i259:procdis_n" )
			)
			( pin "U5D1.AC16"
				( objectStatus "@baseboard_fab2_lib.baseboard_fab2(sch_1):page21_i259:prochot_n" )
			)
			( pin "U5D1.BC24"
				( objectStatus "@baseboard_fab2_lib.baseboard_fab2(sch_1):page21_i259:pwrgood" )
			)
			( pin "U5D1.AP21"
				( objectStatus "@baseboard_fab2_lib.baseboard_fab2(sch_1):page21_i259:reset_n" )
			)
			( pin "U5D1.AR18"
				( objectStatus "@baseboard_fab2_lib.baseboard_fab2(sch_1):page21_i259:safe_mode_boot" )
			)
			( pin "U5D1.AB13"
				( objectStatus "@baseboard_fab2_lib.baseboard_fab2(sch_1):page21_i259:sktocc_n" )
			)
			( pin "U5D1.CV59"
				( objectStatus "@baseboard_fab2_lib.baseboard_fab2(sch_1):page21_i259:sm_wp" )
			)
			( pin "U5D1.CT59"
				( objectStatus "@baseboard_fab2_lib.baseboard_fab2(sch_1):page21_i259:smbclk" )
			)
			( pin "U5D1.CW58"
				( objectStatus "@baseboard_fab2_lib.baseboard_fab2(sch_1):page21_i259:smbdat" )
			)
			( pin "U5D1.AU22"
				( objectStatus "@baseboard_fab2_lib.baseboard_fab2(sch_1):page21_i259:socket_id(0)" )
			)
			( pin "U5D1.AU16"
				( objectStatus "@baseboard_fab2_lib.baseboard_fab2(sch_1):page21_i259:socket_id(1)" )
			)
			( pin "U5D1.AU20"
				( objectStatus "@baseboard_fab2_lib.baseboard_fab2(sch_1):page21_i259:socket_id(2)" )
			)
			( pin "U5D1.DE44"
				( objectStatus "@baseboard_fab2_lib.baseboard_fab2(sch_1):page21_i259:svidalert_n(0)" )
			)
			( pin "U5D1.DL44"
				( objectStatus "@baseboard_fab2_lib.baseboard_fab2(sch_1):page21_i259:svidalert_n(1)" )
			)
			( pin "U5D1.DC44"
				( objectStatus "@baseboard_fab2_lib.baseboard_fab2(sch_1):page21_i259:svidclk(0)" )
			)
			( pin "U5D1.DG44"
				( objectStatus "@baseboard_fab2_lib.baseboard_fab2(sch_1):page21_i259:svidclk(1)" )
			)
			( pin "U5D1.DB45"
				( objectStatus "@baseboard_fab2_lib.baseboard_fab2(sch_1):page21_i259:sviddata(0)" )
			)
			( pin "U5D1.DJ44"
				( objectStatus "@baseboard_fab2_lib.baseboard_fab2(sch_1):page21_i259:sviddata(1)" )
			)
			( pin "U5D1.AA14"
				( objectStatus "@baseboard_fab2_lib.baseboard_fab2(sch_1):page21_i259:tck" )
			)
			( pin "U5D1.AC14"
				( objectStatus "@baseboard_fab2_lib.baseboard_fab2(sch_1):page21_i259:tdi" )
			)
			( pin "U5D1.AE14"
				( objectStatus "@baseboard_fab2_lib.baseboard_fab2(sch_1):page21_i259:tdo" )
			)
			( pin "U5D1.AY19"
				( objectStatus "@baseboard_fab2_lib.baseboard_fab2(sch_1):page21_i259:test_12" )
			)
			( pin "U5D1.DB51"
				( objectStatus "@baseboard_fab2_lib.baseboard_fab2(sch_1):page21_i259:test_13" )
			)
			( pin "U5D1.DC50"
				( objectStatus "@baseboard_fab2_lib.baseboard_fab2(sch_1):page21_i259:test_14" )
			)
			( pin "U5D1.AW14"
				( objectStatus "@baseboard_fab2_lib.baseboard_fab2(sch_1):page21_i259:test_15" )
			)
			( pin "U5D1.AB15"
				( objectStatus "@baseboard_fab2_lib.baseboard_fab2(sch_1):page21_i259:thermtrip_n" )
			)
			( pin "U5D1.W14"
				( objectStatus "@baseboard_fab2_lib.baseboard_fab2(sch_1):page21_i259:tms" )
			)
			( pin "U5D1.Y13"
				( objectStatus "@baseboard_fab2_lib.baseboard_fab2(sch_1):page21_i259:trst_n" )
			)
			( pin "U5D1.AM11"
				( objectStatus "@baseboard_fab2_lib.baseboard_fab2(sch_1):page21_i259:tsc_sync" )
			)
			( pin "U5D1.AW18"
				( objectStatus "@baseboard_fab2_lib.baseboard_fab2(sch_1):page21_i259:txt_agent" )
			)
			( pin "U5D1.AV15"
				( objectStatus "@baseboard_fab2_lib.baseboard_fab2(sch_1):page21_i259:txt_plten" )
			)
			( pin "U5D1.AT29"
				( objectStatus "@baseboard_fab2_lib.baseboard_fab2(sch_1):page21_i259:upi01_rbias(0)" )
			)
			( pin "U5D1.AP29"
				( objectStatus "@baseboard_fab2_lib.baseboard_fab2(sch_1):page21_i259:upi01_rbias(1)" )
			)
			( pin "U5D1.CL28"
				( objectStatus "@baseboard_fab2_lib.baseboard_fab2(sch_1):page21_i259:upi2_rbias(0)" )
			)
			( pin "U5D1.CK29"
				( objectStatus "@baseboard_fab2_lib.baseboard_fab2(sch_1):page21_i259:upi2_rbias(1)" )
			)
			( pin "R5R1.1"
				( objectStatus "@baseboard_fab2_lib.baseboard_fab2(sch_1):page22_i188:a" )
			)
			( pin "R5R1.2"
				( objectStatus "@baseboard_fab2_lib.baseboard_fab2(sch_1):page22_i188:b" )
			)
			( pin "R5P4.1"
				( objectStatus "@baseboard_fab2_lib.baseboard_fab2(sch_1):page22_i190:a" )
			)
			( pin "R5P4.2"
				( objectStatus "@baseboard_fab2_lib.baseboard_fab2(sch_1):page22_i190:b" )
			)
			( pin "U5D1.AV21"
				( objectStatus "@baseboard_fab2_lib.baseboard_fab2(sch_1):page22_i204:debug_en_n" )
			)
			( pin "U5D1.AW12"
				( objectStatus "@baseboard_fab2_lib.baseboard_fab2(sch_1):page22_i204:dmimode_override" )
			)
			( pin "U5D1.AU14"
				( objectStatus "@baseboard_fab2_lib.baseboard_fab2(sch_1):page22_i204:fivr_fault" )
			)
			( pin "U5D1.AP17"
				( objectStatus "@baseboard_fab2_lib.baseboard_fab2(sch_1):page22_i204:pwr_debug_n" )
			)
			( pin "U5D1.AP61"
				( objectStatus "@baseboard_fab2_lib.baseboard_fab2(sch_1):page22_i204:rsvd(194)" )
			)
			( pin "U5D1.AP27"
				( objectStatus "@baseboard_fab2_lib.baseboard_fab2(sch_1):page22_i204:rsvd(195)" )
			)
			( pin "U5D1.AP25"
				( objectStatus "@baseboard_fab2_lib.baseboard_fab2(sch_1):page22_i204:rsvd(196)" )
			)
			( pin "U5D1.AP23"
				( objectStatus "@baseboard_fab2_lib.baseboard_fab2(sch_1):page22_i204:rsvd(197)" )
			)
			( pin "U5D1.AN62"
				( objectStatus "@baseboard_fab2_lib.baseboard_fab2(sch_1):page22_i204:rsvd(198)" )
			)
			( pin "U5D1.AN60"
				( objectStatus "@baseboard_fab2_lib.baseboard_fab2(sch_1):page22_i204:rsvd(199)" )
			)
			( pin "U5D1.AN26"
				( objectStatus "@baseboard_fab2_lib.baseboard_fab2(sch_1):page22_i204:rsvd(200)" )
			)
			( pin "U5D1.AN24"
				( objectStatus "@baseboard_fab2_lib.baseboard_fab2(sch_1):page22_i204:rsvd(201)" )
			)
			( pin "U5D1.AN22"
				( objectStatus "@baseboard_fab2_lib.baseboard_fab2(sch_1):page22_i204:rsvd(202)" )
			)
			( pin "U5D1.AN18"
				( objectStatus "@baseboard_fab2_lib.baseboard_fab2(sch_1):page22_i204:rsvd(203)" )
			)
			( pin "U5D1.AM61"
				( objectStatus "@baseboard_fab2_lib.baseboard_fab2(sch_1):page22_i204:rsvd(204)" )
			)
			( pin "U5D1.AM59"
				( objectStatus "@baseboard_fab2_lib.baseboard_fab2(sch_1):page22_i204:rsvd(205)" )
			)
			( pin "U5D1.AM27"
				( objectStatus "@baseboard_fab2_lib.baseboard_fab2(sch_1):page22_i204:rsvd(206)" )
			)
			( pin "U5D1.AM25"
				( objectStatus "@baseboard_fab2_lib.baseboard_fab2(sch_1):page22_i204:rsvd(207)" )
			)
			( pin "U5D1.AM23"
				( objectStatus "@baseboard_fab2_lib.baseboard_fab2(sch_1):page22_i204:rsvd(208)" )
			)
			( pin "U5D1.AM21"
				( objectStatus "@baseboard_fab2_lib.baseboard_fab2(sch_1):page22_i204:rsvd(209)" )
			)
			( pin "U5D1.AL62"
				( objectStatus "@baseboard_fab2_lib.baseboard_fab2(sch_1):page22_i204:rsvd(210)" )
			)
			( pin "U5D1.AL60"
				( objectStatus "@baseboard_fab2_lib.baseboard_fab2(sch_1):page22_i204:rsvd(211)" )
			)
			( pin "U5D1.AL58"
				( objectStatus "@baseboard_fab2_lib.baseboard_fab2(sch_1):page22_i204:rsvd(212)" )
			)
			( pin "U5D1.AL26"
				( objectStatus "@baseboard_fab2_lib.baseboard_fab2(sch_1):page22_i204:rsvd(213)" )
			)
			( pin "U5D1.AL22"
				( objectStatus "@baseboard_fab2_lib.baseboard_fab2(sch_1):page22_i204:rsvd(214)" )
			)
			( pin "U5D1.AL20"
				( objectStatus "@baseboard_fab2_lib.baseboard_fab2(sch_1):page22_i204:rsvd(215)" )
			)
			( pin "U5D1.AK69"
				( objectStatus "@baseboard_fab2_lib.baseboard_fab2(sch_1):page22_i204:rsvd(216)" )
			)
			( pin "U5D1.AK61"
				( objectStatus "@baseboard_fab2_lib.baseboard_fab2(sch_1):page22_i204:rsvd(217)" )
			)
			( pin "U5D1.AK59"
				( objectStatus "@baseboard_fab2_lib.baseboard_fab2(sch_1):page22_i204:rsvd(218)" )
			)
			( pin "U5D1.AK57"
				( objectStatus "@baseboard_fab2_lib.baseboard_fab2(sch_1):page22_i204:rsvd(219)" )
			)
			( pin "U5D1.AK27"
				( objectStatus "@baseboard_fab2_lib.baseboard_fab2(sch_1):page22_i204:rsvd(220)" )
			)
			( pin "U5D1.AK21"
				( objectStatus "@baseboard_fab2_lib.baseboard_fab2(sch_1):page22_i204:rsvd(221)" )
			)
			( pin "U5D1.AJ70"
				( objectStatus "@baseboard_fab2_lib.baseboard_fab2(sch_1):page22_i204:rsvd(222)" )
			)
			( pin "U5D1.AJ62"
				( objectStatus "@baseboard_fab2_lib.baseboard_fab2(sch_1):page22_i204:rsvd(223)" )
			)
			( pin "U5D1.AJ60"
				( objectStatus "@baseboard_fab2_lib.baseboard_fab2(sch_1):page22_i204:rsvd(224)" )
			)
			( pin "U5D1.AJ58"
				( objectStatus "@baseboard_fab2_lib.baseboard_fab2(sch_1):page22_i204:rsvd(225)" )
			)
			( pin "U5D1.AJ56"
				( objectStatus "@baseboard_fab2_lib.baseboard_fab2(sch_1):page22_i204:rsvd(226)" )
			)
			( pin "U5D1.AJ20"
				( objectStatus "@baseboard_fab2_lib.baseboard_fab2(sch_1):page22_i204:rsvd(227)" )
			)
			( pin "U5D1.AH73"
				( objectStatus "@baseboard_fab2_lib.baseboard_fab2(sch_1):page22_i204:rsvd(228)" )
			)
			( pin "U5D1.AH71"
				( objectStatus "@baseboard_fab2_lib.baseboard_fab2(sch_1):page22_i204:rsvd(229)" )
			)
			( pin "U5D1.AH57"
				( objectStatus "@baseboard_fab2_lib.baseboard_fab2(sch_1):page22_i204:rsvd(230)" )
			)
			( pin "U5D1.AH55"
				( objectStatus "@baseboard_fab2_lib.baseboard_fab2(sch_1):page22_i204:rsvd(231)" )
			)
			( pin "U5D1.AH19"
				( objectStatus "@baseboard_fab2_lib.baseboard_fab2(sch_1):page22_i204:rsvd(232)" )
			)
			( pin "U5D1.AH15"
				( objectStatus "@baseboard_fab2_lib.baseboard_fab2(sch_1):page22_i204:rsvd(233)" )
			)
			( pin "U5D1.AG72"
				( objectStatus "@baseboard_fab2_lib.baseboard_fab2(sch_1):page22_i204:rsvd(234)" )
			)
			( pin "U5D1.AG56"
				( objectStatus "@baseboard_fab2_lib.baseboard_fab2(sch_1):page22_i204:rsvd(235)" )
			)
			( pin "U5D1.AG54"
				( objectStatus "@baseboard_fab2_lib.baseboard_fab2(sch_1):page22_i204:rsvd(236)" )
			)
			( pin "U5D1.AG52"
				( objectStatus "@baseboard_fab2_lib.baseboard_fab2(sch_1):page22_i204:rsvd(237)" )
			)
			( pin "U5D1.AG50"
				( objectStatus "@baseboard_fab2_lib.baseboard_fab2(sch_1):page22_i204:rsvd(238)" )
			)
			( pin "U5D1.AG48"
				( objectStatus "@baseboard_fab2_lib.baseboard_fab2(sch_1):page22_i204:rsvd(239)" )
			)
			( pin "U5D1.AG20"
				( objectStatus "@baseboard_fab2_lib.baseboard_fab2(sch_1):page22_i204:rsvd(240)" )
			)
			( pin "U5D1.AF71"
				( objectStatus "@baseboard_fab2_lib.baseboard_fab2(sch_1):page22_i204:rsvd(241)" )
			)
			( pin "U5D1.AF53"
				( objectStatus "@baseboard_fab2_lib.baseboard_fab2(sch_1):page22_i204:rsvd(242)" )
			)
			( pin "U5D1.AF51"
				( objectStatus "@baseboard_fab2_lib.baseboard_fab2(sch_1):page22_i204:rsvd(243)" )
			)
			( pin "U5D1.AF49"
				( objectStatus "@baseboard_fab2_lib.baseboard_fab2(sch_1):page22_i204:rsvd(244)" )
			)
			( pin "U5D1.AF47"
				( objectStatus "@baseboard_fab2_lib.baseboard_fab2(sch_1):page22_i204:rsvd(245)" )
			)
			( pin "U5D1.AF19"
				( objectStatus "@baseboard_fab2_lib.baseboard_fab2(sch_1):page22_i204:rsvd(246)" )
			)
			( pin "U5D1.AE72"
				( objectStatus "@baseboard_fab2_lib.baseboard_fab2(sch_1):page22_i204:rsvd(247)" )
			)
			( pin "U5D1.AE52"
				( objectStatus "@baseboard_fab2_lib.baseboard_fab2(sch_1):page22_i204:rsvd(248)" )
			)
			( pin "U5D1.AE50"
				( objectStatus "@baseboard_fab2_lib.baseboard_fab2(sch_1):page22_i204:rsvd(249)" )
			)
			( pin "U5D1.AE48"
				( objectStatus "@baseboard_fab2_lib.baseboard_fab2(sch_1):page22_i204:rsvd(250)" )
			)
			( pin "U5D1.AE46"
				( objectStatus "@baseboard_fab2_lib.baseboard_fab2(sch_1):page22_i204:rsvd(251)" )
			)
			( pin "U5D1.AD51"
				( objectStatus "@baseboard_fab2_lib.baseboard_fab2(sch_1):page22_i204:rsvd(252)" )
			)
			( pin "U5D1.AD49"
				( objectStatus "@baseboard_fab2_lib.baseboard_fab2(sch_1):page22_i204:rsvd(253)" )
			)
			( pin "U5D1.AD47"
				( objectStatus "@baseboard_fab2_lib.baseboard_fab2(sch_1):page22_i204:rsvd(254)" )
			)
			( pin "U5D1.Y65"
				( objectStatus "@baseboard_fab2_lib.baseboard_fab2(sch_1):page22_i204:rsvd(256)" )
			)
			( pin "U5D1.Y23"
				( objectStatus "@baseboard_fab2_lib.baseboard_fab2(sch_1):page22_i204:rsvd(257)" )
			)
			( pin "U5D1.W66"
				( objectStatus "@baseboard_fab2_lib.baseboard_fab2(sch_1):page22_i204:rsvd(258)" )
			)
			( pin "U5D1.V67"
				( objectStatus "@baseboard_fab2_lib.baseboard_fab2(sch_1):page22_i204:rsvd(259)" )
			)
			( pin "U5D1.V65"
				( objectStatus "@baseboard_fab2_lib.baseboard_fab2(sch_1):page22_i204:rsvd(260)" )
			)
			( pin "U5D1.U66"
				( objectStatus "@baseboard_fab2_lib.baseboard_fab2(sch_1):page22_i204:rsvd(261)" )
			)
			( pin "U5D1.T67"
				( objectStatus "@baseboard_fab2_lib.baseboard_fab2(sch_1):page22_i204:rsvd(262)" )
			)
			( pin "U5D1.R66"
				( objectStatus "@baseboard_fab2_lib.baseboard_fab2(sch_1):page22_i204:rsvd(263)" )
			)
			( pin "U5D1.R62"
				( objectStatus "@baseboard_fab2_lib.baseboard_fab2(sch_1):page22_i204:rsvd(264)" )
			)
			( pin "U5D1.P65"
				( objectStatus "@baseboard_fab2_lib.baseboard_fab2(sch_1):page22_i204:rsvd(265)" )
			)
			( pin "U5D1.M63"
				( objectStatus "@baseboard_fab2_lib.baseboard_fab2(sch_1):page22_i204:rsvd(266)" )
			)
			( pin "U5D1.K61"
				( objectStatus "@baseboard_fab2_lib.baseboard_fab2(sch_1):page22_i204:rsvd(267)" )
			)
			( pin "U5D1.J62"
				( objectStatus "@baseboard_fab2_lib.baseboard_fab2(sch_1):page22_i204:rsvd(268)" )
			)
			( pin "U5D1.J46"
				( objectStatus "@baseboard_fab2_lib.baseboard_fab2(sch_1):page22_i204:rsvd(269)" )
			)
			( pin "U5D1.H85"
				( objectStatus "@baseboard_fab2_lib.baseboard_fab2(sch_1):page22_i204:rsvd(270)" )
			)
			( pin "U5D1.H83"
				( objectStatus "@baseboard_fab2_lib.baseboard_fab2(sch_1):page22_i204:rsvd(271)" )
			)
			( pin "U5D1.H1"
				( objectStatus "@baseboard_fab2_lib.baseboard_fab2(sch_1):page22_i204:rsvd(272)" )
			)
			( pin "U5D1.G84"
				( objectStatus "@baseboard_fab2_lib.baseboard_fab2(sch_1):page22_i204:rsvd(273)" )
			)
			( pin "U5D1.G64"
				( objectStatus "@baseboard_fab2_lib.baseboard_fab2(sch_1):page22_i204:rsvd(274)" )
			)
			( pin "U5D1.G2"
				( objectStatus "@baseboard_fab2_lib.baseboard_fab2(sch_1):page22_i204:rsvd(275)" )
			)
			( pin "U5D1.F83"
				( objectStatus "@baseboard_fab2_lib.baseboard_fab2(sch_1):page22_i204:rsvd(276)" )
			)
			( pin "U5D1.F65"
				( objectStatus "@baseboard_fab2_lib.baseboard_fab2(sch_1):page22_i204:rsvd(277)" )
			)
			( pin "U5D1.F23"
				( objectStatus "@baseboard_fab2_lib.baseboard_fab2(sch_1):page22_i204:rsvd(278)" )
			)
			( pin "U5D1.F3"
				( objectStatus "@baseboard_fab2_lib.baseboard_fab2(sch_1):page22_i204:rsvd(279)" )
			)
			( pin "U5D1.E84"
				( objectStatus "@baseboard_fab2_lib.baseboard_fab2(sch_1):page22_i204:rsvd(280)" )
			)
			( pin "U5D1.E24"
				( objectStatus "@baseboard_fab2_lib.baseboard_fab2(sch_1):page22_i204:rsvd(281)" )
			)
			( pin "U5D1.E4"
				( objectStatus "@baseboard_fab2_lib.baseboard_fab2(sch_1):page22_i204:rsvd(282)" )
			)
			( pin "U5D1.E2"
				( objectStatus "@baseboard_fab2_lib.baseboard_fab2(sch_1):page22_i204:rsvd(283)" )
			)
			( pin "U5D1.D83"
				( objectStatus "@baseboard_fab2_lib.baseboard_fab2(sch_1):page22_i204:rsvd(284)" )
			)
			( pin "U5D1.D65"
				( objectStatus "@baseboard_fab2_lib.baseboard_fab2(sch_1):page22_i204:rsvd(285)" )
			)
			( pin "U5D1.D17"
				( objectStatus "@baseboard_fab2_lib.baseboard_fab2(sch_1):page22_i204:rsvd(286)" )
			)
			( pin "U5D1.D5"
				( objectStatus "@baseboard_fab2_lib.baseboard_fab2(sch_1):page22_i204:rsvd(287)" )
			)
			( pin "U5D1.C82"
				( objectStatus "@baseboard_fab2_lib.baseboard_fab2(sch_1):page22_i204:rsvd(288)" )
			)
			( pin "U5D1.C24"
				( objectStatus "@baseboard_fab2_lib.baseboard_fab2(sch_1):page22_i204:rsvd(289)" )
			)
			( pin "U5D1.C18"
				( objectStatus "@baseboard_fab2_lib.baseboard_fab2(sch_1):page22_i204:rsvd(290)" )
			)
			( pin "U5D1.C6"
				( objectStatus "@baseboard_fab2_lib.baseboard_fab2(sch_1):page22_i204:rsvd(291)" )
			)
			( pin "U5D1.B81"
				( objectStatus "@baseboard_fab2_lib.baseboard_fab2(sch_1):page22_i204:rsvd(292)" )
			)
			( pin "U5D1.B77"
				( objectStatus "@baseboard_fab2_lib.baseboard_fab2(sch_1):page22_i204:rsvd(293)" )
			)
			( pin "U5D1.B17"
				( objectStatus "@baseboard_fab2_lib.baseboard_fab2(sch_1):page22_i204:rsvd(294)" )
			)
			( pin "U5D1.B15"
				( objectStatus "@baseboard_fab2_lib.baseboard_fab2(sch_1):page22_i204:rsvd(295)" )
			)
			( pin "U5D1.B13"
				( objectStatus "@baseboard_fab2_lib.baseboard_fab2(sch_1):page22_i204:rsvd(296)" )
			)
			( pin "U5D1.B7"
				( objectStatus "@baseboard_fab2_lib.baseboard_fab2(sch_1):page22_i204:rsvd(298)" )
			)
			( pin "U5D1.B3"
				( objectStatus "@baseboard_fab2_lib.baseboard_fab2(sch_1):page22_i204:rsvd(299)" )
			)
			( pin "U5D1.A24"
				( objectStatus "@baseboard_fab2_lib.baseboard_fab2(sch_1):page22_i204:rsvd(300)" )
			)
			( pin "U5D1.A16"
				( objectStatus "@baseboard_fab2_lib.baseboard_fab2(sch_1):page22_i204:rsvd(301)" )
			)
			( pin "U5D1.A14"
				( objectStatus "@baseboard_fab2_lib.baseboard_fab2(sch_1):page22_i204:rsvd(302)" )
			)
			( pin "U5D1.A6"
				( objectStatus "@baseboard_fab2_lib.baseboard_fab2(sch_1):page22_i204:rsvd(303)" )
			)
			( pin "U5D1.A4"
				( objectStatus "@baseboard_fab2_lib.baseboard_fab2(sch_1):page22_i204:rsvd(304)" )
			)
			( pin "U5D1.AF45"
				( objectStatus "@baseboard_fab2_lib.baseboard_fab2(sch_1):page22_i204:test_1" )
			)
			( pin "U5D1.AG46"
				( objectStatus "@baseboard_fab2_lib.baseboard_fab2(sch_1):page22_i204:test_2" )
			)
			( pin "U5D1.AM13"
				( objectStatus "@baseboard_fab2_lib.baseboard_fab2(sch_1):page22_i204:test_3" )
			)
			( pin "U5D1.AN12"
				( objectStatus "@baseboard_fab2_lib.baseboard_fab2(sch_1):page22_i204:test_4" )
			)
			( pin "U5D1.AN14"
				( objectStatus "@baseboard_fab2_lib.baseboard_fab2(sch_1):page22_i204:test_5" )
			)
			( pin "U5D1.AY13"
				( objectStatus "@baseboard_fab2_lib.baseboard_fab2(sch_1):page22_i204:test_11" )
			)
			( pin "U5D1.J60"
				( objectStatus "@baseboard_fab2_lib.baseboard_fab2(sch_1):page23_i172:ddr0_act_n" )
			)
			( pin "U5D1.B61"
				( objectStatus "@baseboard_fab2_lib.baseboard_fab2(sch_1):page23_i172:ddr0_alert_n" )
			)
			( pin "U5D1.C52"
				( objectStatus "@baseboard_fab2_lib.baseboard_fab2(sch_1):page23_i172:ddr0_ba(0)" )
			)
			( pin "U5D1.G54"
				( objectStatus "@baseboard_fab2_lib.baseboard_fab2(sch_1):page23_i172:ddr0_ba(1)" )
			)
			( pin "U5D1.D61"
				( objectStatus "@baseboard_fab2_lib.baseboard_fab2(sch_1):page23_i172:ddr0_bg(0)" )
			)
			( pin "U5D1.F63"
				( objectStatus "@baseboard_fab2_lib.baseboard_fab2(sch_1):page23_i172:ddr0_bg(1)" )
			)
			( pin "U5D1.G46"
				( objectStatus "@baseboard_fab2_lib.baseboard_fab2(sch_1):page23_i172:ddr0_cid(2)" )
			)
			( pin "U5D1.C62"
				( objectStatus "@baseboard_fab2_lib.baseboard_fab2(sch_1):page23_i172:ddr0_cke(0)" )
			)
			( pin "U5D1.C64"
				( objectStatus "@baseboard_fab2_lib.baseboard_fab2(sch_1):page23_i172:ddr0_cke(1)" )
			)
			( pin "U5D1.B63"
				( objectStatus "@baseboard_fab2_lib.baseboard_fab2(sch_1):page23_i172:ddr0_cke(2)" )
			)
			( pin "U5D1.D63"
				( objectStatus "@baseboard_fab2_lib.baseboard_fab2(sch_1):page23_i172:ddr0_cke(3)" )
			)
			( pin "U5D1.F55"
				( objectStatus "@baseboard_fab2_lib.baseboard_fab2(sch_1):page23_i172:ddr0_clk_dn(0)" )
			)
			( pin "U5D1.C54"
				( objectStatus "@baseboard_fab2_lib.baseboard_fab2(sch_1):page23_i172:ddr0_clk_dn(1)" )
			)
			( pin "U5D1.J56"
				( objectStatus "@baseboard_fab2_lib.baseboard_fab2(sch_1):page23_i172:ddr0_clk_dn(2)" )
			)
			( pin "U5D1.C56"
				( objectStatus "@baseboard_fab2_lib.baseboard_fab2(sch_1):page23_i172:ddr0_clk_dn(3)" )
			)
			( pin "U5D1.D55"
				( objectStatus "@baseboard_fab2_lib.baseboard_fab2(sch_1):page23_i172:ddr0_clk_dp(0)" )
			)
			( pin "U5D1.B55"
				( objectStatus "@baseboard_fab2_lib.baseboard_fab2(sch_1):page23_i172:ddr0_clk_dp(1)" )
			)
			( pin "U5D1.G56"
				( objectStatus "@baseboard_fab2_lib.baseboard_fab2(sch_1):page23_i172:ddr0_clk_dp(2)" )
			)
			( pin "U5D1.B57"
				( objectStatus "@baseboard_fab2_lib.baseboard_fab2(sch_1):page23_i172:ddr0_clk_dp(3)" )
			)
			( pin "U5D1.G52"
				( objectStatus "@baseboard_fab2_lib.baseboard_fab2(sch_1):page23_i172:ddr0_cs_n(0)" )
			)
			( pin "U5D1.F49"
				( objectStatus "@baseboard_fab2_lib.baseboard_fab2(sch_1):page23_i172:ddr0_cs_n(1)" )
			)
			( pin "U5D1.D47"
				( objectStatus "@baseboard_fab2_lib.baseboard_fab2(sch_1):page23_i172:ddr0_cs_n(2)" )
			)
			( pin "U5D1.F47"
				( objectStatus "@baseboard_fab2_lib.baseboard_fab2(sch_1):page23_i172:ddr0_cs_n(3)" )
			)
			( pin "U5D1.B51"
				( objectStatus "@baseboard_fab2_lib.baseboard_fab2(sch_1):page23_i172:ddr0_cs_n(4)" )
			)
			( pin "U5D1.D49"
				( objectStatus "@baseboard_fab2_lib.baseboard_fab2(sch_1):page23_i172:ddr0_cs_n(5)" )
			)
			( pin "U5D1.F45"
				( objectStatus "@baseboard_fab2_lib.baseboard_fab2(sch_1):page23_i172:ddr0_cs_n(6)" )
			)
			( pin "U5D1.K45"
				( objectStatus "@baseboard_fab2_lib.baseboard_fab2(sch_1):page23_i172:ddr0_cs_n(7)" )
			)
			( pin "U5D1.AN86"
				( objectStatus "@baseboard_fab2_lib.baseboard_fab2(sch_1):page23_i172:ddr0_dq(0)" )
			)
			( pin "U5D1.AN84"
				( objectStatus "@baseboard_fab2_lib.baseboard_fab2(sch_1):page23_i172:ddr0_dq(1)" )
			)
			( pin "U5D1.AE86"
				( objectStatus "@baseboard_fab2_lib.baseboard_fab2(sch_1):page23_i172:ddr0_dq(2)" )
			)
			( pin "U5D1.AE84"
				( objectStatus "@baseboard_fab2_lib.baseboard_fab2(sch_1):page23_i172:ddr0_dq(3)" )
			)
			( pin "U5D1.AR86"
				( objectStatus "@baseboard_fab2_lib.baseboard_fab2(sch_1):page23_i172:ddr0_dq(4)" )
			)
			( pin "U5D1.AR84"
				( objectStatus "@baseboard_fab2_lib.baseboard_fab2(sch_1):page23_i172:ddr0_dq(5)" )
			)
			( pin "U5D1.AG86"
				( objectStatus "@baseboard_fab2_lib.baseboard_fab2(sch_1):page23_i172:ddr0_dq(6)" )
			)
			( pin "U5D1.AG84"
				( objectStatus "@baseboard_fab2_lib.baseboard_fab2(sch_1):page23_i172:ddr0_dq(7)" )
			)
			( pin "U5D1.W86"
				( objectStatus "@baseboard_fab2_lib.baseboard_fab2(sch_1):page23_i172:ddr0_dq(8)" )
			)
			( pin "U5D1.W84"
				( objectStatus "@baseboard_fab2_lib.baseboard_fab2(sch_1):page23_i172:ddr0_dq(9)" )
			)
			( pin "U5D1.L86"
				( objectStatus "@baseboard_fab2_lib.baseboard_fab2(sch_1):page23_i172:ddr0_dq(10)" )
			)
			( pin "U5D1.L84"
				( objectStatus "@baseboard_fab2_lib.baseboard_fab2(sch_1):page23_i172:ddr0_dq(11)" )
			)
			( pin "U5D1.AA86"
				( objectStatus "@baseboard_fab2_lib.baseboard_fab2(sch_1):page23_i172:ddr0_dq(12)" )
			)
			( pin "U5D1.AA84"
				( objectStatus "@baseboard_fab2_lib.baseboard_fab2(sch_1):page23_i172:ddr0_dq(13)" )
			)
			( pin "U5D1.N86"
				( objectStatus "@baseboard_fab2_lib.baseboard_fab2(sch_1):page23_i172:ddr0_dq(14)" )
			)
			( pin "U5D1.N84"
				( objectStatus "@baseboard_fab2_lib.baseboard_fab2(sch_1):page23_i172:ddr0_dq(15)" )
			)
			( pin "U5D1.V81"
				( objectStatus "@baseboard_fab2_lib.baseboard_fab2(sch_1):page23_i172:ddr0_dq(16)" )
			)
			( pin "U5D1.T79"
				( objectStatus "@baseboard_fab2_lib.baseboard_fab2(sch_1):page23_i172:ddr0_dq(17)" )
			)
			( pin "U5D1.N82"
				( objectStatus "@baseboard_fab2_lib.baseboard_fab2(sch_1):page23_i172:ddr0_dq(18)" )
			)
			( pin "U5D1.M81"
				( objectStatus "@baseboard_fab2_lib.baseboard_fab2(sch_1):page23_i172:ddr0_dq(19)" )
			)
			( pin "U5D1.W80"
				( objectStatus "@baseboard_fab2_lib.baseboard_fab2(sch_1):page23_i172:ddr0_dq(20)" )
			)
			( pin "U5D1.V79"
				( objectStatus "@baseboard_fab2_lib.baseboard_fab2(sch_1):page23_i172:ddr0_dq(21)" )
			)
			( pin "U5D1.R82"
				( objectStatus "@baseboard_fab2_lib.baseboard_fab2(sch_1):page23_i172:ddr0_dq(22)" )
			)
			( pin "U5D1.N80"
				( objectStatus "@baseboard_fab2_lib.baseboard_fab2(sch_1):page23_i172:ddr0_dq(23)" )
			)
			( pin "U5D1.L76"
				( objectStatus "@baseboard_fab2_lib.baseboard_fab2(sch_1):page23_i172:ddr0_dq(24)" )
			)
			( pin "U5D1.R76"
				( objectStatus "@baseboard_fab2_lib.baseboard_fab2(sch_1):page23_i172:ddr0_dq(25)" )
			)
			( pin "U5D1.M73"
				( objectStatus "@baseboard_fab2_lib.baseboard_fab2(sch_1):page23_i172:ddr0_dq(26)" )
			)
			( pin "U5D1.P73"
				( objectStatus "@baseboard_fab2_lib.baseboard_fab2(sch_1):page23_i172:ddr0_dq(27)" )
			)
			( pin "U5D1.M77"
				( objectStatus "@baseboard_fab2_lib.baseboard_fab2(sch_1):page23_i172:ddr0_dq(28)" )
			)
			( pin "U5D1.P77"
				( objectStatus "@baseboard_fab2_lib.baseboard_fab2(sch_1):page23_i172:ddr0_dq(29)" )
			)
			( pin "U5D1.L74"
				( objectStatus "@baseboard_fab2_lib.baseboard_fab2(sch_1):page23_i172:ddr0_dq(30)" )
			)
			( pin "U5D1.R74"
				( objectStatus "@baseboard_fab2_lib.baseboard_fab2(sch_1):page23_i172:ddr0_dq(31)" )
			)
			( pin "U5D1.C42"
				( objectStatus "@baseboard_fab2_lib.baseboard_fab2(sch_1):page23_i172:ddr0_dq(32)" )
			)
			( pin "U5D1.B41"
				( objectStatus "@baseboard_fab2_lib.baseboard_fab2(sch_1):page23_i172:ddr0_dq(33)" )
			)
			( pin "U5D1.C38"
				( objectStatus "@baseboard_fab2_lib.baseboard_fab2(sch_1):page23_i172:ddr0_dq(34)" )
			)
			( pin "U5D1.E38"
				( objectStatus "@baseboard_fab2_lib.baseboard_fab2(sch_1):page23_i172:ddr0_dq(35)" )
			)
			( pin "U5D1.E42"
				( objectStatus "@baseboard_fab2_lib.baseboard_fab2(sch_1):page23_i172:ddr0_dq(36)" )
			)
			( pin "U5D1.F41"
				( objectStatus "@baseboard_fab2_lib.baseboard_fab2(sch_1):page23_i172:ddr0_dq(37)" )
			)
			( pin "U5D1.B39"
				( objectStatus "@baseboard_fab2_lib.baseboard_fab2(sch_1):page23_i172:ddr0_dq(38)" )
			)
			( pin "U5D1.F39"
				( objectStatus "@baseboard_fab2_lib.baseboard_fab2(sch_1):page23_i172:ddr0_dq(39)" )
			)
			( pin "U5D1.K37"
				( objectStatus "@baseboard_fab2_lib.baseboard_fab2(sch_1):page23_i172:ddr0_dq(40)" )
			)
			( pin "U5D1.P37"
				( objectStatus "@baseboard_fab2_lib.baseboard_fab2(sch_1):page23_i172:ddr0_dq(41)" )
			)
			( pin "U5D1.L34"
				( objectStatus "@baseboard_fab2_lib.baseboard_fab2(sch_1):page23_i172:ddr0_dq(42)" )
			)
			( pin "U5D1.N34"
				( objectStatus "@baseboard_fab2_lib.baseboard_fab2(sch_1):page23_i172:ddr0_dq(43)" )
			)
			( pin "U5D1.L38"
				( objectStatus "@baseboard_fab2_lib.baseboard_fab2(sch_1):page23_i172:ddr0_dq(44)" )
			)
			( pin "U5D1.N38"
				( objectStatus "@baseboard_fab2_lib.baseboard_fab2(sch_1):page23_i172:ddr0_dq(45)" )
			)
			( pin "U5D1.K35"
				( objectStatus "@baseboard_fab2_lib.baseboard_fab2(sch_1):page23_i172:ddr0_dq(46)" )
			)
			( pin "U5D1.P35"
				( objectStatus "@baseboard_fab2_lib.baseboard_fab2(sch_1):page23_i172:ddr0_dq(47)" )
			)
			( pin "U5D1.K31"
				( objectStatus "@baseboard_fab2_lib.baseboard_fab2(sch_1):page23_i172:ddr0_dq(48)" )
			)
			( pin "U5D1.P31"
				( objectStatus "@baseboard_fab2_lib.baseboard_fab2(sch_1):page23_i172:ddr0_dq(49)" )
			)
			( pin "U5D1.L28"
				( objectStatus "@baseboard_fab2_lib.baseboard_fab2(sch_1):page23_i172:ddr0_dq(50)" )
			)
			( pin "U5D1.N28"
				( objectStatus "@baseboard_fab2_lib.baseboard_fab2(sch_1):page23_i172:ddr0_dq(51)" )
			)
			( pin "U5D1.L32"
				( objectStatus "@baseboard_fab2_lib.baseboard_fab2(sch_1):page23_i172:ddr0_dq(52)" )
			)
			( pin "U5D1.N32"
				( objectStatus "@baseboard_fab2_lib.baseboard_fab2(sch_1):page23_i172:ddr0_dq(53)" )
			)
			( pin "U5D1.K29"
				( objectStatus "@baseboard_fab2_lib.baseboard_fab2(sch_1):page23_i172:ddr0_dq(54)" )
			)
			( pin "U5D1.P29"
				( objectStatus "@baseboard_fab2_lib.baseboard_fab2(sch_1):page23_i172:ddr0_dq(55)" )
			)
			( pin "U5D1.K25"
				( objectStatus "@baseboard_fab2_lib.baseboard_fab2(sch_1):page23_i172:ddr0_dq(56)" )
			)
			( pin "U5D1.P25"
				( objectStatus "@baseboard_fab2_lib.baseboard_fab2(sch_1):page23_i172:ddr0_dq(57)" )
			)
			( pin "U5D1.P23"
				( objectStatus "@baseboard_fab2_lib.baseboard_fab2(sch_1):page23_i172:ddr0_dq(58)" )
			)
			( pin "U5D1.T23"
				( objectStatus "@baseboard_fab2_lib.baseboard_fab2(sch_1):page23_i172:ddr0_dq(59)" )
			)
			( pin "U5D1.L26"
				( objectStatus "@baseboard_fab2_lib.baseboard_fab2(sch_1):page23_i172:ddr0_dq(60)" )
			)
			( pin "U5D1.N26"
				( objectStatus "@baseboard_fab2_lib.baseboard_fab2(sch_1):page23_i172:ddr0_dq(61)" )
			)
			( pin "U5D1.H23"
				( objectStatus "@baseboard_fab2_lib.baseboard_fab2(sch_1):page23_i172:ddr0_dq(62)" )
			)
			( pin "U5D1.K23"
				( objectStatus "@baseboard_fab2_lib.baseboard_fab2(sch_1):page23_i172:ddr0_dq(63)" )
			)
			( pin "U5D1.AJ84"
				( objectStatus "@baseboard_fab2_lib.baseboard_fab2(sch_1):page23_i172:ddr0_dqs_dn(0)" )
			)
			( pin "U5D1.R84"
				( objectStatus "@baseboard_fab2_lib.baseboard_fab2(sch_1):page23_i172:ddr0_dqs_dn(1)" )
			)
			( pin "U5D1.P79"
				( objectStatus "@baseboard_fab2_lib.baseboard_fab2(sch_1):page23_i172:ddr0_dqs_dn(2)" )
			)
			( pin "U5D1.T75"
				( objectStatus "@baseboard_fab2_lib.baseboard_fab2(sch_1):page23_i172:ddr0_dqs_dn(3)" )
			)
			( pin "U5D1.G40"
				( objectStatus "@baseboard_fab2_lib.baseboard_fab2(sch_1):page23_i172:ddr0_dqs_dn(4)" )
			)
			( pin "U5D1.R36"
				( objectStatus "@baseboard_fab2_lib.baseboard_fab2(sch_1):page23_i172:ddr0_dqs_dn(5)" )
			)
			( pin "U5D1.R30"
				( objectStatus "@baseboard_fab2_lib.baseboard_fab2(sch_1):page23_i172:ddr0_dqs_dn(6)" )
			)
			( pin "U5D1.N24"
				( objectStatus "@baseboard_fab2_lib.baseboard_fab2(sch_1):page23_i172:ddr0_dqs_dn(7)" )
			)
			( pin "U5D1.AH67"
				( objectStatus "@baseboard_fab2_lib.baseboard_fab2(sch_1):page23_i172:ddr0_dqs_dn(8)" )
			)
			( pin "U5D1.AL84"
				( objectStatus "@baseboard_fab2_lib.baseboard_fab2(sch_1):page23_i172:ddr0_dqs_dn(9)" )
			)
			( pin "U5D1.U84"
				( objectStatus "@baseboard_fab2_lib.baseboard_fab2(sch_1):page23_i172:ddr0_dqs_dn(10)" )
			)
			( pin "U5D1.U82"
				( objectStatus "@baseboard_fab2_lib.baseboard_fab2(sch_1):page23_i172:ddr0_dqs_dn(11)" )
			)
			( pin "U5D1.K75"
				( objectStatus "@baseboard_fab2_lib.baseboard_fab2(sch_1):page23_i172:ddr0_dqs_dn(12)" )
			)
			( pin "U5D1.A40"
				( objectStatus "@baseboard_fab2_lib.baseboard_fab2(sch_1):page23_i172:ddr0_dqs_dn(13)" )
			)
			( pin "U5D1.J36"
				( objectStatus "@baseboard_fab2_lib.baseboard_fab2(sch_1):page23_i172:ddr0_dqs_dn(14)" )
			)
			( pin "U5D1.J30"
				( objectStatus "@baseboard_fab2_lib.baseboard_fab2(sch_1):page23_i172:ddr0_dqs_dn(15)" )
			)
			( pin "U5D1.J24"
				( objectStatus "@baseboard_fab2_lib.baseboard_fab2(sch_1):page23_i172:ddr0_dqs_dn(16)" )
			)
			( pin "U5D1.AB67"
				( objectStatus "@baseboard_fab2_lib.baseboard_fab2(sch_1):page23_i172:ddr0_dqs_dn(17)" )
			)
			( pin "U5D1.AH85"
				( objectStatus "@baseboard_fab2_lib.baseboard_fab2(sch_1):page23_i172:ddr0_dqs_dp(0)" )
			)
			( pin "U5D1.P85"
				( objectStatus "@baseboard_fab2_lib.baseboard_fab2(sch_1):page23_i172:ddr0_dqs_dp(1)" )
			)
			( pin "U5D1.R80"
				( objectStatus "@baseboard_fab2_lib.baseboard_fab2(sch_1):page23_i172:ddr0_dqs_dp(2)" )
			)
			( pin "U5D1.P75"
				( objectStatus "@baseboard_fab2_lib.baseboard_fab2(sch_1):page23_i172:ddr0_dqs_dp(3)" )
			)
			( pin "U5D1.E40"
				( objectStatus "@baseboard_fab2_lib.baseboard_fab2(sch_1):page23_i172:ddr0_dqs_dp(4)" )
			)
			( pin "U5D1.N36"
				( objectStatus "@baseboard_fab2_lib.baseboard_fab2(sch_1):page23_i172:ddr0_dqs_dp(5)" )
			)
			( pin "U5D1.N30"
				( objectStatus "@baseboard_fab2_lib.baseboard_fab2(sch_1):page23_i172:ddr0_dqs_dp(6)" )
			)
			( pin "U5D1.R24"
				( objectStatus "@baseboard_fab2_lib.baseboard_fab2(sch_1):page23_i172:ddr0_dqs_dp(7)" )
			)
			( pin "U5D1.AF67"
				( objectStatus "@baseboard_fab2_lib.baseboard_fab2(sch_1):page23_i172:ddr0_dqs_dp(8)" )
			)
			( pin "U5D1.AM85"
				( objectStatus "@baseboard_fab2_lib.baseboard_fab2(sch_1):page23_i172:ddr0_dqs_dp(9)" )
			)
			( pin "U5D1.V85"
				( objectStatus "@baseboard_fab2_lib.baseboard_fab2(sch_1):page23_i172:ddr0_dqs_dp(10)" )
			)
			( pin "U5D1.T81"
				( objectStatus "@baseboard_fab2_lib.baseboard_fab2(sch_1):page23_i172:ddr0_dqs_dp(11)" )
			)
			( pin "U5D1.M75"
				( objectStatus "@baseboard_fab2_lib.baseboard_fab2(sch_1):page23_i172:ddr0_dqs_dp(12)" )
			)
			( pin "U5D1.C40"
				( objectStatus "@baseboard_fab2_lib.baseboard_fab2(sch_1):page23_i172:ddr0_dqs_dp(13)" )
			)
			( pin "U5D1.L36"
				( objectStatus "@baseboard_fab2_lib.baseboard_fab2(sch_1):page23_i172:ddr0_dqs_dp(14)" )
			)
			( pin "U5D1.L30"
				( objectStatus "@baseboard_fab2_lib.baseboard_fab2(sch_1):page23_i172:ddr0_dqs_dp(15)" )
			)
			( pin "U5D1.L24"
				( objectStatus "@baseboard_fab2_lib.baseboard_fab2(sch_1):page23_i172:ddr0_dqs_dp(16)" )
			)
			( pin "U5D1.AD67"
				( objectStatus "@baseboard_fab2_lib.baseboard_fab2(sch_1):page23_i172:ddr0_dqs_dp(17)" )
			)
			( pin "U5D1.AC68"
				( objectStatus "@baseboard_fab2_lib.baseboard_fab2(sch_1):page23_i172:ddr0_ecc(0)" )
			)
			( pin "U5D1.AG68"
				( objectStatus "@baseboard_fab2_lib.baseboard_fab2(sch_1):page23_i172:ddr0_ecc(1)" )
			)
			( pin "U5D1.AD65"
				( objectStatus "@baseboard_fab2_lib.baseboard_fab2(sch_1):page23_i172:ddr0_ecc(2)" )
			)
			( pin "U5D1.AF65"
				( objectStatus "@baseboard_fab2_lib.baseboard_fab2(sch_1):page23_i172:ddr0_ecc(3)" )
			)
			( pin "U5D1.AD69"
				( objectStatus "@baseboard_fab2_lib.baseboard_fab2(sch_1):page23_i172:ddr0_ecc(4)" )
			)
			( pin "U5D1.AF69"
				( objectStatus "@baseboard_fab2_lib.baseboard_fab2(sch_1):page23_i172:ddr0_ecc(5)" )
			)
			( pin "U5D1.AC66"
				( objectStatus "@baseboard_fab2_lib.baseboard_fab2(sch_1):page23_i172:ddr0_ecc(6)" )
			)
			( pin "U5D1.AG66"
				( objectStatus "@baseboard_fab2_lib.baseboard_fab2(sch_1):page23_i172:ddr0_ecc(7)" )
			)
			( pin "U5D1.F53"
				( objectStatus "@baseboard_fab2_lib.baseboard_fab2(sch_1):page23_i172:ddr0_ma(0)" )
			)
			( pin "U5D1.F57"
				( objectStatus "@baseboard_fab2_lib.baseboard_fab2(sch_1):page23_i172:ddr0_ma(1)" )
			)
			( pin "U5D1.D57"
				( objectStatus "@baseboard_fab2_lib.baseboard_fab2(sch_1):page23_i172:ddr0_ma(2)" )
			)
			( pin "U5D1.C58"
				( objectStatus "@baseboard_fab2_lib.baseboard_fab2(sch_1):page23_i172:ddr0_ma(3)" )
			)
			( pin "U5D1.G58"
				( objectStatus "@baseboard_fab2_lib.baseboard_fab2(sch_1):page23_i172:ddr0_ma(4)" )
			)
			( pin "U5D1.F59"
				( objectStatus "@baseboard_fab2_lib.baseboard_fab2(sch_1):page23_i172:ddr0_ma(5)" )
			)
			( pin "U5D1.D59"
				( objectStatus "@baseboard_fab2_lib.baseboard_fab2(sch_1):page23_i172:ddr0_ma(6)" )
			)
			( pin "U5D1.G60"
				( objectStatus "@baseboard_fab2_lib.baseboard_fab2(sch_1):page23_i172:ddr0_ma(7)" )
			)
			( pin "U5D1.C60"
				( objectStatus "@baseboard_fab2_lib.baseboard_fab2(sch_1):page23_i172:ddr0_ma(8)" )
			)
			( pin "U5D1.F61"
				( objectStatus "@baseboard_fab2_lib.baseboard_fab2(sch_1):page23_i172:ddr0_ma(9)" )
			)
			( pin "U5D1.J54"
				( objectStatus "@baseboard_fab2_lib.baseboard_fab2(sch_1):page23_i172:ddr0_ma(10)" )
			)
			( pin "U5D1.G62"
				( objectStatus "@baseboard_fab2_lib.baseboard_fab2(sch_1):page23_i172:ddr0_ma(11)" )
			)
			( pin "U5D1.J64"
				( objectStatus "@baseboard_fab2_lib.baseboard_fab2(sch_1):page23_i172:ddr0_ma(12)" )
			)
			( pin "U5D1.J48"
				( objectStatus "@baseboard_fab2_lib.baseboard_fab2(sch_1):page23_i172:ddr0_ma(13)" )
			)
			( pin "U5D1.F51"
				( objectStatus "@baseboard_fab2_lib.baseboard_fab2(sch_1):page23_i172:ddr0_ma(14)" )
			)
			( pin "U5D1.K49"
				( objectStatus "@baseboard_fab2_lib.baseboard_fab2(sch_1):page23_i172:ddr0_ma(15)" )
			)
			( pin "U5D1.D51"
				( objectStatus "@baseboard_fab2_lib.baseboard_fab2(sch_1):page23_i172:ddr0_ma(16)" )
			)
			( pin "U5D1.K47"
				( objectStatus "@baseboard_fab2_lib.baseboard_fab2(sch_1):page23_i172:ddr0_ma(17)" )
			)
			( pin "U5D1.C50"
				( objectStatus "@baseboard_fab2_lib.baseboard_fab2(sch_1):page23_i172:ddr0_odt(0)" )
			)
			( pin "U5D1.C48"
				( objectStatus "@baseboard_fab2_lib.baseboard_fab2(sch_1):page23_i172:ddr0_odt(1)" )
			)
			( pin "U5D1.G50"
				( objectStatus "@baseboard_fab2_lib.baseboard_fab2(sch_1):page23_i172:ddr0_odt(2)" )
			)
			( pin "U5D1.G48"
				( objectStatus "@baseboard_fab2_lib.baseboard_fab2(sch_1):page23_i172:ddr0_odt(3)" )
			)
			( pin "U5D1.D53"
				( objectStatus "@baseboard_fab2_lib.baseboard_fab2(sch_1):page23_i172:ddr0_par" )
			)
			( pin "U5D1.T63"
				( objectStatus "@baseboard_fab2_lib.baseboard_fab2(sch_1):page24_i172:ddr1_act_n" )
			)
			( pin "U5D1.W62"
				( objectStatus "@baseboard_fab2_lib.baseboard_fab2(sch_1):page24_i172:ddr1_alert_n" )
			)
			( pin "U5D1.T53"
				( objectStatus "@baseboard_fab2_lib.baseboard_fab2(sch_1):page24_i172:ddr1_ba(0)" )
			)
			( pin "U5D1.K55"
				( objectStatus "@baseboard_fab2_lib.baseboard_fab2(sch_1):page24_i172:ddr1_ba(1)" )
			)
			( pin "U5D1.M61"
				( objectStatus "@baseboard_fab2_lib.baseboard_fab2(sch_1):page24_i172:ddr1_bg(0)" )
			)
			( pin "U5D1.N60"
				( objectStatus "@baseboard_fab2_lib.baseboard_fab2(sch_1):page24_i172:ddr1_bg(1)" )
			)
			( pin "U5D1.M47"
				( objectStatus "@baseboard_fab2_lib.baseboard_fab2(sch_1):page24_i172:ddr1_cid(2)" )
			)
			( pin "U5D1.N62"
				( objectStatus "@baseboard_fab2_lib.baseboard_fab2(sch_1):page24_i172:ddr1_cke(0)" )
			)
			( pin "U5D1.R64"
				( objectStatus "@baseboard_fab2_lib.baseboard_fab2(sch_1):page24_i172:ddr1_cke(1)" )
			)
			( pin "U5D1.K63"
				( objectStatus "@baseboard_fab2_lib.baseboard_fab2(sch_1):page24_i172:ddr1_cke(2)" )
			)
			( pin "U5D1.L64"
				( objectStatus "@baseboard_fab2_lib.baseboard_fab2(sch_1):page24_i172:ddr1_cke(3)" )
			)
			( pin "U5D1.M53"
				( objectStatus "@baseboard_fab2_lib.baseboard_fab2(sch_1):page24_i172:ddr1_clk_dn(0)" )
			)
			( pin "U5D1.R54"
				( objectStatus "@baseboard_fab2_lib.baseboard_fab2(sch_1):page24_i172:ddr1_clk_dn(1)" )
			)
			( pin "U5D1.N56"
				( objectStatus "@baseboard_fab2_lib.baseboard_fab2(sch_1):page24_i172:ddr1_clk_dn(2)" )
			)
			( pin "U5D1.R56"
				( objectStatus "@baseboard_fab2_lib.baseboard_fab2(sch_1):page24_i172:ddr1_clk_dn(3)" )
			)
			( pin "U5D1.N54"
				( objectStatus "@baseboard_fab2_lib.baseboard_fab2(sch_1):page24_i172:ddr1_clk_dp(0)" )
			)
			( pin "U5D1.T55"
				( objectStatus "@baseboard_fab2_lib.baseboard_fab2(sch_1):page24_i172:ddr1_clk_dp(1)" )
			)
			( pin "U5D1.M57"
				( objectStatus "@baseboard_fab2_lib.baseboard_fab2(sch_1):page24_i172:ddr1_clk_dp(2)" )
			)
			( pin "U5D1.T57"
				( objectStatus "@baseboard_fab2_lib.baseboard_fab2(sch_1):page24_i172:ddr1_clk_dp(3)" )
			)
			( pin "U5D1.K51"
				( objectStatus "@baseboard_fab2_lib.baseboard_fab2(sch_1):page24_i172:ddr1_cs_n(0)" )
			)
			( pin "U5D1.R50"
				( objectStatus "@baseboard_fab2_lib.baseboard_fab2(sch_1):page24_i172:ddr1_cs_n(1)" )
			)
			( pin "U5D1.N46"
				( objectStatus "@baseboard_fab2_lib.baseboard_fab2(sch_1):page24_i172:ddr1_cs_n(2)" )
			)
			( pin "U5D1.V47"
				( objectStatus "@baseboard_fab2_lib.baseboard_fab2(sch_1):page24_i172:ddr1_cs_n(3)" )
			)
			( pin "U5D1.J50"
				( objectStatus "@baseboard_fab2_lib.baseboard_fab2(sch_1):page24_i172:ddr1_cs_n(4)" )
			)
			( pin "U5D1.T49"
				( objectStatus "@baseboard_fab2_lib.baseboard_fab2(sch_1):page24_i172:ddr1_cs_n(5)" )
			)
			( pin "U5D1.M45"
				( objectStatus "@baseboard_fab2_lib.baseboard_fab2(sch_1):page24_i172:ddr1_cs_n(6)" )
			)
			( pin "U5D1.R46"
				( objectStatus "@baseboard_fab2_lib.baseboard_fab2(sch_1):page24_i172:ddr1_cs_n(7)" )
			)
			( pin "U5D1.AV81"
				( objectStatus "@baseboard_fab2_lib.baseboard_fab2(sch_1):page24_i172:ddr1_dq(0)" )
			)
			( pin "U5D1.AT79"
				( objectStatus "@baseboard_fab2_lib.baseboard_fab2(sch_1):page24_i172:ddr1_dq(1)" )
			)
			( pin "U5D1.AN82"
				( objectStatus "@baseboard_fab2_lib.baseboard_fab2(sch_1):page24_i172:ddr1_dq(2)" )
			)
			( pin "U5D1.AM81"
				( objectStatus "@baseboard_fab2_lib.baseboard_fab2(sch_1):page24_i172:ddr1_dq(3)" )
			)
			( pin "U5D1.AW80"
				( objectStatus "@baseboard_fab2_lib.baseboard_fab2(sch_1):page24_i172:ddr1_dq(4)" )
			)
			( pin "U5D1.AV79"
				( objectStatus "@baseboard_fab2_lib.baseboard_fab2(sch_1):page24_i172:ddr1_dq(5)" )
			)
			( pin "U5D1.AR82"
				( objectStatus "@baseboard_fab2_lib.baseboard_fab2(sch_1):page24_i172:ddr1_dq(6)" )
			)
			( pin "U5D1.AN80"
				( objectStatus "@baseboard_fab2_lib.baseboard_fab2(sch_1):page24_i172:ddr1_dq(7)" )
			)
			( pin "U5D1.AH81"
				( objectStatus "@baseboard_fab2_lib.baseboard_fab2(sch_1):page24_i172:ddr1_dq(8)" )
			)
			( pin "U5D1.AF79"
				( objectStatus "@baseboard_fab2_lib.baseboard_fab2(sch_1):page24_i172:ddr1_dq(9)" )
			)
			( pin "U5D1.AC82"
				( objectStatus "@baseboard_fab2_lib.baseboard_fab2(sch_1):page24_i172:ddr1_dq(10)" )
			)
			( pin "U5D1.AB81"
				( objectStatus "@baseboard_fab2_lib.baseboard_fab2(sch_1):page24_i172:ddr1_dq(11)" )
			)
			( pin "U5D1.AJ80"
				( objectStatus "@baseboard_fab2_lib.baseboard_fab2(sch_1):page24_i172:ddr1_dq(12)" )
			)
			( pin "U5D1.AH79"
				( objectStatus "@baseboard_fab2_lib.baseboard_fab2(sch_1):page24_i172:ddr1_dq(13)" )
			)
			( pin "U5D1.AE82"
				( objectStatus "@baseboard_fab2_lib.baseboard_fab2(sch_1):page24_i172:ddr1_dq(14)" )
			)
			( pin "U5D1.AC80"
				( objectStatus "@baseboard_fab2_lib.baseboard_fab2(sch_1):page24_i172:ddr1_dq(15)" )
			)
			( pin "U5D1.E80"
				( objectStatus "@baseboard_fab2_lib.baseboard_fab2(sch_1):page24_i172:ddr1_dq(16)" )
			)
			( pin "U5D1.J80"
				( objectStatus "@baseboard_fab2_lib.baseboard_fab2(sch_1):page24_i172:ddr1_dq(17)" )
			)
			( pin "U5D1.F77"
				( objectStatus "@baseboard_fab2_lib.baseboard_fab2(sch_1):page24_i172:ddr1_dq(18)" )
			)
			( pin "U5D1.H77"
				( objectStatus "@baseboard_fab2_lib.baseboard_fab2(sch_1):page24_i172:ddr1_dq(19)" )
			)
			( pin "U5D1.F81"
				( objectStatus "@baseboard_fab2_lib.baseboard_fab2(sch_1):page24_i172:ddr1_dq(20)" )
			)
			( pin "U5D1.H81"
				( objectStatus "@baseboard_fab2_lib.baseboard_fab2(sch_1):page24_i172:ddr1_dq(21)" )
			)
			( pin "U5D1.E78"
				( objectStatus "@baseboard_fab2_lib.baseboard_fab2(sch_1):page24_i172:ddr1_dq(22)" )
			)
			( pin "U5D1.J78"
				( objectStatus "@baseboard_fab2_lib.baseboard_fab2(sch_1):page24_i172:ddr1_dq(23)" )
			)
			( pin "U5D1.D75"
				( objectStatus "@baseboard_fab2_lib.baseboard_fab2(sch_1):page24_i172:ddr1_dq(24)" )
			)
			( pin "U5D1.C74"
				( objectStatus "@baseboard_fab2_lib.baseboard_fab2(sch_1):page24_i172:ddr1_dq(25)" )
			)
			( pin "U5D1.D71"
				( objectStatus "@baseboard_fab2_lib.baseboard_fab2(sch_1):page24_i172:ddr1_dq(26)" )
			)
			( pin "U5D1.F71"
				( objectStatus "@baseboard_fab2_lib.baseboard_fab2(sch_1):page24_i172:ddr1_dq(27)" )
			)
			( pin "U5D1.F75"
				( objectStatus "@baseboard_fab2_lib.baseboard_fab2(sch_1):page24_i172:ddr1_dq(28)" )
			)
			( pin "U5D1.G74"
				( objectStatus "@baseboard_fab2_lib.baseboard_fab2(sch_1):page24_i172:ddr1_dq(29)" )
			)
			( pin "U5D1.C72"
				( objectStatus "@baseboard_fab2_lib.baseboard_fab2(sch_1):page24_i172:ddr1_dq(30)" )
			)
			( pin "U5D1.G72"
				( objectStatus "@baseboard_fab2_lib.baseboard_fab2(sch_1):page24_i172:ddr1_dq(31)" )
			)
			( pin "U5D1.K43"
				( objectStatus "@baseboard_fab2_lib.baseboard_fab2(sch_1):page24_i172:ddr1_dq(32)" )
			)
			( pin "U5D1.H43"
				( objectStatus "@baseboard_fab2_lib.baseboard_fab2(sch_1):page24_i172:ddr1_dq(33)" )
			)
			( pin "U5D1.L40"
				( objectStatus "@baseboard_fab2_lib.baseboard_fab2(sch_1):page24_i172:ddr1_dq(34)" )
			)
			( pin "U5D1.N40"
				( objectStatus "@baseboard_fab2_lib.baseboard_fab2(sch_1):page24_i172:ddr1_dq(35)" )
			)
			( pin "U5D1.P43"
				( objectStatus "@baseboard_fab2_lib.baseboard_fab2(sch_1):page24_i172:ddr1_dq(36)" )
			)
			( pin "U5D1.T43"
				( objectStatus "@baseboard_fab2_lib.baseboard_fab2(sch_1):page24_i172:ddr1_dq(37)" )
			)
			( pin "U5D1.K41"
				( objectStatus "@baseboard_fab2_lib.baseboard_fab2(sch_1):page24_i172:ddr1_dq(38)" )
			)
			( pin "U5D1.P41"
				( objectStatus "@baseboard_fab2_lib.baseboard_fab2(sch_1):page24_i172:ddr1_dq(39)" )
			)
			( pin "U5D1.C36"
				( objectStatus "@baseboard_fab2_lib.baseboard_fab2(sch_1):page24_i172:ddr1_dq(40)" )
			)
			( pin "U5D1.B35"
				( objectStatus "@baseboard_fab2_lib.baseboard_fab2(sch_1):page24_i172:ddr1_dq(41)" )
			)
			( pin "U5D1.C32"
				( objectStatus "@baseboard_fab2_lib.baseboard_fab2(sch_1):page24_i172:ddr1_dq(42)" )
			)
			( pin "U5D1.E32"
				( objectStatus "@baseboard_fab2_lib.baseboard_fab2(sch_1):page24_i172:ddr1_dq(43)" )
			)
			( pin "U5D1.E36"
				( objectStatus "@baseboard_fab2_lib.baseboard_fab2(sch_1):page24_i172:ddr1_dq(44)" )
			)
			( pin "U5D1.F35"
				( objectStatus "@baseboard_fab2_lib.baseboard_fab2(sch_1):page24_i172:ddr1_dq(45)" )
			)
			( pin "U5D1.B33"
				( objectStatus "@baseboard_fab2_lib.baseboard_fab2(sch_1):page24_i172:ddr1_dq(46)" )
			)
			( pin "U5D1.F33"
				( objectStatus "@baseboard_fab2_lib.baseboard_fab2(sch_1):page24_i172:ddr1_dq(47)" )
			)
			( pin "U5D1.C30"
				( objectStatus "@baseboard_fab2_lib.baseboard_fab2(sch_1):page24_i172:ddr1_dq(48)" )
			)
			( pin "U5D1.B29"
				( objectStatus "@baseboard_fab2_lib.baseboard_fab2(sch_1):page24_i172:ddr1_dq(49)" )
			)
			( pin "U5D1.C26"
				( objectStatus "@baseboard_fab2_lib.baseboard_fab2(sch_1):page24_i172:ddr1_dq(50)" )
			)
			( pin "U5D1.E26"
				( objectStatus "@baseboard_fab2_lib.baseboard_fab2(sch_1):page24_i172:ddr1_dq(51)" )
			)
			( pin "U5D1.E30"
				( objectStatus "@baseboard_fab2_lib.baseboard_fab2(sch_1):page24_i172:ddr1_dq(52)" )
			)
			( pin "U5D1.F29"
				( objectStatus "@baseboard_fab2_lib.baseboard_fab2(sch_1):page24_i172:ddr1_dq(53)" )
			)
			( pin "U5D1.B27"
				( objectStatus "@baseboard_fab2_lib.baseboard_fab2(sch_1):page24_i172:ddr1_dq(54)" )
			)
			( pin "U5D1.F27"
				( objectStatus "@baseboard_fab2_lib.baseboard_fab2(sch_1):page24_i172:ddr1_dq(55)" )
			)
			( pin "U5D1.U28"
				( objectStatus "@baseboard_fab2_lib.baseboard_fab2(sch_1):page24_i172:ddr1_dq(56)" )
			)
			( pin "U5D1.AA28"
				( objectStatus "@baseboard_fab2_lib.baseboard_fab2(sch_1):page24_i172:ddr1_dq(57)" )
			)
			( pin "U5D1.V25"
				( objectStatus "@baseboard_fab2_lib.baseboard_fab2(sch_1):page24_i172:ddr1_dq(58)" )
			)
			( pin "U5D1.Y25"
				( objectStatus "@baseboard_fab2_lib.baseboard_fab2(sch_1):page24_i172:ddr1_dq(59)" )
			)
			( pin "U5D1.V29"
				( objectStatus "@baseboard_fab2_lib.baseboard_fab2(sch_1):page24_i172:ddr1_dq(60)" )
			)
			( pin "U5D1.Y29"
				( objectStatus "@baseboard_fab2_lib.baseboard_fab2(sch_1):page24_i172:ddr1_dq(61)" )
			)
			( pin "U5D1.U26"
				( objectStatus "@baseboard_fab2_lib.baseboard_fab2(sch_1):page24_i172:ddr1_dq(62)" )
			)
			( pin "U5D1.AA26"
				( objectStatus "@baseboard_fab2_lib.baseboard_fab2(sch_1):page24_i172:ddr1_dq(63)" )
			)
			( pin "U5D1.AP79"
				( objectStatus "@baseboard_fab2_lib.baseboard_fab2(sch_1):page24_i172:ddr1_dqs_dn(0)" )
			)
			( pin "U5D1.AD79"
				( objectStatus "@baseboard_fab2_lib.baseboard_fab2(sch_1):page24_i172:ddr1_dqs_dn(1)" )
			)
			( pin "U5D1.K79"
				( objectStatus "@baseboard_fab2_lib.baseboard_fab2(sch_1):page24_i172:ddr1_dqs_dn(2)" )
			)
			( pin "U5D1.H73"
				( objectStatus "@baseboard_fab2_lib.baseboard_fab2(sch_1):page24_i172:ddr1_dqs_dn(3)" )
			)
			( pin "U5D1.N42"
				( objectStatus "@baseboard_fab2_lib.baseboard_fab2(sch_1):page24_i172:ddr1_dqs_dn(4)" )
			)
			( pin "U5D1.G34"
				( objectStatus "@baseboard_fab2_lib.baseboard_fab2(sch_1):page24_i172:ddr1_dqs_dn(5)" )
			)
			( pin "U5D1.G28"
				( objectStatus "@baseboard_fab2_lib.baseboard_fab2(sch_1):page24_i172:ddr1_dqs_dn(6)" )
			)
			( pin "U5D1.AB27"
				( objectStatus "@baseboard_fab2_lib.baseboard_fab2(sch_1):page24_i172:ddr1_dqs_dn(7)" )
			)
			( pin "U5D1.N68"
				( objectStatus "@baseboard_fab2_lib.baseboard_fab2(sch_1):page24_i172:ddr1_dqs_dn(8)" )
			)
			( pin "U5D1.AU82"
				( objectStatus "@baseboard_fab2_lib.baseboard_fab2(sch_1):page24_i172:ddr1_dqs_dn(9)" )
			)
			( pin "U5D1.AG82"
				( objectStatus "@baseboard_fab2_lib.baseboard_fab2(sch_1):page24_i172:ddr1_dqs_dn(10)" )
			)
			( pin "U5D1.D79"
				( objectStatus "@baseboard_fab2_lib.baseboard_fab2(sch_1):page24_i172:ddr1_dqs_dn(11)" )
			)
			( pin "U5D1.B73"
				( objectStatus "@baseboard_fab2_lib.baseboard_fab2(sch_1):page24_i172:ddr1_dqs_dn(12)" )
			)
			( pin "U5D1.J42"
				( objectStatus "@baseboard_fab2_lib.baseboard_fab2(sch_1):page24_i172:ddr1_dqs_dn(13)" )
			)
			( pin "U5D1.A34"
				( objectStatus "@baseboard_fab2_lib.baseboard_fab2(sch_1):page24_i172:ddr1_dqs_dn(14)" )
			)
			( pin "U5D1.A28"
				( objectStatus "@baseboard_fab2_lib.baseboard_fab2(sch_1):page24_i172:ddr1_dqs_dn(15)" )
			)
			( pin "U5D1.T27"
				( objectStatus "@baseboard_fab2_lib.baseboard_fab2(sch_1):page24_i172:ddr1_dqs_dn(16)" )
			)
			( pin "U5D1.G68"
				( objectStatus "@baseboard_fab2_lib.baseboard_fab2(sch_1):page24_i172:ddr1_dqs_dn(17)" )
			)
			( pin "U5D1.AR80"
				( objectStatus "@baseboard_fab2_lib.baseboard_fab2(sch_1):page24_i172:ddr1_dqs_dp(0)" )
			)
			( pin "U5D1.AE80"
				( objectStatus "@baseboard_fab2_lib.baseboard_fab2(sch_1):page24_i172:ddr1_dqs_dp(1)" )
			)
			( pin "U5D1.H79"
				( objectStatus "@baseboard_fab2_lib.baseboard_fab2(sch_1):page24_i172:ddr1_dqs_dp(2)" )
			)
			( pin "U5D1.F73"
				( objectStatus "@baseboard_fab2_lib.baseboard_fab2(sch_1):page24_i172:ddr1_dqs_dp(3)" )
			)
			( pin "U5D1.R42"
				( objectStatus "@baseboard_fab2_lib.baseboard_fab2(sch_1):page24_i172:ddr1_dqs_dp(4)" )
			)
			( pin "U5D1.E34"
				( objectStatus "@baseboard_fab2_lib.baseboard_fab2(sch_1):page24_i172:ddr1_dqs_dp(5)" )
			)
			( pin "U5D1.E28"
				( objectStatus "@baseboard_fab2_lib.baseboard_fab2(sch_1):page24_i172:ddr1_dqs_dp(6)" )
			)
			( pin "U5D1.Y27"
				( objectStatus "@baseboard_fab2_lib.baseboard_fab2(sch_1):page24_i172:ddr1_dqs_dp(7)" )
			)
			( pin "U5D1.L68"
				( objectStatus "@baseboard_fab2_lib.baseboard_fab2(sch_1):page24_i172:ddr1_dqs_dp(8)" )
			)
			( pin "U5D1.AT81"
				( objectStatus "@baseboard_fab2_lib.baseboard_fab2(sch_1):page24_i172:ddr1_dqs_dp(9)" )
			)
			( pin "U5D1.AF81"
				( objectStatus "@baseboard_fab2_lib.baseboard_fab2(sch_1):page24_i172:ddr1_dqs_dp(10)" )
			)
			( pin "U5D1.F79"
				( objectStatus "@baseboard_fab2_lib.baseboard_fab2(sch_1):page24_i172:ddr1_dqs_dp(11)" )
			)
			( pin "U5D1.D73"
				( objectStatus "@baseboard_fab2_lib.baseboard_fab2(sch_1):page24_i172:ddr1_dqs_dp(12)" )
			)
			( pin "U5D1.L42"
				( objectStatus "@baseboard_fab2_lib.baseboard_fab2(sch_1):page24_i172:ddr1_dqs_dp(13)" )
			)
			( pin "U5D1.C34"
				( objectStatus "@baseboard_fab2_lib.baseboard_fab2(sch_1):page24_i172:ddr1_dqs_dp(14)" )
			)
			( pin "U5D1.C28"
				( objectStatus "@baseboard_fab2_lib.baseboard_fab2(sch_1):page24_i172:ddr1_dqs_dp(15)" )
			)
			( pin "U5D1.V27"
				( objectStatus "@baseboard_fab2_lib.baseboard_fab2(sch_1):page24_i172:ddr1_dqs_dp(16)" )
			)
			( pin "U5D1.J68"
				( objectStatus "@baseboard_fab2_lib.baseboard_fab2(sch_1):page24_i172:ddr1_dqs_dp(17)" )
			)
			( pin "U5D1.J70"
				( objectStatus "@baseboard_fab2_lib.baseboard_fab2(sch_1):page24_i172:ddr1_ecc(0)" )
			)
			( pin "U5D1.H69"
				( objectStatus "@baseboard_fab2_lib.baseboard_fab2(sch_1):page24_i172:ddr1_ecc(1)" )
			)
			( pin "U5D1.J66"
				( objectStatus "@baseboard_fab2_lib.baseboard_fab2(sch_1):page24_i172:ddr1_ecc(2)" )
			)
			( pin "U5D1.L66"
				( objectStatus "@baseboard_fab2_lib.baseboard_fab2(sch_1):page24_i172:ddr1_ecc(3)" )
			)
			( pin "U5D1.L70"
				( objectStatus "@baseboard_fab2_lib.baseboard_fab2(sch_1):page24_i172:ddr1_ecc(4)" )
			)
			( pin "U5D1.M69"
				( objectStatus "@baseboard_fab2_lib.baseboard_fab2(sch_1):page24_i172:ddr1_ecc(5)" )
			)
			( pin "U5D1.H67"
				( objectStatus "@baseboard_fab2_lib.baseboard_fab2(sch_1):page24_i172:ddr1_ecc(6)" )
			)
			( pin "U5D1.M67"
				( objectStatus "@baseboard_fab2_lib.baseboard_fab2(sch_1):page24_i172:ddr1_ecc(7)" )
			)
			( pin "U5D1.J52"
				( objectStatus "@baseboard_fab2_lib.baseboard_fab2(sch_1):page24_i172:ddr1_ma(0)" )
			)
			( pin "U5D1.J58"
				( objectStatus "@baseboard_fab2_lib.baseboard_fab2(sch_1):page24_i172:ddr1_ma(1)" )
			)
			( pin "U5D1.K57"
				( objectStatus "@baseboard_fab2_lib.baseboard_fab2(sch_1):page24_i172:ddr1_ma(2)" )
			)
			( pin "U5D1.N58"
				( objectStatus "@baseboard_fab2_lib.baseboard_fab2(sch_1):page24_i172:ddr1_ma(3)" )
			)
			( pin "U5D1.M59"
				( objectStatus "@baseboard_fab2_lib.baseboard_fab2(sch_1):page24_i172:ddr1_ma(4)" )
			)
			( pin "U5D1.R58"
				( objectStatus "@baseboard_fab2_lib.baseboard_fab2(sch_1):page24_i172:ddr1_ma(5)" )
			)
			( pin "U5D1.T59"
				( objectStatus "@baseboard_fab2_lib.baseboard_fab2(sch_1):page24_i172:ddr1_ma(6)" )
			)
			( pin "U5D1.V61"
				( objectStatus "@baseboard_fab2_lib.baseboard_fab2(sch_1):page24_i172:ddr1_ma(7)" )
			)
			( pin "U5D1.W60"
				( objectStatus "@baseboard_fab2_lib.baseboard_fab2(sch_1):page24_i172:ddr1_ma(8)" )
			)
			( pin "U5D1.K59"
				( objectStatus "@baseboard_fab2_lib.baseboard_fab2(sch_1):page24_i172:ddr1_ma(9)" )
			)
			( pin "U5D1.M55"
				( objectStatus "@baseboard_fab2_lib.baseboard_fab2(sch_1):page24_i172:ddr1_ma(10)" )
			)
			( pin "U5D1.R60"
				( objectStatus "@baseboard_fab2_lib.baseboard_fab2(sch_1):page24_i172:ddr1_ma(11)" )
			)
			( pin "U5D1.T61"
				( objectStatus "@baseboard_fab2_lib.baseboard_fab2(sch_1):page24_i172:ddr1_ma(12)" )
			)
			( pin "U5D1.M51"
				( objectStatus "@baseboard_fab2_lib.baseboard_fab2(sch_1):page24_i172:ddr1_ma(13)" )
			)
			( pin "U5D1.T51"
				( objectStatus "@baseboard_fab2_lib.baseboard_fab2(sch_1):page24_i172:ddr1_ma(14)" )
			)
			( pin "U5D1.N52"
				( objectStatus "@baseboard_fab2_lib.baseboard_fab2(sch_1):page24_i172:ddr1_ma(15)" )
			)
			( pin "U5D1.R52"
				( objectStatus "@baseboard_fab2_lib.baseboard_fab2(sch_1):page24_i172:ddr1_ma(16)" )
			)
			( pin "U5D1.N48"
				( objectStatus "@baseboard_fab2_lib.baseboard_fab2(sch_1):page24_i172:ddr1_ma(17)" )
			)
			( pin "U5D1.N50"
				( objectStatus "@baseboard_fab2_lib.baseboard_fab2(sch_1):page24_i172:ddr1_odt(0)" )
			)
			( pin "U5D1.R48"
				( objectStatus "@baseboard_fab2_lib.baseboard_fab2(sch_1):page24_i172:ddr1_odt(1)" )
			)
			( pin "U5D1.M49"
				( objectStatus "@baseboard_fab2_lib.baseboard_fab2(sch_1):page24_i172:ddr1_odt(2)" )
			)
			( pin "U5D1.T47"
				( objectStatus "@baseboard_fab2_lib.baseboard_fab2(sch_1):page24_i172:ddr1_odt(3)" )
			)
			( pin "U5D1.K53"
				( objectStatus "@baseboard_fab2_lib.baseboard_fab2(sch_1):page24_i172:ddr1_par" )
			)
			( pin "U5D1.AB61"
				( objectStatus "@baseboard_fab2_lib.baseboard_fab2(sch_1):page25_i172:ddr2_act_n" )
			)
			( pin "U5D1.AD61"
				( objectStatus "@baseboard_fab2_lib.baseboard_fab2(sch_1):page25_i172:ddr2_alert_n" )
			)
			( pin "U5D1.W52"
				( objectStatus "@baseboard_fab2_lib.baseboard_fab2(sch_1):page25_i172:ddr2_ba(0)" )
			)
			( pin "U5D1.AE56"
				( objectStatus "@baseboard_fab2_lib.baseboard_fab2(sch_1):page25_i172:ddr2_ba(1)" )
			)
			( pin "U5D1.AA60"
				( objectStatus "@baseboard_fab2_lib.baseboard_fab2(sch_1):page25_i172:ddr2_bg(0)" )
			)
			( pin "U5D1.AE62"
				( objectStatus "@baseboard_fab2_lib.baseboard_fab2(sch_1):page25_i172:ddr2_bg(1)" )
			)
			( pin "U5D1.AB45"
				( objectStatus "@baseboard_fab2_lib.baseboard_fab2(sch_1):page25_i172:ddr2_cid(2)" )
			)
			( pin "U5D1.AA62"
				( objectStatus "@baseboard_fab2_lib.baseboard_fab2(sch_1):page25_i172:ddr2_cke(0)" )
			)
			( pin "U5D1.AD63"
				( objectStatus "@baseboard_fab2_lib.baseboard_fab2(sch_1):page25_i172:ddr2_cke(1)" )
			)
			( pin "U5D1.V63"
				( objectStatus "@baseboard_fab2_lib.baseboard_fab2(sch_1):page25_i172:ddr2_cke(2)" )
			)
			( pin "U5D1.AB63"
				( objectStatus "@baseboard_fab2_lib.baseboard_fab2(sch_1):page25_i172:ddr2_cke(3)" )
			)
			( pin "U5D1.AA54"
				( objectStatus "@baseboard_fab2_lib.baseboard_fab2(sch_1):page25_i172:ddr2_clk_dn(0)" )
			)
			( pin "U5D1.W54"
				( objectStatus "@baseboard_fab2_lib.baseboard_fab2(sch_1):page25_i172:ddr2_clk_dn(1)" )
			)
			( pin "U5D1.AA56"
				( objectStatus "@baseboard_fab2_lib.baseboard_fab2(sch_1):page25_i172:ddr2_clk_dn(2)" )
			)
			( pin "U5D1.W56"
				( objectStatus "@baseboard_fab2_lib.baseboard_fab2(sch_1):page25_i172:ddr2_clk_dn(3)" )
			)
			( pin "U5D1.AB55"
				( objectStatus "@baseboard_fab2_lib.baseboard_fab2(sch_1):page25_i172:ddr2_clk_dp(0)" )
			)
			( pin "U5D1.V55"
				( objectStatus "@baseboard_fab2_lib.baseboard_fab2(sch_1):page25_i172:ddr2_clk_dp(1)" )
			)
			( pin "U5D1.AB57"
				( objectStatus "@baseboard_fab2_lib.baseboard_fab2(sch_1):page25_i172:ddr2_clk_dp(2)" )
			)
			( pin "U5D1.V57"
				( objectStatus "@baseboard_fab2_lib.baseboard_fab2(sch_1):page25_i172:ddr2_clk_dp(3)" )
			)
			( pin "U5D1.V51"
				( objectStatus "@baseboard_fab2_lib.baseboard_fab2(sch_1):page25_i172:ddr2_cs_n(0)" )
			)
			( pin "U5D1.AB49"
				( objectStatus "@baseboard_fab2_lib.baseboard_fab2(sch_1):page25_i172:ddr2_cs_n(1)" )
			)
			( pin "U5D1.W46"
				( objectStatus "@baseboard_fab2_lib.baseboard_fab2(sch_1):page25_i172:ddr2_cs_n(2)" )
			)
			( pin "U5D1.AA46"
				( objectStatus "@baseboard_fab2_lib.baseboard_fab2(sch_1):page25_i172:ddr2_cs_n(3)" )
			)
			( pin "U5D1.AB51"
				( objectStatus "@baseboard_fab2_lib.baseboard_fab2(sch_1):page25_i172:ddr2_cs_n(4)" )
			)
			( pin "U5D1.W48"
				( objectStatus "@baseboard_fab2_lib.baseboard_fab2(sch_1):page25_i172:ddr2_cs_n(5)" )
			)
			( pin "U5D1.T45"
				( objectStatus "@baseboard_fab2_lib.baseboard_fab2(sch_1):page25_i172:ddr2_cs_n(6)" )
			)
			( pin "U5D1.V45"
				( objectStatus "@baseboard_fab2_lib.baseboard_fab2(sch_1):page25_i172:ddr2_cs_n(7)" )
			)
			( pin "U5D1.AR76"
				( objectStatus "@baseboard_fab2_lib.baseboard_fab2(sch_1):page25_i172:ddr2_dq(0)" )
			)
			( pin "U5D1.AN74"
				( objectStatus "@baseboard_fab2_lib.baseboard_fab2(sch_1):page25_i172:ddr2_dq(1)" )
			)
			( pin "U5D1.AK77"
				( objectStatus "@baseboard_fab2_lib.baseboard_fab2(sch_1):page25_i172:ddr2_dq(2)" )
			)
			( pin "U5D1.AJ76"
				( objectStatus "@baseboard_fab2_lib.baseboard_fab2(sch_1):page25_i172:ddr2_dq(3)" )
			)
			( pin "U5D1.AT75"
				( objectStatus "@baseboard_fab2_lib.baseboard_fab2(sch_1):page25_i172:ddr2_dq(4)" )
			)
			( pin "U5D1.AR74"
				( objectStatus "@baseboard_fab2_lib.baseboard_fab2(sch_1):page25_i172:ddr2_dq(5)" )
			)
			( pin "U5D1.AM77"
				( objectStatus "@baseboard_fab2_lib.baseboard_fab2(sch_1):page25_i172:ddr2_dq(6)" )
			)
			( pin "U5D1.AK75"
				( objectStatus "@baseboard_fab2_lib.baseboard_fab2(sch_1):page25_i172:ddr2_dq(7)" )
			)
			( pin "U5D1.AE76"
				( objectStatus "@baseboard_fab2_lib.baseboard_fab2(sch_1):page25_i172:ddr2_dq(8)" )
			)
			( pin "U5D1.AC74"
				( objectStatus "@baseboard_fab2_lib.baseboard_fab2(sch_1):page25_i172:ddr2_dq(9)" )
			)
			( pin "U5D1.Y77"
				( objectStatus "@baseboard_fab2_lib.baseboard_fab2(sch_1):page25_i172:ddr2_dq(10)" )
			)
			( pin "U5D1.W76"
				( objectStatus "@baseboard_fab2_lib.baseboard_fab2(sch_1):page25_i172:ddr2_dq(11)" )
			)
			( pin "U5D1.AF75"
				( objectStatus "@baseboard_fab2_lib.baseboard_fab2(sch_1):page25_i172:ddr2_dq(12)" )
			)
			( pin "U5D1.AE74"
				( objectStatus "@baseboard_fab2_lib.baseboard_fab2(sch_1):page25_i172:ddr2_dq(13)" )
			)
			( pin "U5D1.AB77"
				( objectStatus "@baseboard_fab2_lib.baseboard_fab2(sch_1):page25_i172:ddr2_dq(14)" )
			)
			( pin "U5D1.Y75"
				( objectStatus "@baseboard_fab2_lib.baseboard_fab2(sch_1):page25_i172:ddr2_dq(15)" )
			)
			( pin "U5D1.W72"
				( objectStatus "@baseboard_fab2_lib.baseboard_fab2(sch_1):page25_i172:ddr2_dq(16)" )
			)
			( pin "U5D1.AA70"
				( objectStatus "@baseboard_fab2_lib.baseboard_fab2(sch_1):page25_i172:ddr2_dq(17)" )
			)
			( pin "U5D1.R70"
				( objectStatus "@baseboard_fab2_lib.baseboard_fab2(sch_1):page25_i172:ddr2_dq(18)" )
			)
			( pin "U5D1.T69"
				( objectStatus "@baseboard_fab2_lib.baseboard_fab2(sch_1):page25_i172:ddr2_dq(19)" )
			)
			( pin "U5D1.AA72"
				( objectStatus "@baseboard_fab2_lib.baseboard_fab2(sch_1):page25_i172:ddr2_dq(20)" )
			)
			( pin "U5D1.AB71"
				( objectStatus "@baseboard_fab2_lib.baseboard_fab2(sch_1):page25_i172:ddr2_dq(21)" )
			)
			( pin "U5D1.T71"
				( objectStatus "@baseboard_fab2_lib.baseboard_fab2(sch_1):page25_i172:ddr2_dq(22)" )
			)
			( pin "U5D1.V69"
				( objectStatus "@baseboard_fab2_lib.baseboard_fab2(sch_1):page25_i172:ddr2_dq(23)" )
			)
			( pin "U5D1.AM67"
				( objectStatus "@baseboard_fab2_lib.baseboard_fab2(sch_1):page25_i172:ddr2_dq(24)" )
			)
			( pin "U5D1.AT67"
				( objectStatus "@baseboard_fab2_lib.baseboard_fab2(sch_1):page25_i172:ddr2_dq(25)" )
			)
			( pin "U5D1.AN64"
				( objectStatus "@baseboard_fab2_lib.baseboard_fab2(sch_1):page25_i172:ddr2_dq(26)" )
			)
			( pin "U5D1.AR64"
				( objectStatus "@baseboard_fab2_lib.baseboard_fab2(sch_1):page25_i172:ddr2_dq(27)" )
			)
			( pin "U5D1.AN68"
				( objectStatus "@baseboard_fab2_lib.baseboard_fab2(sch_1):page25_i172:ddr2_dq(28)" )
			)
			( pin "U5D1.AR68"
				( objectStatus "@baseboard_fab2_lib.baseboard_fab2(sch_1):page25_i172:ddr2_dq(29)" )
			)
			( pin "U5D1.AM65"
				( objectStatus "@baseboard_fab2_lib.baseboard_fab2(sch_1):page25_i172:ddr2_dq(30)" )
			)
			( pin "U5D1.AT65"
				( objectStatus "@baseboard_fab2_lib.baseboard_fab2(sch_1):page25_i172:ddr2_dq(31)" )
			)
			( pin "U5D1.U40"
				( objectStatus "@baseboard_fab2_lib.baseboard_fab2(sch_1):page25_i172:ddr2_dq(32)" )
			)
			( pin "U5D1.AA40"
				( objectStatus "@baseboard_fab2_lib.baseboard_fab2(sch_1):page25_i172:ddr2_dq(33)" )
			)
			( pin "U5D1.V37"
				( objectStatus "@baseboard_fab2_lib.baseboard_fab2(sch_1):page25_i172:ddr2_dq(34)" )
			)
			( pin "U5D1.Y37"
				( objectStatus "@baseboard_fab2_lib.baseboard_fab2(sch_1):page25_i172:ddr2_dq(35)" )
			)
			( pin "U5D1.V41"
				( objectStatus "@baseboard_fab2_lib.baseboard_fab2(sch_1):page25_i172:ddr2_dq(36)" )
			)
			( pin "U5D1.Y41"
				( objectStatus "@baseboard_fab2_lib.baseboard_fab2(sch_1):page25_i172:ddr2_dq(37)" )
			)
			( pin "U5D1.U38"
				( objectStatus "@baseboard_fab2_lib.baseboard_fab2(sch_1):page25_i172:ddr2_dq(38)" )
			)
			( pin "U5D1.AA38"
				( objectStatus "@baseboard_fab2_lib.baseboard_fab2(sch_1):page25_i172:ddr2_dq(39)" )
			)
			( pin "U5D1.U34"
				( objectStatus "@baseboard_fab2_lib.baseboard_fab2(sch_1):page25_i172:ddr2_dq(40)" )
			)
			( pin "U5D1.AA34"
				( objectStatus "@baseboard_fab2_lib.baseboard_fab2(sch_1):page25_i172:ddr2_dq(41)" )
			)
			( pin "U5D1.V31"
				( objectStatus "@baseboard_fab2_lib.baseboard_fab2(sch_1):page25_i172:ddr2_dq(42)" )
			)
			( pin "U5D1.Y31"
				( objectStatus "@baseboard_fab2_lib.baseboard_fab2(sch_1):page25_i172:ddr2_dq(43)" )
			)
			( pin "U5D1.V35"
				( objectStatus "@baseboard_fab2_lib.baseboard_fab2(sch_1):page25_i172:ddr2_dq(44)" )
			)
			( pin "U5D1.Y35"
				( objectStatus "@baseboard_fab2_lib.baseboard_fab2(sch_1):page25_i172:ddr2_dq(45)" )
			)
			( pin "U5D1.U32"
				( objectStatus "@baseboard_fab2_lib.baseboard_fab2(sch_1):page25_i172:ddr2_dq(46)" )
			)
			( pin "U5D1.AA32"
				( objectStatus "@baseboard_fab2_lib.baseboard_fab2(sch_1):page25_i172:ddr2_dq(47)" )
			)
			( pin "U5D1.AD31"
				( objectStatus "@baseboard_fab2_lib.baseboard_fab2(sch_1):page25_i172:ddr2_dq(48)" )
			)
			( pin "U5D1.AH31"
				( objectStatus "@baseboard_fab2_lib.baseboard_fab2(sch_1):page25_i172:ddr2_dq(49)" )
			)
			( pin "U5D1.AE28"
				( objectStatus "@baseboard_fab2_lib.baseboard_fab2(sch_1):page25_i172:ddr2_dq(50)" )
			)
			( pin "U5D1.AG28"
				( objectStatus "@baseboard_fab2_lib.baseboard_fab2(sch_1):page25_i172:ddr2_dq(51)" )
			)
			( pin "U5D1.AE32"
				( objectStatus "@baseboard_fab2_lib.baseboard_fab2(sch_1):page25_i172:ddr2_dq(52)" )
			)
			( pin "U5D1.AG32"
				( objectStatus "@baseboard_fab2_lib.baseboard_fab2(sch_1):page25_i172:ddr2_dq(53)" )
			)
			( pin "U5D1.AD29"
				( objectStatus "@baseboard_fab2_lib.baseboard_fab2(sch_1):page25_i172:ddr2_dq(54)" )
			)
			( pin "U5D1.AH29"
				( objectStatus "@baseboard_fab2_lib.baseboard_fab2(sch_1):page25_i172:ddr2_dq(55)" )
			)
			( pin "U5D1.AD25"
				( objectStatus "@baseboard_fab2_lib.baseboard_fab2(sch_1):page25_i172:ddr2_dq(56)" )
			)
			( pin "U5D1.AH25"
				( objectStatus "@baseboard_fab2_lib.baseboard_fab2(sch_1):page25_i172:ddr2_dq(57)" )
			)
			( pin "U5D1.AE22"
				( objectStatus "@baseboard_fab2_lib.baseboard_fab2(sch_1):page25_i172:ddr2_dq(58)" )
			)
			( pin "U5D1.AG22"
				( objectStatus "@baseboard_fab2_lib.baseboard_fab2(sch_1):page25_i172:ddr2_dq(59)" )
			)
			( pin "U5D1.AE26"
				( objectStatus "@baseboard_fab2_lib.baseboard_fab2(sch_1):page25_i172:ddr2_dq(60)" )
			)
			( pin "U5D1.AG26"
				( objectStatus "@baseboard_fab2_lib.baseboard_fab2(sch_1):page25_i172:ddr2_dq(61)" )
			)
			( pin "U5D1.AD23"
				( objectStatus "@baseboard_fab2_lib.baseboard_fab2(sch_1):page25_i172:ddr2_dq(62)" )
			)
			( pin "U5D1.AH23"
				( objectStatus "@baseboard_fab2_lib.baseboard_fab2(sch_1):page25_i172:ddr2_dq(63)" )
			)
			( pin "U5D1.AL74"
				( objectStatus "@baseboard_fab2_lib.baseboard_fab2(sch_1):page25_i172:ddr2_dqs_dn(0)" )
			)
			( pin "U5D1.AA74"
				( objectStatus "@baseboard_fab2_lib.baseboard_fab2(sch_1):page25_i172:ddr2_dqs_dn(1)" )
			)
			( pin "U5D1.Y69"
				( objectStatus "@baseboard_fab2_lib.baseboard_fab2(sch_1):page25_i172:ddr2_dqs_dn(2)" )
			)
			( pin "U5D1.AU66"
				( objectStatus "@baseboard_fab2_lib.baseboard_fab2(sch_1):page25_i172:ddr2_dqs_dn(3)" )
			)
			( pin "U5D1.AB39"
				( objectStatus "@baseboard_fab2_lib.baseboard_fab2(sch_1):page25_i172:ddr2_dqs_dn(4)" )
			)
			( pin "U5D1.AB33"
				( objectStatus "@baseboard_fab2_lib.baseboard_fab2(sch_1):page25_i172:ddr2_dqs_dn(5)" )
			)
			( pin "U5D1.AJ30"
				( objectStatus "@baseboard_fab2_lib.baseboard_fab2(sch_1):page25_i172:ddr2_dqs_dn(6)" )
			)
			( pin "U5D1.AJ24"
				( objectStatus "@baseboard_fab2_lib.baseboard_fab2(sch_1):page25_i172:ddr2_dqs_dn(7)" )
			)
			( pin "U5D1.BB71"
				( objectStatus "@baseboard_fab2_lib.baseboard_fab2(sch_1):page25_i172:ddr2_dqs_dn(8)" )
			)
			( pin "U5D1.AP77"
				( objectStatus "@baseboard_fab2_lib.baseboard_fab2(sch_1):page25_i172:ddr2_dqs_dn(9)" )
			)
			( pin "U5D1.AD77"
				( objectStatus "@baseboard_fab2_lib.baseboard_fab2(sch_1):page25_i172:ddr2_dqs_dn(10)" )
			)
			( pin "U5D1.U72"
				( objectStatus "@baseboard_fab2_lib.baseboard_fab2(sch_1):page25_i172:ddr2_dqs_dn(11)" )
			)
			( pin "U5D1.AL66"
				( objectStatus "@baseboard_fab2_lib.baseboard_fab2(sch_1):page25_i172:ddr2_dqs_dn(12)" )
			)
			( pin "U5D1.T39"
				( objectStatus "@baseboard_fab2_lib.baseboard_fab2(sch_1):page25_i172:ddr2_dqs_dn(13)" )
			)
			( pin "U5D1.T33"
				( objectStatus "@baseboard_fab2_lib.baseboard_fab2(sch_1):page25_i172:ddr2_dqs_dn(14)" )
			)
			( pin "U5D1.AC30"
				( objectStatus "@baseboard_fab2_lib.baseboard_fab2(sch_1):page25_i172:ddr2_dqs_dn(15)" )
			)
			( pin "U5D1.AC24"
				( objectStatus "@baseboard_fab2_lib.baseboard_fab2(sch_1):page25_i172:ddr2_dqs_dn(16)" )
			)
			( pin "U5D1.AT71"
				( objectStatus "@baseboard_fab2_lib.baseboard_fab2(sch_1):page25_i172:ddr2_dqs_dn(17)" )
			)
			( pin "U5D1.AM75"
				( objectStatus "@baseboard_fab2_lib.baseboard_fab2(sch_1):page25_i172:ddr2_dqs_dp(0)" )
			)
			( pin "U5D1.AB75"
				( objectStatus "@baseboard_fab2_lib.baseboard_fab2(sch_1):page25_i172:ddr2_dqs_dp(1)" )
			)
			( pin "U5D1.W70"
				( objectStatus "@baseboard_fab2_lib.baseboard_fab2(sch_1):page25_i172:ddr2_dqs_dp(2)" )
			)
			( pin "U5D1.AR66"
				( objectStatus "@baseboard_fab2_lib.baseboard_fab2(sch_1):page25_i172:ddr2_dqs_dp(3)" )
			)
			( pin "U5D1.Y39"
				( objectStatus "@baseboard_fab2_lib.baseboard_fab2(sch_1):page25_i172:ddr2_dqs_dp(4)" )
			)
			( pin "U5D1.Y33"
				( objectStatus "@baseboard_fab2_lib.baseboard_fab2(sch_1):page25_i172:ddr2_dqs_dp(5)" )
			)
			( pin "U5D1.AG30"
				( objectStatus "@baseboard_fab2_lib.baseboard_fab2(sch_1):page25_i172:ddr2_dqs_dp(6)" )
			)
			( pin "U5D1.AG24"
				( objectStatus "@baseboard_fab2_lib.baseboard_fab2(sch_1):page25_i172:ddr2_dqs_dp(7)" )
			)
			( pin "U5D1.AY71"
				( objectStatus "@baseboard_fab2_lib.baseboard_fab2(sch_1):page25_i172:ddr2_dqs_dp(8)" )
			)
			( pin "U5D1.AN76"
				( objectStatus "@baseboard_fab2_lib.baseboard_fab2(sch_1):page25_i172:ddr2_dqs_dp(9)" )
			)
			( pin "U5D1.AC76"
				( objectStatus "@baseboard_fab2_lib.baseboard_fab2(sch_1):page25_i172:ddr2_dqs_dp(10)" )
			)
			( pin "U5D1.V71"
				( objectStatus "@baseboard_fab2_lib.baseboard_fab2(sch_1):page25_i172:ddr2_dqs_dp(11)" )
			)
			( pin "U5D1.AN66"
				( objectStatus "@baseboard_fab2_lib.baseboard_fab2(sch_1):page25_i172:ddr2_dqs_dp(12)" )
			)
			( pin "U5D1.V39"
				( objectStatus "@baseboard_fab2_lib.baseboard_fab2(sch_1):page25_i172:ddr2_dqs_dp(13)" )
			)
			( pin "U5D1.V33"
				( objectStatus "@baseboard_fab2_lib.baseboard_fab2(sch_1):page25_i172:ddr2_dqs_dp(14)" )
			)
			( pin "U5D1.AE30"
				( objectStatus "@baseboard_fab2_lib.baseboard_fab2(sch_1):page25_i172:ddr2_dqs_dp(15)" )
			)
			( pin "U5D1.AE24"
				( objectStatus "@baseboard_fab2_lib.baseboard_fab2(sch_1):page25_i172:ddr2_dqs_dp(16)" )
			)
			( pin "U5D1.AV71"
				( objectStatus "@baseboard_fab2_lib.baseboard_fab2(sch_1):page25_i172:ddr2_dqs_dp(17)" )
			)
			( pin "U5D1.AU72"
				( objectStatus "@baseboard_fab2_lib.baseboard_fab2(sch_1):page25_i172:ddr2_ecc(0)" )
			)
			( pin "U5D1.BA72"
				( objectStatus "@baseboard_fab2_lib.baseboard_fab2(sch_1):page25_i172:ddr2_ecc(1)" )
			)
			( pin "U5D1.AV69"
				( objectStatus "@baseboard_fab2_lib.baseboard_fab2(sch_1):page25_i172:ddr2_ecc(2)" )
			)
			( pin "U5D1.AY69"
				( objectStatus "@baseboard_fab2_lib.baseboard_fab2(sch_1):page25_i172:ddr2_ecc(3)" )
			)
			( pin "U5D1.AV73"
				( objectStatus "@baseboard_fab2_lib.baseboard_fab2(sch_1):page25_i172:ddr2_ecc(4)" )
			)
			( pin "U5D1.AY73"
				( objectStatus "@baseboard_fab2_lib.baseboard_fab2(sch_1):page25_i172:ddr2_ecc(5)" )
			)
			( pin "U5D1.AU70"
				( objectStatus "@baseboard_fab2_lib.baseboard_fab2(sch_1):page25_i172:ddr2_ecc(6)" )
			)
			( pin "U5D1.BA70"
				( objectStatus "@baseboard_fab2_lib.baseboard_fab2(sch_1):page25_i172:ddr2_ecc(7)" )
			)
			( pin "U5D1.AB53"
				( objectStatus "@baseboard_fab2_lib.baseboard_fab2(sch_1):page25_i172:ddr2_ma(0)" )
			)
			( pin "U5D1.AE58"
				( objectStatus "@baseboard_fab2_lib.baseboard_fab2(sch_1):page25_i172:ddr2_ma(1)" )
			)
			( pin "U5D1.AD57"
				( objectStatus "@baseboard_fab2_lib.baseboard_fab2(sch_1):page25_i172:ddr2_ma(2)" )
			)
			( pin "U5D1.W58"
				( objectStatus "@baseboard_fab2_lib.baseboard_fab2(sch_1):page25_i172:ddr2_ma(3)" )
			)
			( pin "U5D1.AA58"
				( objectStatus "@baseboard_fab2_lib.baseboard_fab2(sch_1):page25_i172:ddr2_ma(4)" )
			)
			( pin "U5D1.V59"
				( objectStatus "@baseboard_fab2_lib.baseboard_fab2(sch_1):page25_i172:ddr2_ma(5)" )
			)
			( pin "U5D1.AB59"
				( objectStatus "@baseboard_fab2_lib.baseboard_fab2(sch_1):page25_i172:ddr2_ma(6)" )
			)
			( pin "U5D1.AE60"
				( objectStatus "@baseboard_fab2_lib.baseboard_fab2(sch_1):page25_i172:ddr2_ma(7)" )
			)
			( pin "U5D1.AD59"
				( objectStatus "@baseboard_fab2_lib.baseboard_fab2(sch_1):page25_i172:ddr2_ma(8)" )
			)
			( pin "U5D1.AG58"
				( objectStatus "@baseboard_fab2_lib.baseboard_fab2(sch_1):page25_i172:ddr2_ma(9)" )
			)
			( pin "U5D1.AD55"
				( objectStatus "@baseboard_fab2_lib.baseboard_fab2(sch_1):page25_i172:ddr2_ma(10)" )
			)
			( pin "U5D1.AG60"
				( objectStatus "@baseboard_fab2_lib.baseboard_fab2(sch_1):page25_i172:ddr2_ma(11)" )
			)
			( pin "U5D1.AG62"
				( objectStatus "@baseboard_fab2_lib.baseboard_fab2(sch_1):page25_i172:ddr2_ma(12)" )
			)
			( pin "U5D1.AD53"
				( objectStatus "@baseboard_fab2_lib.baseboard_fab2(sch_1):page25_i172:ddr2_ma(13)" )
			)
			( pin "U5D1.W50"
				( objectStatus "@baseboard_fab2_lib.baseboard_fab2(sch_1):page25_i172:ddr2_ma(14)" )
			)
			( pin "U5D1.AE54"
				( objectStatus "@baseboard_fab2_lib.baseboard_fab2(sch_1):page25_i172:ddr2_ma(15)" )
			)
			( pin "U5D1.AA52"
				( objectStatus "@baseboard_fab2_lib.baseboard_fab2(sch_1):page25_i172:ddr2_ma(16)" )
			)
			( pin "U5D1.AC46"
				( objectStatus "@baseboard_fab2_lib.baseboard_fab2(sch_1):page25_i172:ddr2_ma(17)" )
			)
			( pin "U5D1.AA50"
				( objectStatus "@baseboard_fab2_lib.baseboard_fab2(sch_1):page25_i172:ddr2_odt(0)" )
			)
			( pin "U5D1.AA48"
				( objectStatus "@baseboard_fab2_lib.baseboard_fab2(sch_1):page25_i172:ddr2_odt(1)" )
			)
			( pin "U5D1.V49"
				( objectStatus "@baseboard_fab2_lib.baseboard_fab2(sch_1):page25_i172:ddr2_odt(2)" )
			)
			( pin "U5D1.AB47"
				( objectStatus "@baseboard_fab2_lib.baseboard_fab2(sch_1):page25_i172:ddr2_odt(3)" )
			)
			( pin "U5D1.V53"
				( objectStatus "@baseboard_fab2_lib.baseboard_fab2(sch_1):page25_i172:ddr2_par" )
			)
			( pin "U5D1.DW60"
				( objectStatus "@baseboard_fab2_lib.baseboard_fab2(sch_1):page26_i172:ddr3_act_n" )
			)
			( pin "U5D1.ED63"
				( objectStatus "@baseboard_fab2_lib.baseboard_fab2(sch_1):page26_i172:ddr3_alert_n" )
			)
			( pin "U5D1.EE52"
				( objectStatus "@baseboard_fab2_lib.baseboard_fab2(sch_1):page26_i172:ddr3_ba(0)" )
			)
			( pin "U5D1.EA54"
				( objectStatus "@baseboard_fab2_lib.baseboard_fab2(sch_1):page26_i172:ddr3_ba(1)" )
			)
			( pin "U5D1.ED61"
				( objectStatus "@baseboard_fab2_lib.baseboard_fab2(sch_1):page26_i172:ddr3_bg(0)" )
			)
			( pin "U5D1.DW62"
				( objectStatus "@baseboard_fab2_lib.baseboard_fab2(sch_1):page26_i172:ddr3_bg(1)" )
			)
			( pin "U5D1.DV47"
				( objectStatus "@baseboard_fab2_lib.baseboard_fab2(sch_1):page26_i172:ddr3_cid(2)" )
			)
			( pin "U5D1.EE62"
				( objectStatus "@baseboard_fab2_lib.baseboard_fab2(sch_1):page26_i172:ddr3_cke(0)" )
			)
			( pin "U5D1.EF63"
				( objectStatus "@baseboard_fab2_lib.baseboard_fab2(sch_1):page26_i172:ddr3_cke(1)" )
			)
			( pin "U5D1.EA62"
				( objectStatus "@baseboard_fab2_lib.baseboard_fab2(sch_1):page26_i172:ddr3_cke(2)" )
			)
			( pin "U5D1.EB63"
				( objectStatus "@baseboard_fab2_lib.baseboard_fab2(sch_1):page26_i172:ddr3_cke(3)" )
			)
			( pin "U5D1.ED55"
				( objectStatus "@baseboard_fab2_lib.baseboard_fab2(sch_1):page26_i172:ddr3_clk_dn(0)" )
			)
			( pin "U5D1.EF55"
				( objectStatus "@baseboard_fab2_lib.baseboard_fab2(sch_1):page26_i172:ddr3_clk_dn(1)" )
			)
			( pin "U5D1.DW56"
				( objectStatus "@baseboard_fab2_lib.baseboard_fab2(sch_1):page26_i172:ddr3_clk_dn(2)" )
			)
			( pin "U5D1.EF57"
				( objectStatus "@baseboard_fab2_lib.baseboard_fab2(sch_1):page26_i172:ddr3_clk_dn(3)" )
			)
			( pin "U5D1.EB55"
				( objectStatus "@baseboard_fab2_lib.baseboard_fab2(sch_1):page26_i172:ddr3_clk_dp(0)" )
			)
			( pin "U5D1.EE54"
				( objectStatus "@baseboard_fab2_lib.baseboard_fab2(sch_1):page26_i172:ddr3_clk_dp(1)" )
			)
			( pin "U5D1.EA56"
				( objectStatus "@baseboard_fab2_lib.baseboard_fab2(sch_1):page26_i172:ddr3_clk_dp(2)" )
			)
			( pin "U5D1.EE56"
				( objectStatus "@baseboard_fab2_lib.baseboard_fab2(sch_1):page26_i172:ddr3_clk_dp(3)" )
			)
			( pin "U5D1.EF51"
				( objectStatus "@baseboard_fab2_lib.baseboard_fab2(sch_1):page26_i172:ddr3_cs_n(0)" )
			)
			( pin "U5D1.ED49"
				( objectStatus "@baseboard_fab2_lib.baseboard_fab2(sch_1):page26_i172:ddr3_cs_n(1)" )
			)
			( pin "U5D1.ED47"
				( objectStatus "@baseboard_fab2_lib.baseboard_fab2(sch_1):page26_i172:ddr3_cs_n(2)" )
			)
			( pin "U5D1.EB47"
				( objectStatus "@baseboard_fab2_lib.baseboard_fab2(sch_1):page26_i172:ddr3_cs_n(3)" )
			)
			( pin "U5D1.EB51"
				( objectStatus "@baseboard_fab2_lib.baseboard_fab2(sch_1):page26_i172:ddr3_cs_n(4)" )
			)
			( pin "U5D1.EB49"
				( objectStatus "@baseboard_fab2_lib.baseboard_fab2(sch_1):page26_i172:ddr3_cs_n(5)" )
			)
			( pin "U5D1.DV45"
				( objectStatus "@baseboard_fab2_lib.baseboard_fab2(sch_1):page26_i172:ddr3_cs_n(6)" )
			)
			( pin "U5D1.EB45"
				( objectStatus "@baseboard_fab2_lib.baseboard_fab2(sch_1):page26_i172:ddr3_cs_n(7)" )
			)
			( pin "U5D1.CN84"
				( objectStatus "@baseboard_fab2_lib.baseboard_fab2(sch_1):page26_i172:ddr3_dq(0)" )
			)
			( pin "U5D1.CN86"
				( objectStatus "@baseboard_fab2_lib.baseboard_fab2(sch_1):page26_i172:ddr3_dq(1)" )
			)
			( pin "U5D1.DA86"
				( objectStatus "@baseboard_fab2_lib.baseboard_fab2(sch_1):page26_i172:ddr3_dq(2)" )
			)
			( pin "U5D1.DA84"
				( objectStatus "@baseboard_fab2_lib.baseboard_fab2(sch_1):page26_i172:ddr3_dq(3)" )
			)
			( pin "U5D1.CL84"
				( objectStatus "@baseboard_fab2_lib.baseboard_fab2(sch_1):page26_i172:ddr3_dq(4)" )
			)
			( pin "U5D1.CL86"
				( objectStatus "@baseboard_fab2_lib.baseboard_fab2(sch_1):page26_i172:ddr3_dq(5)" )
			)
			( pin "U5D1.CW86"
				( objectStatus "@baseboard_fab2_lib.baseboard_fab2(sch_1):page26_i172:ddr3_dq(6)" )
			)
			( pin "U5D1.CW84"
				( objectStatus "@baseboard_fab2_lib.baseboard_fab2(sch_1):page26_i172:ddr3_dq(7)" )
			)
			( pin "U5D1.DG84"
				( objectStatus "@baseboard_fab2_lib.baseboard_fab2(sch_1):page26_i172:ddr3_dq(8)" )
			)
			( pin "U5D1.DH85"
				( objectStatus "@baseboard_fab2_lib.baseboard_fab2(sch_1):page26_i172:ddr3_dq(9)" )
			)
			( pin "U5D1.DV83"
				( objectStatus "@baseboard_fab2_lib.baseboard_fab2(sch_1):page26_i172:ddr3_dq(10)" )
			)
			( pin "U5D1.DY83"
				( objectStatus "@baseboard_fab2_lib.baseboard_fab2(sch_1):page26_i172:ddr3_dq(11)" )
			)
			( pin "U5D1.DD85"
				( objectStatus "@baseboard_fab2_lib.baseboard_fab2(sch_1):page26_i172:ddr3_dq(12)" )
			)
			( pin "U5D1.DE84"
				( objectStatus "@baseboard_fab2_lib.baseboard_fab2(sch_1):page26_i172:ddr3_dq(13)" )
			)
			( pin "U5D1.DR84"
				( objectStatus "@baseboard_fab2_lib.baseboard_fab2(sch_1):page26_i172:ddr3_dq(14)" )
			)
			( pin "U5D1.DV85"
				( objectStatus "@baseboard_fab2_lib.baseboard_fab2(sch_1):page26_i172:ddr3_dq(15)" )
			)
			( pin "U5D1.DM79"
				( objectStatus "@baseboard_fab2_lib.baseboard_fab2(sch_1):page26_i172:ddr3_dq(16)" )
			)
			( pin "U5D1.DK81"
				( objectStatus "@baseboard_fab2_lib.baseboard_fab2(sch_1):page26_i172:ddr3_dq(17)" )
			)
			( pin "U5D1.DT81"
				( objectStatus "@baseboard_fab2_lib.baseboard_fab2(sch_1):page26_i172:ddr3_dq(18)" )
			)
			( pin "U5D1.DR82"
				( objectStatus "@baseboard_fab2_lib.baseboard_fab2(sch_1):page26_i172:ddr3_dq(19)" )
			)
			( pin "U5D1.DK79"
				( objectStatus "@baseboard_fab2_lib.baseboard_fab2(sch_1):page26_i172:ddr3_dq(20)" )
			)
			( pin "U5D1.DJ80"
				( objectStatus "@baseboard_fab2_lib.baseboard_fab2(sch_1):page26_i172:ddr3_dq(21)" )
			)
			( pin "U5D1.DR80"
				( objectStatus "@baseboard_fab2_lib.baseboard_fab2(sch_1):page26_i172:ddr3_dq(22)" )
			)
			( pin "U5D1.DN82"
				( objectStatus "@baseboard_fab2_lib.baseboard_fab2(sch_1):page26_i172:ddr3_dq(23)" )
			)
			( pin "U5D1.DN76"
				( objectStatus "@baseboard_fab2_lib.baseboard_fab2(sch_1):page26_i172:ddr3_dq(24)" )
			)
			( pin "U5D1.DU76"
				( objectStatus "@baseboard_fab2_lib.baseboard_fab2(sch_1):page26_i172:ddr3_dq(25)" )
			)
			( pin "U5D1.DP73"
				( objectStatus "@baseboard_fab2_lib.baseboard_fab2(sch_1):page26_i172:ddr3_dq(26)" )
			)
			( pin "U5D1.DT73"
				( objectStatus "@baseboard_fab2_lib.baseboard_fab2(sch_1):page26_i172:ddr3_dq(27)" )
			)
			( pin "U5D1.DP77"
				( objectStatus "@baseboard_fab2_lib.baseboard_fab2(sch_1):page26_i172:ddr3_dq(28)" )
			)
			( pin "U5D1.DT77"
				( objectStatus "@baseboard_fab2_lib.baseboard_fab2(sch_1):page26_i172:ddr3_dq(29)" )
			)
			( pin "U5D1.DN74"
				( objectStatus "@baseboard_fab2_lib.baseboard_fab2(sch_1):page26_i172:ddr3_dq(30)" )
			)
			( pin "U5D1.DU74"
				( objectStatus "@baseboard_fab2_lib.baseboard_fab2(sch_1):page26_i172:ddr3_dq(31)" )
			)
			( pin "U5D1.EC40"
				( objectStatus "@baseboard_fab2_lib.baseboard_fab2(sch_1):page26_i172:ddr3_dq(32)" )
			)
			( pin "U5D1.ED39"
				( objectStatus "@baseboard_fab2_lib.baseboard_fab2(sch_1):page26_i172:ddr3_dq(33)" )
			)
			( pin "U5D1.EA36"
				( objectStatus "@baseboard_fab2_lib.baseboard_fab2(sch_1):page26_i172:ddr3_dq(34)" )
			)
			( pin "U5D1.EC36"
				( objectStatus "@baseboard_fab2_lib.baseboard_fab2(sch_1):page26_i172:ddr3_dq(35)" )
			)
			( pin "U5D1.DY39"
				( objectStatus "@baseboard_fab2_lib.baseboard_fab2(sch_1):page26_i172:ddr3_dq(36)" )
			)
			( pin "U5D1.EA40"
				( objectStatus "@baseboard_fab2_lib.baseboard_fab2(sch_1):page26_i172:ddr3_dq(37)" )
			)
			( pin "U5D1.DY37"
				( objectStatus "@baseboard_fab2_lib.baseboard_fab2(sch_1):page26_i172:ddr3_dq(38)" )
			)
			( pin "U5D1.ED37"
				( objectStatus "@baseboard_fab2_lib.baseboard_fab2(sch_1):page26_i172:ddr3_dq(39)" )
			)
			( pin "U5D1.DN36"
				( objectStatus "@baseboard_fab2_lib.baseboard_fab2(sch_1):page26_i172:ddr3_dq(40)" )
			)
			( pin "U5D1.DU36"
				( objectStatus "@baseboard_fab2_lib.baseboard_fab2(sch_1):page26_i172:ddr3_dq(41)" )
			)
			( pin "U5D1.DP33"
				( objectStatus "@baseboard_fab2_lib.baseboard_fab2(sch_1):page26_i172:ddr3_dq(42)" )
			)
			( pin "U5D1.DT33"
				( objectStatus "@baseboard_fab2_lib.baseboard_fab2(sch_1):page26_i172:ddr3_dq(43)" )
			)
			( pin "U5D1.DP37"
				( objectStatus "@baseboard_fab2_lib.baseboard_fab2(sch_1):page26_i172:ddr3_dq(44)" )
			)
			( pin "U5D1.DT37"
				( objectStatus "@baseboard_fab2_lib.baseboard_fab2(sch_1):page26_i172:ddr3_dq(45)" )
			)
			( pin "U5D1.DN34"
				( objectStatus "@baseboard_fab2_lib.baseboard_fab2(sch_1):page26_i172:ddr3_dq(46)" )
			)
			( pin "U5D1.DU34"
				( objectStatus "@baseboard_fab2_lib.baseboard_fab2(sch_1):page26_i172:ddr3_dq(47)" )
			)
			( pin "U5D1.DN30"
				( objectStatus "@baseboard_fab2_lib.baseboard_fab2(sch_1):page26_i172:ddr3_dq(48)" )
			)
			( pin "U5D1.DU30"
				( objectStatus "@baseboard_fab2_lib.baseboard_fab2(sch_1):page26_i172:ddr3_dq(49)" )
			)
			( pin "U5D1.DP27"
				( objectStatus "@baseboard_fab2_lib.baseboard_fab2(sch_1):page26_i172:ddr3_dq(50)" )
			)
			( pin "U5D1.DT27"
				( objectStatus "@baseboard_fab2_lib.baseboard_fab2(sch_1):page26_i172:ddr3_dq(51)" )
			)
			( pin "U5D1.DP31"
				( objectStatus "@baseboard_fab2_lib.baseboard_fab2(sch_1):page26_i172:ddr3_dq(52)" )
			)
			( pin "U5D1.DT31"
				( objectStatus "@baseboard_fab2_lib.baseboard_fab2(sch_1):page26_i172:ddr3_dq(53)" )
			)
			( pin "U5D1.DN28"
				( objectStatus "@baseboard_fab2_lib.baseboard_fab2(sch_1):page26_i172:ddr3_dq(54)" )
			)
			( pin "U5D1.DU28"
				( objectStatus "@baseboard_fab2_lib.baseboard_fab2(sch_1):page26_i172:ddr3_dq(55)" )
			)
			( pin "U5D1.DN24"
				( objectStatus "@baseboard_fab2_lib.baseboard_fab2(sch_1):page26_i172:ddr3_dq(56)" )
			)
			( pin "U5D1.DU24"
				( objectStatus "@baseboard_fab2_lib.baseboard_fab2(sch_1):page26_i172:ddr3_dq(57)" )
			)
			( pin "U5D1.DY21"
				( objectStatus "@baseboard_fab2_lib.baseboard_fab2(sch_1):page26_i172:ddr3_dq(58)" )
			)
			( pin "U5D1.EB21"
				( objectStatus "@baseboard_fab2_lib.baseboard_fab2(sch_1):page26_i172:ddr3_dq(59)" )
			)
			( pin "U5D1.DP25"
				( objectStatus "@baseboard_fab2_lib.baseboard_fab2(sch_1):page26_i172:ddr3_dq(60)" )
			)
			( pin "U5D1.DT25"
				( objectStatus "@baseboard_fab2_lib.baseboard_fab2(sch_1):page26_i172:ddr3_dq(61)" )
			)
			( pin "U5D1.EC22"
				( objectStatus "@baseboard_fab2_lib.baseboard_fab2(sch_1):page26_i172:ddr3_dq(62)" )
			)
			( pin "U5D1.DW22"
				( objectStatus "@baseboard_fab2_lib.baseboard_fab2(sch_1):page26_i172:ddr3_dq(63)" )
			)
			( pin "U5D1.CU84"
				( objectStatus "@baseboard_fab2_lib.baseboard_fab2(sch_1):page26_i172:ddr3_dqs_dn(0)" )
			)
			( pin "U5D1.DN84"
				( objectStatus "@baseboard_fab2_lib.baseboard_fab2(sch_1):page26_i172:ddr3_dqs_dn(1)" )
			)
			( pin "U5D1.DL82"
				( objectStatus "@baseboard_fab2_lib.baseboard_fab2(sch_1):page26_i172:ddr3_dqs_dn(2)" )
			)
			( pin "U5D1.DV75"
				( objectStatus "@baseboard_fab2_lib.baseboard_fab2(sch_1):page26_i172:ddr3_dqs_dn(3)" )
			)
			( pin "U5D1.EE38"
				( objectStatus "@baseboard_fab2_lib.baseboard_fab2(sch_1):page26_i172:ddr3_dqs_dn(4)" )
			)
			( pin "U5D1.DV35"
				( objectStatus "@baseboard_fab2_lib.baseboard_fab2(sch_1):page26_i172:ddr3_dqs_dn(5)" )
			)
			( pin "U5D1.DV29"
				( objectStatus "@baseboard_fab2_lib.baseboard_fab2(sch_1):page26_i172:ddr3_dqs_dn(6)" )
			)
			( pin "U5D1.DV23"
				( objectStatus "@baseboard_fab2_lib.baseboard_fab2(sch_1):page26_i172:ddr3_dqs_dn(7)" )
			)
			( pin "U5D1.DF67"
				( objectStatus "@baseboard_fab2_lib.baseboard_fab2(sch_1):page26_i172:ddr3_dqs_dn(8)" )
			)
			( pin "U5D1.CR84"
				( objectStatus "@baseboard_fab2_lib.baseboard_fab2(sch_1):page26_i172:ddr3_dqs_dn(9)" )
			)
			( pin "U5D1.DM85"
				( objectStatus "@baseboard_fab2_lib.baseboard_fab2(sch_1):page26_i172:ddr3_dqs_dn(10)" )
			)
			( pin "U5D1.DN80"
				( objectStatus "@baseboard_fab2_lib.baseboard_fab2(sch_1):page26_i172:ddr3_dqs_dn(11)" )
			)
			( pin "U5D1.DP75"
				( objectStatus "@baseboard_fab2_lib.baseboard_fab2(sch_1):page26_i172:ddr3_dqs_dn(12)" )
			)
			( pin "U5D1.EA38"
				( objectStatus "@baseboard_fab2_lib.baseboard_fab2(sch_1):page26_i172:ddr3_dqs_dn(13)" )
			)
			( pin "U5D1.DP35"
				( objectStatus "@baseboard_fab2_lib.baseboard_fab2(sch_1):page26_i172:ddr3_dqs_dn(14)" )
			)
			( pin "U5D1.DM29"
				( objectStatus "@baseboard_fab2_lib.baseboard_fab2(sch_1):page26_i172:ddr3_dqs_dn(15)" )
			)
			( pin "U5D1.DM23"
				( objectStatus "@baseboard_fab2_lib.baseboard_fab2(sch_1):page26_i172:ddr3_dqs_dn(16)" )
			)
			( pin "U5D1.DB67"
				( objectStatus "@baseboard_fab2_lib.baseboard_fab2(sch_1):page26_i172:ddr3_dqs_dn(17)" )
			)
			( pin "U5D1.CV85"
				( objectStatus "@baseboard_fab2_lib.baseboard_fab2(sch_1):page26_i172:ddr3_dqs_dp(0)" )
			)
			( pin "U5D1.DP85"
				( objectStatus "@baseboard_fab2_lib.baseboard_fab2(sch_1):page26_i172:ddr3_dqs_dp(1)" )
			)
			( pin "U5D1.DM81"
				( objectStatus "@baseboard_fab2_lib.baseboard_fab2(sch_1):page26_i172:ddr3_dqs_dp(2)" )
			)
			( pin "U5D1.DT75"
				( objectStatus "@baseboard_fab2_lib.baseboard_fab2(sch_1):page26_i172:ddr3_dqs_dp(3)" )
			)
			( pin "U5D1.EC38"
				( objectStatus "@baseboard_fab2_lib.baseboard_fab2(sch_1):page26_i172:ddr3_dqs_dp(4)" )
			)
			( pin "U5D1.DT35"
				( objectStatus "@baseboard_fab2_lib.baseboard_fab2(sch_1):page26_i172:ddr3_dqs_dp(5)" )
			)
			( pin "U5D1.DT29"
				( objectStatus "@baseboard_fab2_lib.baseboard_fab2(sch_1):page26_i172:ddr3_dqs_dp(6)" )
			)
			( pin "U5D1.DT23"
				( objectStatus "@baseboard_fab2_lib.baseboard_fab2(sch_1):page26_i172:ddr3_dqs_dp(7)" )
			)
			( pin "U5D1.DD67"
				( objectStatus "@baseboard_fab2_lib.baseboard_fab2(sch_1):page26_i172:ddr3_dqs_dp(8)" )
			)
			( pin "U5D1.CP85"
				( objectStatus "@baseboard_fab2_lib.baseboard_fab2(sch_1):page26_i172:ddr3_dqs_dp(9)" )
			)
			( pin "U5D1.DL84"
				( objectStatus "@baseboard_fab2_lib.baseboard_fab2(sch_1):page26_i172:ddr3_dqs_dp(10)" )
			)
			( pin "U5D1.DP79"
				( objectStatus "@baseboard_fab2_lib.baseboard_fab2(sch_1):page26_i172:ddr3_dqs_dp(11)" )
			)
			( pin "U5D1.DM75"
				( objectStatus "@baseboard_fab2_lib.baseboard_fab2(sch_1):page26_i172:ddr3_dqs_dp(12)" )
			)
			( pin "U5D1.DW38"
				( objectStatus "@baseboard_fab2_lib.baseboard_fab2(sch_1):page26_i172:ddr3_dqs_dp(13)" )
			)
			( pin "U5D1.DM35"
				( objectStatus "@baseboard_fab2_lib.baseboard_fab2(sch_1):page26_i172:ddr3_dqs_dp(14)" )
			)
			( pin "U5D1.DP29"
				( objectStatus "@baseboard_fab2_lib.baseboard_fab2(sch_1):page26_i172:ddr3_dqs_dp(15)" )
			)
			( pin "U5D1.DP23"
				( objectStatus "@baseboard_fab2_lib.baseboard_fab2(sch_1):page26_i172:ddr3_dqs_dp(16)" )
			)
			( pin "U5D1.CY67"
				( objectStatus "@baseboard_fab2_lib.baseboard_fab2(sch_1):page26_i172:ddr3_dqs_dp(17)" )
			)
			( pin "U5D1.DA68"
				( objectStatus "@baseboard_fab2_lib.baseboard_fab2(sch_1):page26_i172:ddr3_ecc(0)" )
			)
			( pin "U5D1.DE68"
				( objectStatus "@baseboard_fab2_lib.baseboard_fab2(sch_1):page26_i172:ddr3_ecc(1)" )
			)
			( pin "U5D1.DB65"
				( objectStatus "@baseboard_fab2_lib.baseboard_fab2(sch_1):page26_i172:ddr3_ecc(2)" )
			)
			( pin "U5D1.DD65"
				( objectStatus "@baseboard_fab2_lib.baseboard_fab2(sch_1):page26_i172:ddr3_ecc(3)" )
			)
			( pin "U5D1.DB69"
				( objectStatus "@baseboard_fab2_lib.baseboard_fab2(sch_1):page26_i172:ddr3_ecc(4)" )
			)
			( pin "U5D1.DD69"
				( objectStatus "@baseboard_fab2_lib.baseboard_fab2(sch_1):page26_i172:ddr3_ecc(5)" )
			)
			( pin "U5D1.DA66"
				( objectStatus "@baseboard_fab2_lib.baseboard_fab2(sch_1):page26_i172:ddr3_ecc(6)" )
			)
			( pin "U5D1.DE66"
				( objectStatus "@baseboard_fab2_lib.baseboard_fab2(sch_1):page26_i172:ddr3_ecc(7)" )
			)
			( pin "U5D1.EB53"
				( objectStatus "@baseboard_fab2_lib.baseboard_fab2(sch_1):page26_i172:ddr3_ma(0)" )
			)
			( pin "U5D1.ED57"
				( objectStatus "@baseboard_fab2_lib.baseboard_fab2(sch_1):page26_i172:ddr3_ma(1)" )
			)
			( pin "U5D1.EE58"
				( objectStatus "@baseboard_fab2_lib.baseboard_fab2(sch_1):page26_i172:ddr3_ma(2)" )
			)
			( pin "U5D1.EB57"
				( objectStatus "@baseboard_fab2_lib.baseboard_fab2(sch_1):page26_i172:ddr3_ma(3)" )
			)
			( pin "U5D1.ED59"
				( objectStatus "@baseboard_fab2_lib.baseboard_fab2(sch_1):page26_i172:ddr3_ma(4)" )
			)
			( pin "U5D1.EA58"
				( objectStatus "@baseboard_fab2_lib.baseboard_fab2(sch_1):page26_i172:ddr3_ma(5)" )
			)
			( pin "U5D1.EE60"
				( objectStatus "@baseboard_fab2_lib.baseboard_fab2(sch_1):page26_i172:ddr3_ma(6)" )
			)
			( pin "U5D1.EA60"
				( objectStatus "@baseboard_fab2_lib.baseboard_fab2(sch_1):page26_i172:ddr3_ma(7)" )
			)
			( pin "U5D1.EB59"
				( objectStatus "@baseboard_fab2_lib.baseboard_fab2(sch_1):page26_i172:ddr3_ma(8)" )
			)
			( pin "U5D1.EF61"
				( objectStatus "@baseboard_fab2_lib.baseboard_fab2(sch_1):page26_i172:ddr3_ma(9)" )
			)
			( pin "U5D1.DW54"
				( objectStatus "@baseboard_fab2_lib.baseboard_fab2(sch_1):page26_i172:ddr3_ma(10)" )
			)
			( pin "U5D1.EB61"
				( objectStatus "@baseboard_fab2_lib.baseboard_fab2(sch_1):page26_i172:ddr3_ma(11)" )
			)
			( pin "U5D1.DT63"
				( objectStatus "@baseboard_fab2_lib.baseboard_fab2(sch_1):page26_i172:ddr3_ma(12)" )
			)
			( pin "U5D1.DW48"
				( objectStatus "@baseboard_fab2_lib.baseboard_fab2(sch_1):page26_i172:ddr3_ma(13)" )
			)
			( pin "U5D1.ED51"
				( objectStatus "@baseboard_fab2_lib.baseboard_fab2(sch_1):page26_i172:ddr3_ma(14)" )
			)
			( pin "U5D1.DV49"
				( objectStatus "@baseboard_fab2_lib.baseboard_fab2(sch_1):page26_i172:ddr3_ma(15)" )
			)
			( pin "U5D1.EA52"
				( objectStatus "@baseboard_fab2_lib.baseboard_fab2(sch_1):page26_i172:ddr3_ma(16)" )
			)
			( pin "U5D1.EA46"
				( objectStatus "@baseboard_fab2_lib.baseboard_fab2(sch_1):page26_i172:ddr3_ma(17)" )
			)
			( pin "U5D1.EE50"
				( objectStatus "@baseboard_fab2_lib.baseboard_fab2(sch_1):page26_i172:ddr3_odt(0)" )
			)
			( pin "U5D1.EE48"
				( objectStatus "@baseboard_fab2_lib.baseboard_fab2(sch_1):page26_i172:ddr3_odt(1)" )
			)
			( pin "U5D1.EA50"
				( objectStatus "@baseboard_fab2_lib.baseboard_fab2(sch_1):page26_i172:ddr3_odt(2)" )
			)
			( pin "U5D1.EA48"
				( objectStatus "@baseboard_fab2_lib.baseboard_fab2(sch_1):page26_i172:ddr3_odt(3)" )
			)
			( pin "U5D1.ED53"
				( objectStatus "@baseboard_fab2_lib.baseboard_fab2(sch_1):page26_i172:ddr3_par" )
			)
			( pin "U5D1.DR62"
				( objectStatus "@baseboard_fab2_lib.baseboard_fab2(sch_1):page27_i172:ddr4_act_n" )
			)
			( pin "U5D1.DT61"
				( objectStatus "@baseboard_fab2_lib.baseboard_fab2(sch_1):page27_i172:ddr4_alert_n" )
			)
			( pin "U5D1.DM53"
				( objectStatus "@baseboard_fab2_lib.baseboard_fab2(sch_1):page27_i172:ddr4_ba(0)" )
			)
			( pin "U5D1.DV55"
				( objectStatus "@baseboard_fab2_lib.baseboard_fab2(sch_1):page27_i172:ddr4_ba(1)" )
			)
			( pin "U5D1.DJ62"
				( objectStatus "@baseboard_fab2_lib.baseboard_fab2(sch_1):page27_i172:ddr4_bg(0)" )
			)
			( pin "U5D1.DM61"
				( objectStatus "@baseboard_fab2_lib.baseboard_fab2(sch_1):page27_i172:ddr4_bg(1)" )
			)
			( pin "U5D1.DT47"
				( objectStatus "@baseboard_fab2_lib.baseboard_fab2(sch_1):page27_i172:ddr4_cid(2)" )
			)
			( pin "U5D1.DM63"
				( objectStatus "@baseboard_fab2_lib.baseboard_fab2(sch_1):page27_i172:ddr4_cke(0)" )
			)
			( pin "U5D1.DN64"
				( objectStatus "@baseboard_fab2_lib.baseboard_fab2(sch_1):page27_i172:ddr4_cke(1)" )
			)
			( pin "U5D1.DL64"
				( objectStatus "@baseboard_fab2_lib.baseboard_fab2(sch_1):page27_i172:ddr4_cke(2)" )
			)
			( pin "U5D1.DR64"
				( objectStatus "@baseboard_fab2_lib.baseboard_fab2(sch_1):page27_i172:ddr4_cke(3)" )
			)
			( pin "U5D1.DM55"
				( objectStatus "@baseboard_fab2_lib.baseboard_fab2(sch_1):page27_i172:ddr4_clk_dn(0)" )
			)
			( pin "U5D1.DR54"
				( objectStatus "@baseboard_fab2_lib.baseboard_fab2(sch_1):page27_i172:ddr4_clk_dn(1)" )
			)
			( pin "U5D1.DM57"
				( objectStatus "@baseboard_fab2_lib.baseboard_fab2(sch_1):page27_i172:ddr4_clk_dn(2)" )
			)
			( pin "U5D1.DT57"
				( objectStatus "@baseboard_fab2_lib.baseboard_fab2(sch_1):page27_i172:ddr4_clk_dn(3)" )
			)
			( pin "U5D1.DN54"
				( objectStatus "@baseboard_fab2_lib.baseboard_fab2(sch_1):page27_i172:ddr4_clk_dp(0)" )
			)
			( pin "U5D1.DT53"
				( objectStatus "@baseboard_fab2_lib.baseboard_fab2(sch_1):page27_i172:ddr4_clk_dp(1)" )
			)
			( pin "U5D1.DN56"
				( objectStatus "@baseboard_fab2_lib.baseboard_fab2(sch_1):page27_i172:ddr4_clk_dp(2)" )
			)
			( pin "U5D1.DR56"
				( objectStatus "@baseboard_fab2_lib.baseboard_fab2(sch_1):page27_i172:ddr4_clk_dp(3)" )
			)
			( pin "U5D1.DV51"
				( objectStatus "@baseboard_fab2_lib.baseboard_fab2(sch_1):page27_i172:ddr4_cs_n(0)" )
			)
			( pin "U5D1.DN50"
				( objectStatus "@baseboard_fab2_lib.baseboard_fab2(sch_1):page27_i172:ddr4_cs_n(1)" )
			)
			( pin "U5D1.DR46"
				( objectStatus "@baseboard_fab2_lib.baseboard_fab2(sch_1):page27_i172:ddr4_cs_n(2)" )
			)
			( pin "U5D1.DK47"
				( objectStatus "@baseboard_fab2_lib.baseboard_fab2(sch_1):page27_i172:ddr4_cs_n(3)" )
			)
			( pin "U5D1.DW50"
				( objectStatus "@baseboard_fab2_lib.baseboard_fab2(sch_1):page27_i172:ddr4_cs_n(4)" )
			)
			( pin "U5D1.DM49"
				( objectStatus "@baseboard_fab2_lib.baseboard_fab2(sch_1):page27_i172:ddr4_cs_n(5)" )
			)
			( pin "U5D1.DT45"
				( objectStatus "@baseboard_fab2_lib.baseboard_fab2(sch_1):page27_i172:ddr4_cs_n(6)" )
			)
			( pin "U5D1.DN46"
				( objectStatus "@baseboard_fab2_lib.baseboard_fab2(sch_1):page27_i172:ddr4_cs_n(7)" )
			)
			( pin "U5D1.CM79"
				( objectStatus "@baseboard_fab2_lib.baseboard_fab2(sch_1):page27_i172:ddr4_dq(0)" )
			)
			( pin "U5D1.CK81"
				( objectStatus "@baseboard_fab2_lib.baseboard_fab2(sch_1):page27_i172:ddr4_dq(1)" )
			)
			( pin "U5D1.CT81"
				( objectStatus "@baseboard_fab2_lib.baseboard_fab2(sch_1):page27_i172:ddr4_dq(2)" )
			)
			( pin "U5D1.CR82"
				( objectStatus "@baseboard_fab2_lib.baseboard_fab2(sch_1):page27_i172:ddr4_dq(3)" )
			)
			( pin "U5D1.CK79"
				( objectStatus "@baseboard_fab2_lib.baseboard_fab2(sch_1):page27_i172:ddr4_dq(4)" )
			)
			( pin "U5D1.CJ80"
				( objectStatus "@baseboard_fab2_lib.baseboard_fab2(sch_1):page27_i172:ddr4_dq(5)" )
			)
			( pin "U5D1.CR80"
				( objectStatus "@baseboard_fab2_lib.baseboard_fab2(sch_1):page27_i172:ddr4_dq(6)" )
			)
			( pin "U5D1.CN82"
				( objectStatus "@baseboard_fab2_lib.baseboard_fab2(sch_1):page27_i172:ddr4_dq(7)" )
			)
			( pin "U5D1.DB79"
				( objectStatus "@baseboard_fab2_lib.baseboard_fab2(sch_1):page27_i172:ddr4_dq(8)" )
			)
			( pin "U5D1.CY81"
				( objectStatus "@baseboard_fab2_lib.baseboard_fab2(sch_1):page27_i172:ddr4_dq(9)" )
			)
			( pin "U5D1.DE80"
				( objectStatus "@baseboard_fab2_lib.baseboard_fab2(sch_1):page27_i172:ddr4_dq(10)" )
			)
			( pin "U5D1.DF81"
				( objectStatus "@baseboard_fab2_lib.baseboard_fab2(sch_1):page27_i172:ddr4_dq(11)" )
			)
			( pin "U5D1.CY79"
				( objectStatus "@baseboard_fab2_lib.baseboard_fab2(sch_1):page27_i172:ddr4_dq(12)" )
			)
			( pin "U5D1.CW80"
				( objectStatus "@baseboard_fab2_lib.baseboard_fab2(sch_1):page27_i172:ddr4_dq(13)" )
			)
			( pin "U5D1.DC82"
				( objectStatus "@baseboard_fab2_lib.baseboard_fab2(sch_1):page27_i172:ddr4_dq(14)" )
			)
			( pin "U5D1.DE82"
				( objectStatus "@baseboard_fab2_lib.baseboard_fab2(sch_1):page27_i172:ddr4_dq(15)" )
			)
			( pin "U5D1.DW80"
				( objectStatus "@baseboard_fab2_lib.baseboard_fab2(sch_1):page27_i172:ddr4_dq(16)" )
			)
			( pin "U5D1.EC80"
				( objectStatus "@baseboard_fab2_lib.baseboard_fab2(sch_1):page27_i172:ddr4_dq(17)" )
			)
			( pin "U5D1.DY77"
				( objectStatus "@baseboard_fab2_lib.baseboard_fab2(sch_1):page27_i172:ddr4_dq(18)" )
			)
			( pin "U5D1.EB77"
				( objectStatus "@baseboard_fab2_lib.baseboard_fab2(sch_1):page27_i172:ddr4_dq(19)" )
			)
			( pin "U5D1.DY81"
				( objectStatus "@baseboard_fab2_lib.baseboard_fab2(sch_1):page27_i172:ddr4_dq(20)" )
			)
			( pin "U5D1.EB81"
				( objectStatus "@baseboard_fab2_lib.baseboard_fab2(sch_1):page27_i172:ddr4_dq(21)" )
			)
			( pin "U5D1.DW78"
				( objectStatus "@baseboard_fab2_lib.baseboard_fab2(sch_1):page27_i172:ddr4_dq(22)" )
			)
			( pin "U5D1.EC78"
				( objectStatus "@baseboard_fab2_lib.baseboard_fab2(sch_1):page27_i172:ddr4_dq(23)" )
			)
			( pin "U5D1.ED75"
				( objectStatus "@baseboard_fab2_lib.baseboard_fab2(sch_1):page27_i172:ddr4_dq(24)" )
			)
			( pin "U5D1.EE74"
				( objectStatus "@baseboard_fab2_lib.baseboard_fab2(sch_1):page27_i172:ddr4_dq(25)" )
			)
			( pin "U5D1.EB71"
				( objectStatus "@baseboard_fab2_lib.baseboard_fab2(sch_1):page27_i172:ddr4_dq(26)" )
			)
			( pin "U5D1.ED71"
				( objectStatus "@baseboard_fab2_lib.baseboard_fab2(sch_1):page27_i172:ddr4_dq(27)" )
			)
			( pin "U5D1.EA74"
				( objectStatus "@baseboard_fab2_lib.baseboard_fab2(sch_1):page27_i172:ddr4_dq(28)" )
			)
			( pin "U5D1.EB75"
				( objectStatus "@baseboard_fab2_lib.baseboard_fab2(sch_1):page27_i172:ddr4_dq(29)" )
			)
			( pin "U5D1.EA72"
				( objectStatus "@baseboard_fab2_lib.baseboard_fab2(sch_1):page27_i172:ddr4_dq(30)" )
			)
			( pin "U5D1.EE72"
				( objectStatus "@baseboard_fab2_lib.baseboard_fab2(sch_1):page27_i172:ddr4_dq(31)" )
			)
			( pin "U5D1.DU42"
				( objectStatus "@baseboard_fab2_lib.baseboard_fab2(sch_1):page27_i172:ddr4_dq(32)" )
			)
			( pin "U5D1.DW42"
				( objectStatus "@baseboard_fab2_lib.baseboard_fab2(sch_1):page27_i172:ddr4_dq(33)" )
			)
			( pin "U5D1.DP39"
				( objectStatus "@baseboard_fab2_lib.baseboard_fab2(sch_1):page27_i172:ddr4_dq(34)" )
			)
			( pin "U5D1.DT39"
				( objectStatus "@baseboard_fab2_lib.baseboard_fab2(sch_1):page27_i172:ddr4_dq(35)" )
			)
			( pin "U5D1.DL42"
				( objectStatus "@baseboard_fab2_lib.baseboard_fab2(sch_1):page27_i172:ddr4_dq(36)" )
			)
			( pin "U5D1.DN42"
				( objectStatus "@baseboard_fab2_lib.baseboard_fab2(sch_1):page27_i172:ddr4_dq(37)" )
			)
			( pin "U5D1.DN40"
				( objectStatus "@baseboard_fab2_lib.baseboard_fab2(sch_1):page27_i172:ddr4_dq(38)" )
			)
			( pin "U5D1.DU40"
				( objectStatus "@baseboard_fab2_lib.baseboard_fab2(sch_1):page27_i172:ddr4_dq(39)" )
			)
			( pin "U5D1.EC34"
				( objectStatus "@baseboard_fab2_lib.baseboard_fab2(sch_1):page27_i172:ddr4_dq(40)" )
			)
			( pin "U5D1.ED33"
				( objectStatus "@baseboard_fab2_lib.baseboard_fab2(sch_1):page27_i172:ddr4_dq(41)" )
			)
			( pin "U5D1.EA30"
				( objectStatus "@baseboard_fab2_lib.baseboard_fab2(sch_1):page27_i172:ddr4_dq(42)" )
			)
			( pin "U5D1.EC30"
				( objectStatus "@baseboard_fab2_lib.baseboard_fab2(sch_1):page27_i172:ddr4_dq(43)" )
			)
			( pin "U5D1.DY33"
				( objectStatus "@baseboard_fab2_lib.baseboard_fab2(sch_1):page27_i172:ddr4_dq(44)" )
			)
			( pin "U5D1.EA34"
				( objectStatus "@baseboard_fab2_lib.baseboard_fab2(sch_1):page27_i172:ddr4_dq(45)" )
			)
			( pin "U5D1.DY31"
				( objectStatus "@baseboard_fab2_lib.baseboard_fab2(sch_1):page27_i172:ddr4_dq(46)" )
			)
			( pin "U5D1.ED31"
				( objectStatus "@baseboard_fab2_lib.baseboard_fab2(sch_1):page27_i172:ddr4_dq(47)" )
			)
			( pin "U5D1.EC28"
				( objectStatus "@baseboard_fab2_lib.baseboard_fab2(sch_1):page27_i172:ddr4_dq(48)" )
			)
			( pin "U5D1.ED27"
				( objectStatus "@baseboard_fab2_lib.baseboard_fab2(sch_1):page27_i172:ddr4_dq(49)" )
			)
			( pin "U5D1.EA24"
				( objectStatus "@baseboard_fab2_lib.baseboard_fab2(sch_1):page27_i172:ddr4_dq(50)" )
			)
			( pin "U5D1.EC24"
				( objectStatus "@baseboard_fab2_lib.baseboard_fab2(sch_1):page27_i172:ddr4_dq(51)" )
			)
			( pin "U5D1.DY27"
				( objectStatus "@baseboard_fab2_lib.baseboard_fab2(sch_1):page27_i172:ddr4_dq(52)" )
			)
			( pin "U5D1.EA28"
				( objectStatus "@baseboard_fab2_lib.baseboard_fab2(sch_1):page27_i172:ddr4_dq(53)" )
			)
			( pin "U5D1.DY25"
				( objectStatus "@baseboard_fab2_lib.baseboard_fab2(sch_1):page27_i172:ddr4_dq(54)" )
			)
			( pin "U5D1.ED25"
				( objectStatus "@baseboard_fab2_lib.baseboard_fab2(sch_1):page27_i172:ddr4_dq(55)" )
			)
			( pin "U5D1.DF27"
				( objectStatus "@baseboard_fab2_lib.baseboard_fab2(sch_1):page27_i172:ddr4_dq(56)" )
			)
			( pin "U5D1.DK27"
				( objectStatus "@baseboard_fab2_lib.baseboard_fab2(sch_1):page27_i172:ddr4_dq(57)" )
			)
			( pin "U5D1.DD25"
				( objectStatus "@baseboard_fab2_lib.baseboard_fab2(sch_1):page27_i172:ddr4_dq(58)" )
			)
			( pin "U5D1.DJ24"
				( objectStatus "@baseboard_fab2_lib.baseboard_fab2(sch_1):page27_i172:ddr4_dq(59)" )
			)
			( pin "U5D1.DG28"
				( objectStatus "@baseboard_fab2_lib.baseboard_fab2(sch_1):page27_i172:ddr4_dq(60)" )
			)
			( pin "U5D1.DJ28"
				( objectStatus "@baseboard_fab2_lib.baseboard_fab2(sch_1):page27_i172:ddr4_dq(61)" )
			)
			( pin "U5D1.DF25"
				( objectStatus "@baseboard_fab2_lib.baseboard_fab2(sch_1):page27_i172:ddr4_dq(62)" )
			)
			( pin "U5D1.DK25"
				( objectStatus "@baseboard_fab2_lib.baseboard_fab2(sch_1):page27_i172:ddr4_dq(63)" )
			)
			( pin "U5D1.CL82"
				( objectStatus "@baseboard_fab2_lib.baseboard_fab2(sch_1):page27_i172:ddr4_dqs_dn(0)" )
			)
			( pin "U5D1.DA82"
				( objectStatus "@baseboard_fab2_lib.baseboard_fab2(sch_1):page27_i172:ddr4_dqs_dn(1)" )
			)
			( pin "U5D1.ED79"
				( objectStatus "@baseboard_fab2_lib.baseboard_fab2(sch_1):page27_i172:ddr4_dqs_dn(2)" )
			)
			( pin "U5D1.EF73"
				( objectStatus "@baseboard_fab2_lib.baseboard_fab2(sch_1):page27_i172:ddr4_dqs_dn(3)" )
			)
			( pin "U5D1.DV41"
				( objectStatus "@baseboard_fab2_lib.baseboard_fab2(sch_1):page27_i172:ddr4_dqs_dn(4)" )
			)
			( pin "U5D1.EE32"
				( objectStatus "@baseboard_fab2_lib.baseboard_fab2(sch_1):page27_i172:ddr4_dqs_dn(5)" )
			)
			( pin "U5D1.EE26"
				( objectStatus "@baseboard_fab2_lib.baseboard_fab2(sch_1):page27_i172:ddr4_dqs_dn(6)" )
			)
			( pin "U5D1.DL26"
				( objectStatus "@baseboard_fab2_lib.baseboard_fab2(sch_1):page27_i172:ddr4_dqs_dn(7)" )
			)
			( pin "U5D1.EB67"
				( objectStatus "@baseboard_fab2_lib.baseboard_fab2(sch_1):page27_i172:ddr4_dqs_dn(8)" )
			)
			( pin "U5D1.CN80"
				( objectStatus "@baseboard_fab2_lib.baseboard_fab2(sch_1):page27_i172:ddr4_dqs_dn(9)" )
			)
			( pin "U5D1.DC80"
				( objectStatus "@baseboard_fab2_lib.baseboard_fab2(sch_1):page27_i172:ddr4_dqs_dn(10)" )
			)
			( pin "U5D1.DY79"
				( objectStatus "@baseboard_fab2_lib.baseboard_fab2(sch_1):page27_i172:ddr4_dqs_dn(11)" )
			)
			( pin "U5D1.EB73"
				( objectStatus "@baseboard_fab2_lib.baseboard_fab2(sch_1):page27_i172:ddr4_dqs_dn(12)" )
			)
			( pin "U5D1.DP41"
				( objectStatus "@baseboard_fab2_lib.baseboard_fab2(sch_1):page27_i172:ddr4_dqs_dn(13)" )
			)
			( pin "U5D1.EA32"
				( objectStatus "@baseboard_fab2_lib.baseboard_fab2(sch_1):page27_i172:ddr4_dqs_dn(14)" )
			)
			( pin "U5D1.EA26"
				( objectStatus "@baseboard_fab2_lib.baseboard_fab2(sch_1):page27_i172:ddr4_dqs_dn(15)" )
			)
			( pin "U5D1.DG26"
				( objectStatus "@baseboard_fab2_lib.baseboard_fab2(sch_1):page27_i172:ddr4_dqs_dn(16)" )
			)
			( pin "U5D1.DV67"
				( objectStatus "@baseboard_fab2_lib.baseboard_fab2(sch_1):page27_i172:ddr4_dqs_dn(17)" )
			)
			( pin "U5D1.CM81"
				( objectStatus "@baseboard_fab2_lib.baseboard_fab2(sch_1):page27_i172:ddr4_dqs_dp(0)" )
			)
			( pin "U5D1.DB81"
				( objectStatus "@baseboard_fab2_lib.baseboard_fab2(sch_1):page27_i172:ddr4_dqs_dp(1)" )
			)
			( pin "U5D1.EB79"
				( objectStatus "@baseboard_fab2_lib.baseboard_fab2(sch_1):page27_i172:ddr4_dqs_dp(2)" )
			)
			( pin "U5D1.ED73"
				( objectStatus "@baseboard_fab2_lib.baseboard_fab2(sch_1):page27_i172:ddr4_dqs_dp(3)" )
			)
			( pin "U5D1.DT41"
				( objectStatus "@baseboard_fab2_lib.baseboard_fab2(sch_1):page27_i172:ddr4_dqs_dp(4)" )
			)
			( pin "U5D1.EC32"
				( objectStatus "@baseboard_fab2_lib.baseboard_fab2(sch_1):page27_i172:ddr4_dqs_dp(5)" )
			)
			( pin "U5D1.EC26"
				( objectStatus "@baseboard_fab2_lib.baseboard_fab2(sch_1):page27_i172:ddr4_dqs_dp(6)" )
			)
			( pin "U5D1.DJ26"
				( objectStatus "@baseboard_fab2_lib.baseboard_fab2(sch_1):page27_i172:ddr4_dqs_dp(7)" )
			)
			( pin "U5D1.DY67"
				( objectStatus "@baseboard_fab2_lib.baseboard_fab2(sch_1):page27_i172:ddr4_dqs_dp(8)" )
			)
			( pin "U5D1.CP79"
				( objectStatus "@baseboard_fab2_lib.baseboard_fab2(sch_1):page27_i172:ddr4_dqs_dp(9)" )
			)
			( pin "U5D1.DD79"
				( objectStatus "@baseboard_fab2_lib.baseboard_fab2(sch_1):page27_i172:ddr4_dqs_dp(10)" )
			)
			( pin "U5D1.DV79"
				( objectStatus "@baseboard_fab2_lib.baseboard_fab2(sch_1):page27_i172:ddr4_dqs_dp(11)" )
			)
			( pin "U5D1.DY73"
				( objectStatus "@baseboard_fab2_lib.baseboard_fab2(sch_1):page27_i172:ddr4_dqs_dp(12)" )
			)
			( pin "U5D1.DM41"
				( objectStatus "@baseboard_fab2_lib.baseboard_fab2(sch_1):page27_i172:ddr4_dqs_dp(13)" )
			)
			( pin "U5D1.DW32"
				( objectStatus "@baseboard_fab2_lib.baseboard_fab2(sch_1):page27_i172:ddr4_dqs_dp(14)" )
			)
			( pin "U5D1.DW26"
				( objectStatus "@baseboard_fab2_lib.baseboard_fab2(sch_1):page27_i172:ddr4_dqs_dp(15)" )
			)
			( pin "U5D1.DE26"
				( objectStatus "@baseboard_fab2_lib.baseboard_fab2(sch_1):page27_i172:ddr4_dqs_dp(16)" )
			)
			( pin "U5D1.DT67"
				( objectStatus "@baseboard_fab2_lib.baseboard_fab2(sch_1):page27_i172:ddr4_dqs_dp(17)" )
			)
			( pin "U5D1.DY69"
				( objectStatus "@baseboard_fab2_lib.baseboard_fab2(sch_1):page27_i172:ddr4_ecc(0)" )
			)
			( pin "U5D1.EA68"
				( objectStatus "@baseboard_fab2_lib.baseboard_fab2(sch_1):page27_i172:ddr4_ecc(1)" )
			)
			( pin "U5D1.DV65"
				( objectStatus "@baseboard_fab2_lib.baseboard_fab2(sch_1):page27_i172:ddr4_ecc(2)" )
			)
			( pin "U5D1.DY65"
				( objectStatus "@baseboard_fab2_lib.baseboard_fab2(sch_1):page27_i172:ddr4_ecc(3)" )
			)
			( pin "U5D1.DU68"
				( objectStatus "@baseboard_fab2_lib.baseboard_fab2(sch_1):page27_i172:ddr4_ecc(4)" )
			)
			( pin "U5D1.DV69"
				( objectStatus "@baseboard_fab2_lib.baseboard_fab2(sch_1):page27_i172:ddr4_ecc(5)" )
			)
			( pin "U5D1.DU66"
				( objectStatus "@baseboard_fab2_lib.baseboard_fab2(sch_1):page27_i172:ddr4_ecc(6)" )
			)
			( pin "U5D1.EA66"
				( objectStatus "@baseboard_fab2_lib.baseboard_fab2(sch_1):page27_i172:ddr4_ecc(7)" )
			)
			( pin "U5D1.DW52"
				( objectStatus "@baseboard_fab2_lib.baseboard_fab2(sch_1):page27_i172:ddr4_ma(0)" )
			)
			( pin "U5D1.DW58"
				( objectStatus "@baseboard_fab2_lib.baseboard_fab2(sch_1):page27_i172:ddr4_ma(1)" )
			)
			( pin "U5D1.DV57"
				( objectStatus "@baseboard_fab2_lib.baseboard_fab2(sch_1):page27_i172:ddr4_ma(2)" )
			)
			( pin "U5D1.DR58"
				( objectStatus "@baseboard_fab2_lib.baseboard_fab2(sch_1):page27_i172:ddr4_ma(3)" )
			)
			( pin "U5D1.DT59"
				( objectStatus "@baseboard_fab2_lib.baseboard_fab2(sch_1):page27_i172:ddr4_ma(4)" )
			)
			( pin "U5D1.DN58"
				( objectStatus "@baseboard_fab2_lib.baseboard_fab2(sch_1):page27_i172:ddr4_ma(5)" )
			)
			( pin "U5D1.DM59"
				( objectStatus "@baseboard_fab2_lib.baseboard_fab2(sch_1):page27_i172:ddr4_ma(6)" )
			)
			( pin "U5D1.DK61"
				( objectStatus "@baseboard_fab2_lib.baseboard_fab2(sch_1):page27_i172:ddr4_ma(7)" )
			)
			( pin "U5D1.DJ60"
				( objectStatus "@baseboard_fab2_lib.baseboard_fab2(sch_1):page27_i172:ddr4_ma(8)" )
			)
			( pin "U5D1.DV59"
				( objectStatus "@baseboard_fab2_lib.baseboard_fab2(sch_1):page27_i172:ddr4_ma(9)" )
			)
			( pin "U5D1.DT55"
				( objectStatus "@baseboard_fab2_lib.baseboard_fab2(sch_1):page27_i172:ddr4_ma(10)" )
			)
			( pin "U5D1.DR60"
				( objectStatus "@baseboard_fab2_lib.baseboard_fab2(sch_1):page27_i172:ddr4_ma(11)" )
			)
			( pin "U5D1.DN60"
				( objectStatus "@baseboard_fab2_lib.baseboard_fab2(sch_1):page27_i172:ddr4_ma(12)" )
			)
			( pin "U5D1.DT51"
				( objectStatus "@baseboard_fab2_lib.baseboard_fab2(sch_1):page27_i172:ddr4_ma(13)" )
			)
			( pin "U5D1.DM51"
				( objectStatus "@baseboard_fab2_lib.baseboard_fab2(sch_1):page27_i172:ddr4_ma(14)" )
			)
			( pin "U5D1.DR52"
				( objectStatus "@baseboard_fab2_lib.baseboard_fab2(sch_1):page27_i172:ddr4_ma(15)" )
			)
			( pin "U5D1.DN52"
				( objectStatus "@baseboard_fab2_lib.baseboard_fab2(sch_1):page27_i172:ddr4_ma(16)" )
			)
			( pin "U5D1.DR48"
				( objectStatus "@baseboard_fab2_lib.baseboard_fab2(sch_1):page27_i172:ddr4_ma(17)" )
			)
			( pin "U5D1.DR50"
				( objectStatus "@baseboard_fab2_lib.baseboard_fab2(sch_1):page27_i172:ddr4_odt(0)" )
			)
			( pin "U5D1.DN48"
				( objectStatus "@baseboard_fab2_lib.baseboard_fab2(sch_1):page27_i172:ddr4_odt(1)" )
			)
			( pin "U5D1.DT49"
				( objectStatus "@baseboard_fab2_lib.baseboard_fab2(sch_1):page27_i172:ddr4_odt(2)" )
			)
			( pin "U5D1.DM47"
				( objectStatus "@baseboard_fab2_lib.baseboard_fab2(sch_1):page27_i172:ddr4_odt(3)" )
			)
			( pin "U5D1.DV53"
				( objectStatus "@baseboard_fab2_lib.baseboard_fab2(sch_1):page27_i172:ddr4_par" )
			)
			( pin "U5D1.DC62"
				( objectStatus "@baseboard_fab2_lib.baseboard_fab2(sch_1):page28_i172:ddr5_act_n" )
			)
			( pin "U5D1.DD61"
				( objectStatus "@baseboard_fab2_lib.baseboard_fab2(sch_1):page28_i172:ddr5_alert_n" )
			)
			( pin "U5D1.DJ52"
				( objectStatus "@baseboard_fab2_lib.baseboard_fab2(sch_1):page28_i172:ddr5_ba(0)" )
			)
			( pin "U5D1.DC56"
				( objectStatus "@baseboard_fab2_lib.baseboard_fab2(sch_1):page28_i172:ddr5_ba(1)" )
			)
			( pin "U5D1.DA62"
				( objectStatus "@baseboard_fab2_lib.baseboard_fab2(sch_1):page28_i172:ddr5_bg(0)" )
			)
			( pin "U5D1.DF61"
				( objectStatus "@baseboard_fab2_lib.baseboard_fab2(sch_1):page28_i172:ddr5_bg(1)" )
			)
			( pin "U5D1.DF45"
				( objectStatus "@baseboard_fab2_lib.baseboard_fab2(sch_1):page28_i172:ddr5_cid(2)" )
			)
			( pin "U5D1.DG62"
				( objectStatus "@baseboard_fab2_lib.baseboard_fab2(sch_1):page28_i172:ddr5_cke(0)" )
			)
			( pin "U5D1.DD63"
				( objectStatus "@baseboard_fab2_lib.baseboard_fab2(sch_1):page28_i172:ddr5_cke(1)" )
			)
			( pin "U5D1.DK63"
				( objectStatus "@baseboard_fab2_lib.baseboard_fab2(sch_1):page28_i172:ddr5_cke(2)" )
			)
			( pin "U5D1.DF63"
				( objectStatus "@baseboard_fab2_lib.baseboard_fab2(sch_1):page28_i172:ddr5_cke(3)" )
			)
			( pin "U5D1.DK55"
				( objectStatus "@baseboard_fab2_lib.baseboard_fab2(sch_1):page28_i172:ddr5_clk_dn(0)" )
			)
			( pin "U5D1.DF55"
				( objectStatus "@baseboard_fab2_lib.baseboard_fab2(sch_1):page28_i172:ddr5_clk_dn(1)" )
			)
			( pin "U5D1.DK57"
				( objectStatus "@baseboard_fab2_lib.baseboard_fab2(sch_1):page28_i172:ddr5_clk_dn(2)" )
			)
			( pin "U5D1.DF57"
				( objectStatus "@baseboard_fab2_lib.baseboard_fab2(sch_1):page28_i172:ddr5_clk_dn(3)" )
			)
			( pin "U5D1.DJ54"
				( objectStatus "@baseboard_fab2_lib.baseboard_fab2(sch_1):page28_i172:ddr5_clk_dp(0)" )
			)
			( pin "U5D1.DG54"
				( objectStatus "@baseboard_fab2_lib.baseboard_fab2(sch_1):page28_i172:ddr5_clk_dp(1)" )
			)
			( pin "U5D1.DJ56"
				( objectStatus "@baseboard_fab2_lib.baseboard_fab2(sch_1):page28_i172:ddr5_clk_dp(2)" )
			)
			( pin "U5D1.DG56"
				( objectStatus "@baseboard_fab2_lib.baseboard_fab2(sch_1):page28_i172:ddr5_clk_dp(3)" )
			)
			( pin "U5D1.DK51"
				( objectStatus "@baseboard_fab2_lib.baseboard_fab2(sch_1):page28_i172:ddr5_cs_n(0)" )
			)
			( pin "U5D1.DF49"
				( objectStatus "@baseboard_fab2_lib.baseboard_fab2(sch_1):page28_i172:ddr5_cs_n(1)" )
			)
			( pin "U5D1.DJ46"
				( objectStatus "@baseboard_fab2_lib.baseboard_fab2(sch_1):page28_i172:ddr5_cs_n(2)" )
			)
			( pin "U5D1.DG46"
				( objectStatus "@baseboard_fab2_lib.baseboard_fab2(sch_1):page28_i172:ddr5_cs_n(3)" )
			)
			( pin "U5D1.DF51"
				( objectStatus "@baseboard_fab2_lib.baseboard_fab2(sch_1):page28_i172:ddr5_cs_n(4)" )
			)
			( pin "U5D1.DJ48"
				( objectStatus "@baseboard_fab2_lib.baseboard_fab2(sch_1):page28_i172:ddr5_cs_n(5)" )
			)
			( pin "U5D1.DM45"
				( objectStatus "@baseboard_fab2_lib.baseboard_fab2(sch_1):page28_i172:ddr5_cs_n(6)" )
			)
			( pin "U5D1.DK45"
				( objectStatus "@baseboard_fab2_lib.baseboard_fab2(sch_1):page28_i172:ddr5_cs_n(7)" )
			)
			( pin "U5D1.CR74"
				( objectStatus "@baseboard_fab2_lib.baseboard_fab2(sch_1):page28_i172:ddr5_dq(0)" )
			)
			( pin "U5D1.CN76"
				( objectStatus "@baseboard_fab2_lib.baseboard_fab2(sch_1):page28_i172:ddr5_dq(1)" )
			)
			( pin "U5D1.CW76"
				( objectStatus "@baseboard_fab2_lib.baseboard_fab2(sch_1):page28_i172:ddr5_dq(2)" )
			)
			( pin "U5D1.CV77"
				( objectStatus "@baseboard_fab2_lib.baseboard_fab2(sch_1):page28_i172:ddr5_dq(3)" )
			)
			( pin "U5D1.CN74"
				( objectStatus "@baseboard_fab2_lib.baseboard_fab2(sch_1):page28_i172:ddr5_dq(4)" )
			)
			( pin "U5D1.CM75"
				( objectStatus "@baseboard_fab2_lib.baseboard_fab2(sch_1):page28_i172:ddr5_dq(5)" )
			)
			( pin "U5D1.CV75"
				( objectStatus "@baseboard_fab2_lib.baseboard_fab2(sch_1):page28_i172:ddr5_dq(6)" )
			)
			( pin "U5D1.CT77"
				( objectStatus "@baseboard_fab2_lib.baseboard_fab2(sch_1):page28_i172:ddr5_dq(7)" )
			)
			( pin "U5D1.DE74"
				( objectStatus "@baseboard_fab2_lib.baseboard_fab2(sch_1):page28_i172:ddr5_dq(8)" )
			)
			( pin "U5D1.DC76"
				( objectStatus "@baseboard_fab2_lib.baseboard_fab2(sch_1):page28_i172:ddr5_dq(9)" )
			)
			( pin "U5D1.DH75"
				( objectStatus "@baseboard_fab2_lib.baseboard_fab2(sch_1):page28_i172:ddr5_dq(10)" )
			)
			( pin "U5D1.DJ76"
				( objectStatus "@baseboard_fab2_lib.baseboard_fab2(sch_1):page28_i172:ddr5_dq(11)" )
			)
			( pin "U5D1.DC74"
				( objectStatus "@baseboard_fab2_lib.baseboard_fab2(sch_1):page28_i172:ddr5_dq(12)" )
			)
			( pin "U5D1.DB75"
				( objectStatus "@baseboard_fab2_lib.baseboard_fab2(sch_1):page28_i172:ddr5_dq(13)" )
			)
			( pin "U5D1.DF77"
				( objectStatus "@baseboard_fab2_lib.baseboard_fab2(sch_1):page28_i172:ddr5_dq(14)" )
			)
			( pin "U5D1.DH77"
				( objectStatus "@baseboard_fab2_lib.baseboard_fab2(sch_1):page28_i172:ddr5_dq(15)" )
			)
			( pin "U5D1.DG70"
				( objectStatus "@baseboard_fab2_lib.baseboard_fab2(sch_1):page28_i172:ddr5_dq(16)" )
			)
			( pin "U5D1.DJ72"
				( objectStatus "@baseboard_fab2_lib.baseboard_fab2(sch_1):page28_i172:ddr5_dq(17)" )
			)
			( pin "U5D1.DM69"
				( objectStatus "@baseboard_fab2_lib.baseboard_fab2(sch_1):page28_i172:ddr5_dq(18)" )
			)
			( pin "U5D1.DN70"
				( objectStatus "@baseboard_fab2_lib.baseboard_fab2(sch_1):page28_i172:ddr5_dq(19)" )
			)
			( pin "U5D1.DF71"
				( objectStatus "@baseboard_fab2_lib.baseboard_fab2(sch_1):page28_i172:ddr5_dq(20)" )
			)
			( pin "U5D1.DG72"
				( objectStatus "@baseboard_fab2_lib.baseboard_fab2(sch_1):page28_i172:ddr5_dq(21)" )
			)
			( pin "U5D1.DK69"
				( objectStatus "@baseboard_fab2_lib.baseboard_fab2(sch_1):page28_i172:ddr5_dq(22)" )
			)
			( pin "U5D1.DM71"
				( objectStatus "@baseboard_fab2_lib.baseboard_fab2(sch_1):page28_i172:ddr5_dq(23)" )
			)
			( pin "U5D1.CN66"
				( objectStatus "@baseboard_fab2_lib.baseboard_fab2(sch_1):page28_i172:ddr5_dq(24)" )
			)
			( pin "U5D1.CU66"
				( objectStatus "@baseboard_fab2_lib.baseboard_fab2(sch_1):page28_i172:ddr5_dq(25)" )
			)
			( pin "U5D1.CP63"
				( objectStatus "@baseboard_fab2_lib.baseboard_fab2(sch_1):page28_i172:ddr5_dq(26)" )
			)
			( pin "U5D1.CT63"
				( objectStatus "@baseboard_fab2_lib.baseboard_fab2(sch_1):page28_i172:ddr5_dq(27)" )
			)
			( pin "U5D1.CP67"
				( objectStatus "@baseboard_fab2_lib.baseboard_fab2(sch_1):page28_i172:ddr5_dq(28)" )
			)
			( pin "U5D1.CT67"
				( objectStatus "@baseboard_fab2_lib.baseboard_fab2(sch_1):page28_i172:ddr5_dq(29)" )
			)
			( pin "U5D1.CN64"
				( objectStatus "@baseboard_fab2_lib.baseboard_fab2(sch_1):page28_i172:ddr5_dq(30)" )
			)
			( pin "U5D1.CU64"
				( objectStatus "@baseboard_fab2_lib.baseboard_fab2(sch_1):page28_i172:ddr5_dq(31)" )
			)
			( pin "U5D1.DD41"
				( objectStatus "@baseboard_fab2_lib.baseboard_fab2(sch_1):page28_i172:ddr5_dq(32)" )
			)
			( pin "U5D1.DG42"
				( objectStatus "@baseboard_fab2_lib.baseboard_fab2(sch_1):page28_i172:ddr5_dq(33)" )
			)
			( pin "U5D1.DE38"
				( objectStatus "@baseboard_fab2_lib.baseboard_fab2(sch_1):page28_i172:ddr5_dq(34)" )
			)
			( pin "U5D1.DG38"
				( objectStatus "@baseboard_fab2_lib.baseboard_fab2(sch_1):page28_i172:ddr5_dq(35)" )
			)
			( pin "U5D1.DA42"
				( objectStatus "@baseboard_fab2_lib.baseboard_fab2(sch_1):page28_i172:ddr5_dq(36)" )
			)
			( pin "U5D1.DE42"
				( objectStatus "@baseboard_fab2_lib.baseboard_fab2(sch_1):page28_i172:ddr5_dq(37)" )
			)
			( pin "U5D1.DD39"
				( objectStatus "@baseboard_fab2_lib.baseboard_fab2(sch_1):page28_i172:ddr5_dq(38)" )
			)
			( pin "U5D1.DH39"
				( objectStatus "@baseboard_fab2_lib.baseboard_fab2(sch_1):page28_i172:ddr5_dq(39)" )
			)
			( pin "U5D1.DF33"
				( objectStatus "@baseboard_fab2_lib.baseboard_fab2(sch_1):page28_i172:ddr5_dq(40)" )
			)
			( pin "U5D1.DK33"
				( objectStatus "@baseboard_fab2_lib.baseboard_fab2(sch_1):page28_i172:ddr5_dq(41)" )
			)
			( pin "U5D1.DG30"
				( objectStatus "@baseboard_fab2_lib.baseboard_fab2(sch_1):page28_i172:ddr5_dq(42)" )
			)
			( pin "U5D1.DJ30"
				( objectStatus "@baseboard_fab2_lib.baseboard_fab2(sch_1):page28_i172:ddr5_dq(43)" )
			)
			( pin "U5D1.DG34"
				( objectStatus "@baseboard_fab2_lib.baseboard_fab2(sch_1):page28_i172:ddr5_dq(44)" )
			)
			( pin "U5D1.DJ34"
				( objectStatus "@baseboard_fab2_lib.baseboard_fab2(sch_1):page28_i172:ddr5_dq(45)" )
			)
			( pin "U5D1.DF31"
				( objectStatus "@baseboard_fab2_lib.baseboard_fab2(sch_1):page28_i172:ddr5_dq(46)" )
			)
			( pin "U5D1.DK31"
				( objectStatus "@baseboard_fab2_lib.baseboard_fab2(sch_1):page28_i172:ddr5_dq(47)" )
			)
			( pin "U5D1.CW36"
				( objectStatus "@baseboard_fab2_lib.baseboard_fab2(sch_1):page28_i172:ddr5_dq(48)" )
			)
			( pin "U5D1.DC36"
				( objectStatus "@baseboard_fab2_lib.baseboard_fab2(sch_1):page28_i172:ddr5_dq(49)" )
			)
			( pin "U5D1.CY33"
				( objectStatus "@baseboard_fab2_lib.baseboard_fab2(sch_1):page28_i172:ddr5_dq(50)" )
			)
			( pin "U5D1.DB33"
				( objectStatus "@baseboard_fab2_lib.baseboard_fab2(sch_1):page28_i172:ddr5_dq(51)" )
			)
			( pin "U5D1.CY37"
				( objectStatus "@baseboard_fab2_lib.baseboard_fab2(sch_1):page28_i172:ddr5_dq(52)" )
			)
			( pin "U5D1.DB37"
				( objectStatus "@baseboard_fab2_lib.baseboard_fab2(sch_1):page28_i172:ddr5_dq(53)" )
			)
			( pin "U5D1.CW34"
				( objectStatus "@baseboard_fab2_lib.baseboard_fab2(sch_1):page28_i172:ddr5_dq(54)" )
			)
			( pin "U5D1.DC34"
				( objectStatus "@baseboard_fab2_lib.baseboard_fab2(sch_1):page28_i172:ddr5_dq(55)" )
			)
			( pin "U5D1.CW30"
				( objectStatus "@baseboard_fab2_lib.baseboard_fab2(sch_1):page28_i172:ddr5_dq(56)" )
			)
			( pin "U5D1.DC30"
				( objectStatus "@baseboard_fab2_lib.baseboard_fab2(sch_1):page28_i172:ddr5_dq(57)" )
			)
			( pin "U5D1.CY27"
				( objectStatus "@baseboard_fab2_lib.baseboard_fab2(sch_1):page28_i172:ddr5_dq(58)" )
			)
			( pin "U5D1.DB27"
				( objectStatus "@baseboard_fab2_lib.baseboard_fab2(sch_1):page28_i172:ddr5_dq(59)" )
			)
			( pin "U5D1.CY31"
				( objectStatus "@baseboard_fab2_lib.baseboard_fab2(sch_1):page28_i172:ddr5_dq(60)" )
			)
			( pin "U5D1.DB31"
				( objectStatus "@baseboard_fab2_lib.baseboard_fab2(sch_1):page28_i172:ddr5_dq(61)" )
			)
			( pin "U5D1.CW28"
				( objectStatus "@baseboard_fab2_lib.baseboard_fab2(sch_1):page28_i172:ddr5_dq(62)" )
			)
			( pin "U5D1.DC28"
				( objectStatus "@baseboard_fab2_lib.baseboard_fab2(sch_1):page28_i172:ddr5_dq(63)" )
			)
			( pin "U5D1.CP77"
				( objectStatus "@baseboard_fab2_lib.baseboard_fab2(sch_1):page28_i172:ddr5_dqs_dn(0)" )
			)
			( pin "U5D1.DD77"
				( objectStatus "@baseboard_fab2_lib.baseboard_fab2(sch_1):page28_i172:ddr5_dqs_dn(1)" )
			)
			( pin "U5D1.DL72"
				( objectStatus "@baseboard_fab2_lib.baseboard_fab2(sch_1):page28_i172:ddr5_dqs_dn(2)" )
			)
			( pin "U5D1.CV65"
				( objectStatus "@baseboard_fab2_lib.baseboard_fab2(sch_1):page28_i172:ddr5_dqs_dn(3)" )
			)
			( pin "U5D1.DG40"
				( objectStatus "@baseboard_fab2_lib.baseboard_fab2(sch_1):page28_i172:ddr5_dqs_dn(4)" )
			)
			( pin "U5D1.DL32"
				( objectStatus "@baseboard_fab2_lib.baseboard_fab2(sch_1):page28_i172:ddr5_dqs_dn(5)" )
			)
			( pin "U5D1.DD35"
				( objectStatus "@baseboard_fab2_lib.baseboard_fab2(sch_1):page28_i172:ddr5_dqs_dn(6)" )
			)
			( pin "U5D1.DD29"
				( objectStatus "@baseboard_fab2_lib.baseboard_fab2(sch_1):page28_i172:ddr5_dqs_dn(7)" )
			)
			( pin "U5D1.CN70"
				( objectStatus "@baseboard_fab2_lib.baseboard_fab2(sch_1):page28_i172:ddr5_dqs_dn(8)" )
			)
			( pin "U5D1.CT75"
				( objectStatus "@baseboard_fab2_lib.baseboard_fab2(sch_1):page28_i172:ddr5_dqs_dn(9)" )
			)
			( pin "U5D1.DF75"
				( objectStatus "@baseboard_fab2_lib.baseboard_fab2(sch_1):page28_i172:ddr5_dqs_dn(10)" )
			)
			( pin "U5D1.DJ70"
				( objectStatus "@baseboard_fab2_lib.baseboard_fab2(sch_1):page28_i172:ddr5_dqs_dn(11)" )
			)
			( pin "U5D1.CP65"
				( objectStatus "@baseboard_fab2_lib.baseboard_fab2(sch_1):page28_i172:ddr5_dqs_dn(12)" )
			)
			( pin "U5D1.DE40"
				( objectStatus "@baseboard_fab2_lib.baseboard_fab2(sch_1):page28_i172:ddr5_dqs_dn(13)" )
			)
			( pin "U5D1.DG32"
				( objectStatus "@baseboard_fab2_lib.baseboard_fab2(sch_1):page28_i172:ddr5_dqs_dn(14)" )
			)
			( pin "U5D1.CY35"
				( objectStatus "@baseboard_fab2_lib.baseboard_fab2(sch_1):page28_i172:ddr5_dqs_dn(15)" )
			)
			( pin "U5D1.CY29"
				( objectStatus "@baseboard_fab2_lib.baseboard_fab2(sch_1):page28_i172:ddr5_dqs_dn(16)" )
			)
			( pin "U5D1.CJ70"
				( objectStatus "@baseboard_fab2_lib.baseboard_fab2(sch_1):page28_i172:ddr5_dqs_dn(17)" )
			)
			( pin "U5D1.CR76"
				( objectStatus "@baseboard_fab2_lib.baseboard_fab2(sch_1):page28_i172:ddr5_dqs_dp(0)" )
			)
			( pin "U5D1.DE76"
				( objectStatus "@baseboard_fab2_lib.baseboard_fab2(sch_1):page28_i172:ddr5_dqs_dp(1)" )
			)
			( pin "U5D1.DK71"
				( objectStatus "@baseboard_fab2_lib.baseboard_fab2(sch_1):page28_i172:ddr5_dqs_dp(2)" )
			)
			( pin "U5D1.CT65"
				( objectStatus "@baseboard_fab2_lib.baseboard_fab2(sch_1):page28_i172:ddr5_dqs_dp(3)" )
			)
			( pin "U5D1.DJ40"
				( objectStatus "@baseboard_fab2_lib.baseboard_fab2(sch_1):page28_i172:ddr5_dqs_dp(4)" )
			)
			( pin "U5D1.DJ32"
				( objectStatus "@baseboard_fab2_lib.baseboard_fab2(sch_1):page28_i172:ddr5_dqs_dp(5)" )
			)
			( pin "U5D1.DB35"
				( objectStatus "@baseboard_fab2_lib.baseboard_fab2(sch_1):page28_i172:ddr5_dqs_dp(6)" )
			)
			( pin "U5D1.DB29"
				( objectStatus "@baseboard_fab2_lib.baseboard_fab2(sch_1):page28_i172:ddr5_dqs_dp(7)" )
			)
			( pin "U5D1.CL70"
				( objectStatus "@baseboard_fab2_lib.baseboard_fab2(sch_1):page28_i172:ddr5_dqs_dp(8)" )
			)
			( pin "U5D1.CU74"
				( objectStatus "@baseboard_fab2_lib.baseboard_fab2(sch_1):page28_i172:ddr5_dqs_dp(9)" )
			)
			( pin "U5D1.DG74"
				( objectStatus "@baseboard_fab2_lib.baseboard_fab2(sch_1):page28_i172:ddr5_dqs_dp(10)" )
			)
			( pin "U5D1.DH69"
				( objectStatus "@baseboard_fab2_lib.baseboard_fab2(sch_1):page28_i172:ddr5_dqs_dp(11)" )
			)
			( pin "U5D1.CM65"
				( objectStatus "@baseboard_fab2_lib.baseboard_fab2(sch_1):page28_i172:ddr5_dqs_dp(12)" )
			)
			( pin "U5D1.DC40"
				( objectStatus "@baseboard_fab2_lib.baseboard_fab2(sch_1):page28_i172:ddr5_dqs_dp(13)" )
			)
			( pin "U5D1.DE32"
				( objectStatus "@baseboard_fab2_lib.baseboard_fab2(sch_1):page28_i172:ddr5_dqs_dp(14)" )
			)
			( pin "U5D1.CV35"
				( objectStatus "@baseboard_fab2_lib.baseboard_fab2(sch_1):page28_i172:ddr5_dqs_dp(15)" )
			)
			( pin "U5D1.CV29"
				( objectStatus "@baseboard_fab2_lib.baseboard_fab2(sch_1):page28_i172:ddr5_dqs_dp(16)" )
			)
			( pin "U5D1.CG70"
				( objectStatus "@baseboard_fab2_lib.baseboard_fab2(sch_1):page28_i172:ddr5_dqs_dp(17)" )
			)
			( pin "U5D1.CH71"
				( objectStatus "@baseboard_fab2_lib.baseboard_fab2(sch_1):page28_i172:ddr5_ecc(0)" )
			)
			( pin "U5D1.CM71"
				( objectStatus "@baseboard_fab2_lib.baseboard_fab2(sch_1):page28_i172:ddr5_ecc(1)" )
			)
			( pin "U5D1.CJ68"
				( objectStatus "@baseboard_fab2_lib.baseboard_fab2(sch_1):page28_i172:ddr5_ecc(2)" )
			)
			( pin "U5D1.CL68"
				( objectStatus "@baseboard_fab2_lib.baseboard_fab2(sch_1):page28_i172:ddr5_ecc(3)" )
			)
			( pin "U5D1.CJ72"
				( objectStatus "@baseboard_fab2_lib.baseboard_fab2(sch_1):page28_i172:ddr5_ecc(4)" )
			)
			( pin "U5D1.CL72"
				( objectStatus "@baseboard_fab2_lib.baseboard_fab2(sch_1):page28_i172:ddr5_ecc(5)" )
			)
			( pin "U5D1.CH69"
				( objectStatus "@baseboard_fab2_lib.baseboard_fab2(sch_1):page28_i172:ddr5_ecc(6)" )
			)
			( pin "U5D1.CM69"
				( objectStatus "@baseboard_fab2_lib.baseboard_fab2(sch_1):page28_i172:ddr5_ecc(7)" )
			)
			( pin "U5D1.DF53"
				( objectStatus "@baseboard_fab2_lib.baseboard_fab2(sch_1):page28_i172:ddr5_ma(0)" )
			)
			( pin "U5D1.DC58"
				( objectStatus "@baseboard_fab2_lib.baseboard_fab2(sch_1):page28_i172:ddr5_ma(1)" )
			)
			( pin "U5D1.DD57"
				( objectStatus "@baseboard_fab2_lib.baseboard_fab2(sch_1):page28_i172:ddr5_ma(2)" )
			)
			( pin "U5D1.DG58"
				( objectStatus "@baseboard_fab2_lib.baseboard_fab2(sch_1):page28_i172:ddr5_ma(3)" )
			)
			( pin "U5D1.DJ58"
				( objectStatus "@baseboard_fab2_lib.baseboard_fab2(sch_1):page28_i172:ddr5_ma(4)" )
			)
			( pin "U5D1.DF59"
				( objectStatus "@baseboard_fab2_lib.baseboard_fab2(sch_1):page28_i172:ddr5_ma(5)" )
			)
			( pin "U5D1.DK59"
				( objectStatus "@baseboard_fab2_lib.baseboard_fab2(sch_1):page28_i172:ddr5_ma(6)" )
			)
			( pin "U5D1.DC60"
				( objectStatus "@baseboard_fab2_lib.baseboard_fab2(sch_1):page28_i172:ddr5_ma(7)" )
			)
			( pin "U5D1.DD59"
				( objectStatus "@baseboard_fab2_lib.baseboard_fab2(sch_1):page28_i172:ddr5_ma(8)" )
			)
			( pin "U5D1.DA58"
				( objectStatus "@baseboard_fab2_lib.baseboard_fab2(sch_1):page28_i172:ddr5_ma(9)" )
			)
			( pin "U5D1.DD55"
				( objectStatus "@baseboard_fab2_lib.baseboard_fab2(sch_1):page28_i172:ddr5_ma(10)" )
			)
			( pin "U5D1.DA60"
				( objectStatus "@baseboard_fab2_lib.baseboard_fab2(sch_1):page28_i172:ddr5_ma(11)" )
			)
			( pin "U5D1.DG60"
				( objectStatus "@baseboard_fab2_lib.baseboard_fab2(sch_1):page28_i172:ddr5_ma(12)" )
			)
			( pin "U5D1.DD53"
				( objectStatus "@baseboard_fab2_lib.baseboard_fab2(sch_1):page28_i172:ddr5_ma(13)" )
			)
			( pin "U5D1.DJ50"
				( objectStatus "@baseboard_fab2_lib.baseboard_fab2(sch_1):page28_i172:ddr5_ma(14)" )
			)
			( pin "U5D1.DC54"
				( objectStatus "@baseboard_fab2_lib.baseboard_fab2(sch_1):page28_i172:ddr5_ma(15)" )
			)
			( pin "U5D1.DG52"
				( objectStatus "@baseboard_fab2_lib.baseboard_fab2(sch_1):page28_i172:ddr5_ma(16)" )
			)
			( pin "U5D1.DE46"
				( objectStatus "@baseboard_fab2_lib.baseboard_fab2(sch_1):page28_i172:ddr5_ma(17)" )
			)
			( pin "U5D1.DG50"
				( objectStatus "@baseboard_fab2_lib.baseboard_fab2(sch_1):page28_i172:ddr5_odt(0)" )
			)
			( pin "U5D1.DG48"
				( objectStatus "@baseboard_fab2_lib.baseboard_fab2(sch_1):page28_i172:ddr5_odt(1)" )
			)
			( pin "U5D1.DK49"
				( objectStatus "@baseboard_fab2_lib.baseboard_fab2(sch_1):page28_i172:ddr5_odt(2)" )
			)
			( pin "U5D1.DF47"
				( objectStatus "@baseboard_fab2_lib.baseboard_fab2(sch_1):page28_i172:ddr5_odt(3)" )
			)
			( pin "U5D1.DK53"
				( objectStatus "@baseboard_fab2_lib.baseboard_fab2(sch_1):page28_i172:ddr5_par" )
			)
			( pin "U5D1.BN22"
				( objectStatus "@baseboard_fab2_lib.baseboard_fab2(sch_1):page29_i61:cd_hfi0_i2cclk" )
			)
			( pin "U5D1.BP23"
				( objectStatus "@baseboard_fab2_lib.baseboard_fab2(sch_1):page29_i61:cd_hfi0_i2cdat" )
			)
			( pin "U5D1.BP19"
				( objectStatus "@baseboard_fab2_lib.baseboard_fab2(sch_1):page29_i61:cd_hfi0_int_n" )
			)
			( pin "U5D1.BK21"
				( objectStatus "@baseboard_fab2_lib.baseboard_fab2(sch_1):page29_i61:cd_hfi0_led_n" )
			)
			( pin "U5D1.BR20"
				( objectStatus "@baseboard_fab2_lib.baseboard_fab2(sch_1):page29_i61:cd_hfi0_modprst_n" )
			)
			( pin "U5D1.BN24"
				( objectStatus "@baseboard_fab2_lib.baseboard_fab2(sch_1):page29_i61:cd_hfi0_reset_n" )
			)
			( pin "U5D1.BJ22"
				( objectStatus "@baseboard_fab2_lib.baseboard_fab2(sch_1):page29_i61:cd_hfi1_i2cclk" )
			)
			( pin "U5D1.BH23"
				( objectStatus "@baseboard_fab2_lib.baseboard_fab2(sch_1):page29_i61:cd_hfi1_i2cdat" )
			)
			( pin "U5D1.BM21"
				( objectStatus "@baseboard_fab2_lib.baseboard_fab2(sch_1):page29_i61:cd_hfi1_int_n" )
			)
			( pin "U5D1.BM23"
				( objectStatus "@baseboard_fab2_lib.baseboard_fab2(sch_1):page29_i61:cd_hfi1_led_n" )
			)
			( pin "U5D1.BT19"
				( objectStatus "@baseboard_fab2_lib.baseboard_fab2(sch_1):page29_i61:cd_hfi1_modprst_n" )
			)
			( pin "U5D1.BK23"
				( objectStatus "@baseboard_fab2_lib.baseboard_fab2(sch_1):page29_i61:cd_hfi1_reset_n" )
			)
			( pin "U5D1.BE16"
				( objectStatus "@baseboard_fab2_lib.baseboard_fab2(sch_1):page29_i61:cd_hfi_refclk_dn" )
			)
			( pin "U5D1.BG16"
				( objectStatus "@baseboard_fab2_lib.baseboard_fab2(sch_1):page29_i61:cd_hfi_refclk_dp" )
			)
			( pin "U5D1.BU24"
				( objectStatus "@baseboard_fab2_lib.baseboard_fab2(sch_1):page29_i61:cd_pe_refclk_dn" )
			)
			( pin "U5D1.BW24"
				( objectStatus "@baseboard_fab2_lib.baseboard_fab2(sch_1):page29_i61:cd_pe_refclk_dp" )
			)
			( pin "U5D1.CF25"
				( objectStatus "@baseboard_fab2_lib.baseboard_fab2(sch_1):page29_i61:cd_por_n" )
			)
			( pin "U5D1.CB23"
				( objectStatus "@baseboard_fab2_lib.baseboard_fab2(sch_1):page29_i61:cd_tclk" )
			)
			( pin "U5D1.BY21"
				( objectStatus "@baseboard_fab2_lib.baseboard_fab2(sch_1):page29_i61:cd_tdi" )
			)
			( pin "U5D1.CC22"
				( objectStatus "@baseboard_fab2_lib.baseboard_fab2(sch_1):page29_i61:cd_tdo" )
			)
			( pin "U5D1.CE24"
				( objectStatus "@baseboard_fab2_lib.baseboard_fab2(sch_1):page29_i61:cd_tms" )
			)
			( pin "U5D1.CD23"
				( objectStatus "@baseboard_fab2_lib.baseboard_fab2(sch_1):page29_i61:cd_trst_n" )
			)
			( pin "U5D1.CK9"
				( objectStatus "@baseboard_fab2_lib.baseboard_fab2(sch_1):page29_i61:dmi_rx_dn(0)" )
			)
			( pin "U5D1.CM11"
				( objectStatus "@baseboard_fab2_lib.baseboard_fab2(sch_1):page29_i61:dmi_rx_dn(1)" )
			)
			( pin "U5D1.CR12"
				( objectStatus "@baseboard_fab2_lib.baseboard_fab2(sch_1):page29_i61:dmi_rx_dn(2)" )
			)
			( pin "U5D1.CT11"
				( objectStatus "@baseboard_fab2_lib.baseboard_fab2(sch_1):page29_i61:dmi_rx_dn(3)" )
			)
			( pin "U5D1.CL10"
				( objectStatus "@baseboard_fab2_lib.baseboard_fab2(sch_1):page29_i61:dmi_rx_dp(0)" )
			)
			( pin "U5D1.CN10"
				( objectStatus "@baseboard_fab2_lib.baseboard_fab2(sch_1):page29_i61:dmi_rx_dp(1)" )
			)
			( pin "U5D1.CP11"
				( objectStatus "@baseboard_fab2_lib.baseboard_fab2(sch_1):page29_i61:dmi_rx_dp(2)" )
			)
			( pin "U5D1.CV11"
				( objectStatus "@baseboard_fab2_lib.baseboard_fab2(sch_1):page29_i61:dmi_rx_dp(3)" )
			)
			( pin "U5D1.CG4"
				( objectStatus "@baseboard_fab2_lib.baseboard_fab2(sch_1):page29_i61:dmi_tx_dn(0)" )
			)
			( pin "U5D1.CJ4"
				( objectStatus "@baseboard_fab2_lib.baseboard_fab2(sch_1):page29_i61:dmi_tx_dn(1)" )
			)
			( pin "U5D1.CN4"
				( objectStatus "@baseboard_fab2_lib.baseboard_fab2(sch_1):page29_i61:dmi_tx_dn(2)" )
			)
			( pin "U5D1.CP5"
				( objectStatus "@baseboard_fab2_lib.baseboard_fab2(sch_1):page29_i61:dmi_tx_dn(3)" )
			)
			( pin "U5D1.CH5"
				( objectStatus "@baseboard_fab2_lib.baseboard_fab2(sch_1):page29_i61:dmi_tx_dp(0)" )
			)
			( pin "U5D1.CL4"
				( objectStatus "@baseboard_fab2_lib.baseboard_fab2(sch_1):page29_i61:dmi_tx_dp(1)" )
			)
			( pin "U5D1.CM3"
				( objectStatus "@baseboard_fab2_lib.baseboard_fab2(sch_1):page29_i61:dmi_tx_dp(2)" )
			)
			( pin "U5D1.CR4"
				( objectStatus "@baseboard_fab2_lib.baseboard_fab2(sch_1):page29_i61:dmi_tx_dp(3)" )
			)
			( pin "U5D1.BA76"
				( objectStatus "@baseboard_fab2_lib.baseboard_fab2(sch_1):page29_i61:rsvd(172)" )
			)
			( pin "U5D1.BA66"
				( objectStatus "@baseboard_fab2_lib.baseboard_fab2(sch_1):page29_i61:rsvd(173)" )
			)
			( pin "U5D1.BA64"
				( objectStatus "@baseboard_fab2_lib.baseboard_fab2(sch_1):page29_i61:rsvd(174)" )
			)
			( pin "U5D1.BA22"
				( objectStatus "@baseboard_fab2_lib.baseboard_fab2(sch_1):page29_i61:rsvd(175)" )
			)
			( pin "U5D1.BA18"
				( objectStatus "@baseboard_fab2_lib.baseboard_fab2(sch_1):page29_i61:rsvd(176)" )
			)
			( pin "U5D1.BA16"
				( objectStatus "@baseboard_fab2_lib.baseboard_fab2(sch_1):page29_i61:rsvd(177)" )
			)
			( pin "U5D1.BA14"
				( objectStatus "@baseboard_fab2_lib.baseboard_fab2(sch_1):page29_i61:rsvd(178)" )
			)
			( pin "U5D1.AY77"
				( objectStatus "@baseboard_fab2_lib.baseboard_fab2(sch_1):page29_i61:rsvd(179)" )
			)
			( pin "U5D1.AY75"
				( objectStatus "@baseboard_fab2_lib.baseboard_fab2(sch_1):page29_i61:rsvd(180)" )
			)
			( pin "U5D1.AY67"
				( objectStatus "@baseboard_fab2_lib.baseboard_fab2(sch_1):page29_i61:rsvd(181)" )
			)
			( pin "U5D1.AY65"
				( objectStatus "@baseboard_fab2_lib.baseboard_fab2(sch_1):page29_i61:rsvd(182)" )
			)
			( pin "U5D1.AW76"
				( objectStatus "@baseboard_fab2_lib.baseboard_fab2(sch_1):page29_i61:rsvd(183)" )
			)
			( pin "U5D1.AW64"
				( objectStatus "@baseboard_fab2_lib.baseboard_fab2(sch_1):page29_i61:rsvd(184)" )
			)
			( pin "U5D1.AV77"
				( objectStatus "@baseboard_fab2_lib.baseboard_fab2(sch_1):page29_i61:rsvd(186)" )
			)
			( pin "U5D1.AT25"
				( objectStatus "@baseboard_fab2_lib.baseboard_fab2(sch_1):page29_i61:rsvd(187)" )
			)
			( pin "U5D1.AT23"
				( objectStatus "@baseboard_fab2_lib.baseboard_fab2(sch_1):page29_i61:rsvd(188)" )
			)
			( pin "U5D1.AT13"
				( objectStatus "@baseboard_fab2_lib.baseboard_fab2(sch_1):page29_i61:rsvd(189)" )
			)
			( pin "U5D1.AR62"
				( objectStatus "@baseboard_fab2_lib.baseboard_fab2(sch_1):page29_i61:rsvd(190)" )
			)
			( pin "U5D1.AR26"
				( objectStatus "@baseboard_fab2_lib.baseboard_fab2(sch_1):page29_i61:rsvd(191)" )
			)
			( pin "U5D1.AR22"
				( objectStatus "@baseboard_fab2_lib.baseboard_fab2(sch_1):page29_i61:rsvd(192)" )
			)
			( pin "U5D1.AR20"
				( objectStatus "@baseboard_fab2_lib.baseboard_fab2(sch_1):page29_i61:rsvd(193)" )
			)
			( pin "U5D1.CW8"
				( objectStatus "@baseboard_fab2_lib.baseboard_fab2(sch_1):page30_i84:pe1_rx_dn(0)" )
			)
			( pin "U5D1.DA8"
				( objectStatus "@baseboard_fab2_lib.baseboard_fab2(sch_1):page30_i84:pe1_rx_dn(1)" )
			)
			( pin "U5D1.DC8"
				( objectStatus "@baseboard_fab2_lib.baseboard_fab2(sch_1):page30_i84:pe1_rx_dn(2)" )
			)
			( pin "U5D1.DC10"
				( objectStatus "@baseboard_fab2_lib.baseboard_fab2(sch_1):page30_i84:pe1_rx_dn(3)" )
			)
			( pin "U5D1.DE10"
				( objectStatus "@baseboard_fab2_lib.baseboard_fab2(sch_1):page30_i84:pe1_rx_dn(4)" )
			)
			( pin "U5D1.DH9"
				( objectStatus "@baseboard_fab2_lib.baseboard_fab2(sch_1):page30_i84:pe1_rx_dn(5)" )
			)
			( pin "U5D1.DK9"
				( objectStatus "@baseboard_fab2_lib.baseboard_fab2(sch_1):page30_i84:pe1_rx_dn(6)" )
			)
			( pin "U5D1.DM9"
				( objectStatus "@baseboard_fab2_lib.baseboard_fab2(sch_1):page30_i84:pe1_rx_dn(7)" )
			)
			( pin "U5D1.DM11"
				( objectStatus "@baseboard_fab2_lib.baseboard_fab2(sch_1):page30_i84:pe1_rx_dn(8)" )
			)
			( pin "U5D1.DP11"
				( objectStatus "@baseboard_fab2_lib.baseboard_fab2(sch_1):page30_i84:pe1_rx_dn(9)" )
			)
			( pin "U5D1.DT11"
				( objectStatus "@baseboard_fab2_lib.baseboard_fab2(sch_1):page30_i84:pe1_rx_dn(10)" )
			)
			( pin "U5D1.DT13"
				( objectStatus "@baseboard_fab2_lib.baseboard_fab2(sch_1):page30_i84:pe1_rx_dn(11)" )
			)
			( pin "U5D1.DV13"
				( objectStatus "@baseboard_fab2_lib.baseboard_fab2(sch_1):page30_i84:pe1_rx_dn(12)" )
			)
			( pin "U5D1.DW14"
				( objectStatus "@baseboard_fab2_lib.baseboard_fab2(sch_1):page30_i84:pe1_rx_dn(13)" )
			)
			( pin "U5D1.DY15"
				( objectStatus "@baseboard_fab2_lib.baseboard_fab2(sch_1):page30_i84:pe1_rx_dn(14)" )
			)
			( pin "U5D1.DU16"
				( objectStatus "@baseboard_fab2_lib.baseboard_fab2(sch_1):page30_i84:pe1_rx_dn(15)" )
			)
			( pin "U5D1.CU8"
				( objectStatus "@baseboard_fab2_lib.baseboard_fab2(sch_1):page30_i84:pe1_rx_dp(0)" )
			)
			( pin "U5D1.CY7"
				( objectStatus "@baseboard_fab2_lib.baseboard_fab2(sch_1):page30_i84:pe1_rx_dp(1)" )
			)
			( pin "U5D1.DB9"
				( objectStatus "@baseboard_fab2_lib.baseboard_fab2(sch_1):page30_i84:pe1_rx_dp(2)" )
			)
			( pin "U5D1.DA10"
				( objectStatus "@baseboard_fab2_lib.baseboard_fab2(sch_1):page30_i84:pe1_rx_dp(3)" )
			)
			( pin "U5D1.DD9"
				( objectStatus "@baseboard_fab2_lib.baseboard_fab2(sch_1):page30_i84:pe1_rx_dp(4)" )
			)
			( pin "U5D1.DF9"
				( objectStatus "@baseboard_fab2_lib.baseboard_fab2(sch_1):page30_i84:pe1_rx_dp(5)" )
			)
			( pin "U5D1.DJ8"
				( objectStatus "@baseboard_fab2_lib.baseboard_fab2(sch_1):page30_i84:pe1_rx_dp(6)" )
			)
			( pin "U5D1.DL10"
				( objectStatus "@baseboard_fab2_lib.baseboard_fab2(sch_1):page30_i84:pe1_rx_dp(7)" )
			)
			( pin "U5D1.DK11"
				( objectStatus "@baseboard_fab2_lib.baseboard_fab2(sch_1):page30_i84:pe1_rx_dp(8)" )
			)
			( pin "U5D1.DN10"
				( objectStatus "@baseboard_fab2_lib.baseboard_fab2(sch_1):page30_i84:pe1_rx_dp(9)" )
			)
			( pin "U5D1.DR12"
				( objectStatus "@baseboard_fab2_lib.baseboard_fab2(sch_1):page30_i84:pe1_rx_dp(10)" )
			)
			( pin "U5D1.DP13"
				( objectStatus "@baseboard_fab2_lib.baseboard_fab2(sch_1):page30_i84:pe1_rx_dp(11)" )
			)
			( pin "U5D1.DU12"
				( objectStatus "@baseboard_fab2_lib.baseboard_fab2(sch_1):page30_i84:pe1_rx_dp(12)" )
			)
			( pin "U5D1.DY13"
				( objectStatus "@baseboard_fab2_lib.baseboard_fab2(sch_1):page30_i84:pe1_rx_dp(13)" )
			)
			( pin "U5D1.DV15"
				( objectStatus "@baseboard_fab2_lib.baseboard_fab2(sch_1):page30_i84:pe1_rx_dp(14)" )
			)
			( pin "U5D1.DT15"
				( objectStatus "@baseboard_fab2_lib.baseboard_fab2(sch_1):page30_i84:pe1_rx_dp(15)" )
			)
			( pin "U5D1.DA2"
				( objectStatus "@baseboard_fab2_lib.baseboard_fab2(sch_1):page30_i84:pe1_tx_dn(0)" )
			)
			( pin "U5D1.DC2"
				( objectStatus "@baseboard_fab2_lib.baseboard_fab2(sch_1):page30_i84:pe1_tx_dn(1)" )
			)
			( pin "U5D1.DE2"
				( objectStatus "@baseboard_fab2_lib.baseboard_fab2(sch_1):page30_i84:pe1_tx_dn(2)" )
			)
			( pin "U5D1.DE4"
				( objectStatus "@baseboard_fab2_lib.baseboard_fab2(sch_1):page30_i84:pe1_tx_dn(3)" )
			)
			( pin "U5D1.DG4"
				( objectStatus "@baseboard_fab2_lib.baseboard_fab2(sch_1):page30_i84:pe1_tx_dn(4)" )
			)
			( pin "U5D1.DK3"
				( objectStatus "@baseboard_fab2_lib.baseboard_fab2(sch_1):page30_i84:pe1_tx_dn(5)" )
			)
			( pin "U5D1.DM3"
				( objectStatus "@baseboard_fab2_lib.baseboard_fab2(sch_1):page30_i84:pe1_tx_dn(6)" )
			)
			( pin "U5D1.DN4"
				( objectStatus "@baseboard_fab2_lib.baseboard_fab2(sch_1):page30_i84:pe1_tx_dn(7)" )
			)
			( pin "U5D1.DT5"
				( objectStatus "@baseboard_fab2_lib.baseboard_fab2(sch_1):page30_i84:pe1_tx_dn(8)" )
			)
			( pin "U5D1.DV3"
				( objectStatus "@baseboard_fab2_lib.baseboard_fab2(sch_1):page30_i84:pe1_tx_dn(9)" )
			)
			( pin "U5D1.DW4"
				( objectStatus "@baseboard_fab2_lib.baseboard_fab2(sch_1):page30_i84:pe1_tx_dn(10)" )
			)
			( pin "U5D1.DU6"
				( objectStatus "@baseboard_fab2_lib.baseboard_fab2(sch_1):page30_i84:pe1_tx_dn(11)" )
			)
			( pin "U5D1.DV7"
				( objectStatus "@baseboard_fab2_lib.baseboard_fab2(sch_1):page30_i84:pe1_tx_dn(12)" )
			)
			( pin "U5D1.DY7"
				( objectStatus "@baseboard_fab2_lib.baseboard_fab2(sch_1):page30_i84:pe1_tx_dn(13)" )
			)
			( pin "U5D1.EA8"
				( objectStatus "@baseboard_fab2_lib.baseboard_fab2(sch_1):page30_i84:pe1_tx_dn(14)" )
			)
			( pin "U5D1.ED9"
				( objectStatus "@baseboard_fab2_lib.baseboard_fab2(sch_1):page30_i84:pe1_tx_dn(15)" )
			)
			( pin "U5D1.CW2"
				( objectStatus "@baseboard_fab2_lib.baseboard_fab2(sch_1):page30_i84:pe1_tx_dp(0)" )
			)
			( pin "U5D1.DB1"
				( objectStatus "@baseboard_fab2_lib.baseboard_fab2(sch_1):page30_i84:pe1_tx_dp(1)" )
			)
			( pin "U5D1.DD3"
				( objectStatus "@baseboard_fab2_lib.baseboard_fab2(sch_1):page30_i84:pe1_tx_dp(2)" )
			)
			( pin "U5D1.DC4"
				( objectStatus "@baseboard_fab2_lib.baseboard_fab2(sch_1):page30_i84:pe1_tx_dp(3)" )
			)
			( pin "U5D1.DF3"
				( objectStatus "@baseboard_fab2_lib.baseboard_fab2(sch_1):page30_i84:pe1_tx_dp(4)" )
			)
			( pin "U5D1.DH3"
				( objectStatus "@baseboard_fab2_lib.baseboard_fab2(sch_1):page30_i84:pe1_tx_dp(5)" )
			)
			( pin "U5D1.DL2"
				( objectStatus "@baseboard_fab2_lib.baseboard_fab2(sch_1):page30_i84:pe1_tx_dp(6)" )
			)
			( pin "U5D1.DP3"
				( objectStatus "@baseboard_fab2_lib.baseboard_fab2(sch_1):page30_i84:pe1_tx_dp(7)" )
			)
			( pin "U5D1.DR4"
				( objectStatus "@baseboard_fab2_lib.baseboard_fab2(sch_1):page30_i84:pe1_tx_dp(8)" )
			)
			( pin "U5D1.DU2"
				( objectStatus "@baseboard_fab2_lib.baseboard_fab2(sch_1):page30_i84:pe1_tx_dp(9)" )
			)
			( pin "U5D1.DU4"
				( objectStatus "@baseboard_fab2_lib.baseboard_fab2(sch_1):page30_i84:pe1_tx_dp(10)" )
			)
			( pin "U5D1.DV5"
				( objectStatus "@baseboard_fab2_lib.baseboard_fab2(sch_1):page30_i84:pe1_tx_dp(11)" )
			)
			( pin "U5D1.DT7"
				( objectStatus "@baseboard_fab2_lib.baseboard_fab2(sch_1):page30_i84:pe1_tx_dp(12)" )
			)
			( pin "U5D1.DW6"
				( objectStatus "@baseboard_fab2_lib.baseboard_fab2(sch_1):page30_i84:pe1_tx_dp(13)" )
			)
			( pin "U5D1.EB7"
				( objectStatus "@baseboard_fab2_lib.baseboard_fab2(sch_1):page30_i84:pe1_tx_dp(14)" )
			)
			( pin "U5D1.EC8"
				( objectStatus "@baseboard_fab2_lib.baseboard_fab2(sch_1):page30_i84:pe1_tx_dp(15)" )
			)
			( pin "U5D1.CT9"
				( objectStatus "@baseboard_fab2_lib.baseboard_fab2(sch_1):page31_i106:pe2_rx_dn(0)" )
			)
			( pin "U5D1.CP9"
				( objectStatus "@baseboard_fab2_lib.baseboard_fab2(sch_1):page31_i106:pe2_rx_dn(1)" )
			)
			( pin "U5D1.CP7"
				( objectStatus "@baseboard_fab2_lib.baseboard_fab2(sch_1):page31_i106:pe2_rx_dn(2)" )
			)
			( pin "U5D1.CM7"
				( objectStatus "@baseboard_fab2_lib.baseboard_fab2(sch_1):page31_i106:pe2_rx_dn(3)" )
			)
			( pin "U5D1.CK7"
				( objectStatus "@baseboard_fab2_lib.baseboard_fab2(sch_1):page31_i106:pe2_rx_dn(4)" )
			)
			( pin "U5D1.CG8"
				( objectStatus "@baseboard_fab2_lib.baseboard_fab2(sch_1):page31_i106:pe2_rx_dn(5)" )
			)
			( pin "U5D1.CE6"
				( objectStatus "@baseboard_fab2_lib.baseboard_fab2(sch_1):page31_i106:pe2_rx_dn(6)" )
			)
			( pin "U5D1.CE8"
				( objectStatus "@baseboard_fab2_lib.baseboard_fab2(sch_1):page31_i106:pe2_rx_dn(7)" )
			)
			( pin "U5D1.BY9"
				( objectStatus "@baseboard_fab2_lib.baseboard_fab2(sch_1):page31_i106:pe2_rx_dn(8)" )
			)
			( pin "U5D1.BY7"
				( objectStatus "@baseboard_fab2_lib.baseboard_fab2(sch_1):page31_i106:pe2_rx_dn(9)" )
			)
			( pin "U5D1.BV7"
				( objectStatus "@baseboard_fab2_lib.baseboard_fab2(sch_1):page31_i106:pe2_rx_dn(10)" )
			)
			( pin "U5D1.BT7"
				( objectStatus "@baseboard_fab2_lib.baseboard_fab2(sch_1):page31_i106:pe2_rx_dn(11)" )
			)
			( pin "U5D1.BR8"
				( objectStatus "@baseboard_fab2_lib.baseboard_fab2(sch_1):page31_i106:pe2_rx_dn(12)" )
			)
			( pin "U5D1.BN8"
				( objectStatus "@baseboard_fab2_lib.baseboard_fab2(sch_1):page31_i106:pe2_rx_dn(13)" )
			)
			( pin "U5D1.BL8"
				( objectStatus "@baseboard_fab2_lib.baseboard_fab2(sch_1):page31_i106:pe2_rx_dn(14)" )
			)
			( pin "U5D1.BK9"
				( objectStatus "@baseboard_fab2_lib.baseboard_fab2(sch_1):page31_i106:pe2_rx_dn(15)" )
			)
			( pin "U5D1.CR8"
				( objectStatus "@baseboard_fab2_lib.baseboard_fab2(sch_1):page31_i106:pe2_rx_dp(0)" )
			)
			( pin "U5D1.CM9"
				( objectStatus "@baseboard_fab2_lib.baseboard_fab2(sch_1):page31_i106:pe2_rx_dp(1)" )
			)
			( pin "U5D1.CN8"
				( objectStatus "@baseboard_fab2_lib.baseboard_fab2(sch_1):page31_i106:pe2_rx_dp(2)" )
			)
			( pin "U5D1.CL6"
				( objectStatus "@baseboard_fab2_lib.baseboard_fab2(sch_1):page31_i106:pe2_rx_dp(3)" )
			)
			( pin "U5D1.CH7"
				( objectStatus "@baseboard_fab2_lib.baseboard_fab2(sch_1):page31_i106:pe2_rx_dp(4)" )
			)
			( pin "U5D1.CF7"
				( objectStatus "@baseboard_fab2_lib.baseboard_fab2(sch_1):page31_i106:pe2_rx_dp(5)" )
			)
			( pin "U5D1.CD7"
				( objectStatus "@baseboard_fab2_lib.baseboard_fab2(sch_1):page31_i106:pe2_rx_dp(6)" )
			)
			( pin "U5D1.CC8"
				( objectStatus "@baseboard_fab2_lib.baseboard_fab2(sch_1):page31_i106:pe2_rx_dp(7)" )
			)
			( pin "U5D1.BV9"
				( objectStatus "@baseboard_fab2_lib.baseboard_fab2(sch_1):page31_i106:pe2_rx_dp(8)" )
			)
			( pin "U5D1.BW8"
				( objectStatus "@baseboard_fab2_lib.baseboard_fab2(sch_1):page31_i106:pe2_rx_dp(9)" )
			)
			( pin "U5D1.BU6"
				( objectStatus "@baseboard_fab2_lib.baseboard_fab2(sch_1):page31_i106:pe2_rx_dp(10)" )
			)
			( pin "U5D1.BP7"
				( objectStatus "@baseboard_fab2_lib.baseboard_fab2(sch_1):page31_i106:pe2_rx_dp(11)" )
			)
			( pin "U5D1.BP9"
				( objectStatus "@baseboard_fab2_lib.baseboard_fab2(sch_1):page31_i106:pe2_rx_dp(12)" )
			)
			( pin "U5D1.BM7"
				( objectStatus "@baseboard_fab2_lib.baseboard_fab2(sch_1):page31_i106:pe2_rx_dp(13)" )
			)
			( pin "U5D1.BJ8"
				( objectStatus "@baseboard_fab2_lib.baseboard_fab2(sch_1):page31_i106:pe2_rx_dp(14)" )
			)
			( pin "U5D1.BJ10"
				( objectStatus "@baseboard_fab2_lib.baseboard_fab2(sch_1):page31_i106:pe2_rx_dp(15)" )
			)
			( pin "U5D1.CY3"
				( objectStatus "@baseboard_fab2_lib.baseboard_fab2(sch_1):page31_i106:pe2_tx_dn(0)" )
			)
			( pin "U5D1.CV3"
				( objectStatus "@baseboard_fab2_lib.baseboard_fab2(sch_1):page31_i106:pe2_tx_dn(1)" )
			)
			( pin "U5D1.CT1"
				( objectStatus "@baseboard_fab2_lib.baseboard_fab2(sch_1):page31_i106:pe2_tx_dn(2)" )
			)
			( pin "U5D1.CT3"
				( objectStatus "@baseboard_fab2_lib.baseboard_fab2(sch_1):page31_i106:pe2_tx_dn(3)" )
			)
			( pin "U5D1.CM1"
				( objectStatus "@baseboard_fab2_lib.baseboard_fab2(sch_1):page31_i106:pe2_tx_dn(4)" )
			)
			( pin "U5D1.CL2"
				( objectStatus "@baseboard_fab2_lib.baseboard_fab2(sch_1):page31_i106:pe2_tx_dn(5)" )
			)
			( pin "U5D1.CG2"
				( objectStatus "@baseboard_fab2_lib.baseboard_fab2(sch_1):page31_i106:pe2_tx_dn(6)" )
			)
			( pin "U5D1.CF3"
				( objectStatus "@baseboard_fab2_lib.baseboard_fab2(sch_1):page31_i106:pe2_tx_dn(7)" )
			)
			( pin "U5D1.CC2"
				( objectStatus "@baseboard_fab2_lib.baseboard_fab2(sch_1):page31_i106:pe2_tx_dn(8)" )
			)
			( pin "U5D1.CB3"
				( objectStatus "@baseboard_fab2_lib.baseboard_fab2(sch_1):page31_i106:pe2_tx_dn(9)" )
			)
			( pin "U5D1.CA4"
				( objectStatus "@baseboard_fab2_lib.baseboard_fab2(sch_1):page31_i106:pe2_tx_dn(10)" )
			)
			( pin "U5D1.BW4"
				( objectStatus "@baseboard_fab2_lib.baseboard_fab2(sch_1):page31_i106:pe2_tx_dn(11)" )
			)
			( pin "U5D1.BU4"
				( objectStatus "@baseboard_fab2_lib.baseboard_fab2(sch_1):page31_i106:pe2_tx_dn(12)" )
			)
			( pin "U5D1.BP5"
				( objectStatus "@baseboard_fab2_lib.baseboard_fab2(sch_1):page31_i106:pe2_tx_dn(13)" )
			)
			( pin "U5D1.BL4"
				( objectStatus "@baseboard_fab2_lib.baseboard_fab2(sch_1):page31_i106:pe2_tx_dn(14)" )
			)
			( pin "U5D1.BM5"
				( objectStatus "@baseboard_fab2_lib.baseboard_fab2(sch_1):page31_i106:pe2_tx_dn(15)" )
			)
			( pin "U5D1.CW4"
				( objectStatus "@baseboard_fab2_lib.baseboard_fab2(sch_1):page31_i106:pe2_tx_dp(0)" )
			)
			( pin "U5D1.CU2"
				( objectStatus "@baseboard_fab2_lib.baseboard_fab2(sch_1):page31_i106:pe2_tx_dp(1)" )
			)
			( pin "U5D1.CR2"
				( objectStatus "@baseboard_fab2_lib.baseboard_fab2(sch_1):page31_i106:pe2_tx_dp(2)" )
			)
			( pin "U5D1.CP3"
				( objectStatus "@baseboard_fab2_lib.baseboard_fab2(sch_1):page31_i106:pe2_tx_dp(3)" )
			)
			( pin "U5D1.CK1"
				( objectStatus "@baseboard_fab2_lib.baseboard_fab2(sch_1):page31_i106:pe2_tx_dp(4)" )
			)
			( pin "U5D1.CK3"
				( objectStatus "@baseboard_fab2_lib.baseboard_fab2(sch_1):page31_i106:pe2_tx_dp(5)" )
			)
			( pin "U5D1.CE2"
				( objectStatus "@baseboard_fab2_lib.baseboard_fab2(sch_1):page31_i106:pe2_tx_dp(6)" )
			)
			( pin "U5D1.CE4"
				( objectStatus "@baseboard_fab2_lib.baseboard_fab2(sch_1):page31_i106:pe2_tx_dp(7)" )
			)
			( pin "U5D1.CD3"
				( objectStatus "@baseboard_fab2_lib.baseboard_fab2(sch_1):page31_i106:pe2_tx_dp(8)" )
			)
			( pin "U5D1.BY3"
				( objectStatus "@baseboard_fab2_lib.baseboard_fab2(sch_1):page31_i106:pe2_tx_dp(9)" )
			)
			( pin "U5D1.BY5"
				( objectStatus "@baseboard_fab2_lib.baseboard_fab2(sch_1):page31_i106:pe2_tx_dp(10)" )
			)
			( pin "U5D1.BV3"
				( objectStatus "@baseboard_fab2_lib.baseboard_fab2(sch_1):page31_i106:pe2_tx_dp(11)" )
			)
			( pin "U5D1.BR4"
				( objectStatus "@baseboard_fab2_lib.baseboard_fab2(sch_1):page31_i106:pe2_tx_dp(12)" )
			)
			( pin "U5D1.BN4"
				( objectStatus "@baseboard_fab2_lib.baseboard_fab2(sch_1):page31_i106:pe2_tx_dp(13)" )
			)
			( pin "U5D1.BM3"
				( objectStatus "@baseboard_fab2_lib.baseboard_fab2(sch_1):page31_i106:pe2_tx_dp(14)" )
			)
			( pin "U5D1.BK5"
				( objectStatus "@baseboard_fab2_lib.baseboard_fab2(sch_1):page31_i106:pe2_tx_dp(15)" )
			)
			( pin "U5D1.EA18"
				( objectStatus "@baseboard_fab2_lib.baseboard_fab2(sch_1):page32_i89:pe3_rx_dn(0)" )
			)
			( pin "U5D1.DW18"
				( objectStatus "@baseboard_fab2_lib.baseboard_fab2(sch_1):page32_i89:pe3_rx_dn(1)" )
			)
			( pin "U5D1.DW16"
				( objectStatus "@baseboard_fab2_lib.baseboard_fab2(sch_1):page32_i89:pe3_rx_dn(2)" )
			)
			( pin "U5D1.DT19"
				( objectStatus "@baseboard_fab2_lib.baseboard_fab2(sch_1):page32_i89:pe3_rx_dn(3)" )
			)
			( pin "U5D1.DR16"
				( objectStatus "@baseboard_fab2_lib.baseboard_fab2(sch_1):page32_i89:pe3_rx_dn(4)" )
			)
			( pin "U5D1.DR14"
				( objectStatus "@baseboard_fab2_lib.baseboard_fab2(sch_1):page32_i89:pe3_rx_dn(5)" )
			)
			( pin "U5D1.DN14"
				( objectStatus "@baseboard_fab2_lib.baseboard_fab2(sch_1):page32_i89:pe3_rx_dn(6)" )
			)
			( pin "U5D1.DL14"
				( objectStatus "@baseboard_fab2_lib.baseboard_fab2(sch_1):page32_i89:pe3_rx_dn(7)" )
			)
			( pin "U5D1.DL12"
				( objectStatus "@baseboard_fab2_lib.baseboard_fab2(sch_1):page32_i89:pe3_rx_dn(8)" )
			)
			( pin "U5D1.DJ12"
				( objectStatus "@baseboard_fab2_lib.baseboard_fab2(sch_1):page32_i89:pe3_rx_dn(9)" )
			)
			( pin "U5D1.DG12"
				( objectStatus "@baseboard_fab2_lib.baseboard_fab2(sch_1):page32_i89:pe3_rx_dn(10)" )
			)
			( pin "U5D1.DG10"
				( objectStatus "@baseboard_fab2_lib.baseboard_fab2(sch_1):page32_i89:pe3_rx_dn(11)" )
			)
			( pin "U5D1.DD13"
				( objectStatus "@baseboard_fab2_lib.baseboard_fab2(sch_1):page32_i89:pe3_rx_dn(12)" )
			)
			( pin "U5D1.DB11"
				( objectStatus "@baseboard_fab2_lib.baseboard_fab2(sch_1):page32_i89:pe3_rx_dn(13)" )
			)
			( pin "U5D1.CY11"
				( objectStatus "@baseboard_fab2_lib.baseboard_fab2(sch_1):page32_i89:pe3_rx_dn(14)" )
			)
			( pin "U5D1.CV9"
				( objectStatus "@baseboard_fab2_lib.baseboard_fab2(sch_1):page32_i89:pe3_rx_dn(15)" )
			)
			( pin "U5D1.DY17"
				( objectStatus "@baseboard_fab2_lib.baseboard_fab2(sch_1):page32_i89:pe3_rx_dp(0)" )
			)
			( pin "U5D1.DU18"
				( objectStatus "@baseboard_fab2_lib.baseboard_fab2(sch_1):page32_i89:pe3_rx_dp(1)" )
			)
			( pin "U5D1.DV17"
				( objectStatus "@baseboard_fab2_lib.baseboard_fab2(sch_1):page32_i89:pe3_rx_dp(2)" )
			)
			( pin "U5D1.DR18"
				( objectStatus "@baseboard_fab2_lib.baseboard_fab2(sch_1):page32_i89:pe3_rx_dp(3)" )
			)
			( pin "U5D1.DN16"
				( objectStatus "@baseboard_fab2_lib.baseboard_fab2(sch_1):page32_i89:pe3_rx_dp(4)" )
			)
			( pin "U5D1.DP15"
				( objectStatus "@baseboard_fab2_lib.baseboard_fab2(sch_1):page32_i89:pe3_rx_dp(5)" )
			)
			( pin "U5D1.DM13"
				( objectStatus "@baseboard_fab2_lib.baseboard_fab2(sch_1):page32_i89:pe3_rx_dp(6)" )
			)
			( pin "U5D1.DJ14"
				( objectStatus "@baseboard_fab2_lib.baseboard_fab2(sch_1):page32_i89:pe3_rx_dp(7)" )
			)
			( pin "U5D1.DK13"
				( objectStatus "@baseboard_fab2_lib.baseboard_fab2(sch_1):page32_i89:pe3_rx_dp(8)" )
			)
			( pin "U5D1.DH11"
				( objectStatus "@baseboard_fab2_lib.baseboard_fab2(sch_1):page32_i89:pe3_rx_dp(9)" )
			)
			( pin "U5D1.DE12"
				( objectStatus "@baseboard_fab2_lib.baseboard_fab2(sch_1):page32_i89:pe3_rx_dp(10)" )
			)
			( pin "U5D1.DF11"
				( objectStatus "@baseboard_fab2_lib.baseboard_fab2(sch_1):page32_i89:pe3_rx_dp(11)" )
			)
			( pin "U5D1.DC12"
				( objectStatus "@baseboard_fab2_lib.baseboard_fab2(sch_1):page32_i89:pe3_rx_dp(12)" )
			)
			( pin "U5D1.DA12"
				( objectStatus "@baseboard_fab2_lib.baseboard_fab2(sch_1):page32_i89:pe3_rx_dp(13)" )
			)
			( pin "U5D1.CW10"
				( objectStatus "@baseboard_fab2_lib.baseboard_fab2(sch_1):page32_i89:pe3_rx_dp(14)" )
			)
			( pin "U5D1.CU10"
				( objectStatus "@baseboard_fab2_lib.baseboard_fab2(sch_1):page32_i89:pe3_rx_dp(15)" )
			)
			( pin "U5D1.EE14"
				( objectStatus "@baseboard_fab2_lib.baseboard_fab2(sch_1):page32_i89:pe3_tx_dn(0)" )
			)
			( pin "U5D1.EE12"
				( objectStatus "@baseboard_fab2_lib.baseboard_fab2(sch_1):page32_i89:pe3_tx_dn(1)" )
			)
			( pin "U5D1.EC12"
				( objectStatus "@baseboard_fab2_lib.baseboard_fab2(sch_1):page32_i89:pe3_tx_dn(2)" )
			)
			( pin "U5D1.DY11"
				( objectStatus "@baseboard_fab2_lib.baseboard_fab2(sch_1):page32_i89:pe3_tx_dn(3)" )
			)
			( pin "U5D1.EB9"
				( objectStatus "@baseboard_fab2_lib.baseboard_fab2(sch_1):page32_i89:pe3_tx_dn(4)" )
			)
			( pin "U5D1.DW10"
				( objectStatus "@baseboard_fab2_lib.baseboard_fab2(sch_1):page32_i89:pe3_tx_dn(5)" )
			)
			( pin "U5D1.DU8"
				( objectStatus "@baseboard_fab2_lib.baseboard_fab2(sch_1):page32_i89:pe3_tx_dn(6)" )
			)
			( pin "U5D1.DR8"
				( objectStatus "@baseboard_fab2_lib.baseboard_fab2(sch_1):page32_i89:pe3_tx_dn(7)" )
			)
			( pin "U5D1.DM7"
				( objectStatus "@baseboard_fab2_lib.baseboard_fab2(sch_1):page32_i89:pe3_tx_dn(8)" )
			)
			( pin "U5D1.DP5"
				( objectStatus "@baseboard_fab2_lib.baseboard_fab2(sch_1):page32_i89:pe3_tx_dn(9)" )
			)
			( pin "U5D1.DL6"
				( objectStatus "@baseboard_fab2_lib.baseboard_fab2(sch_1):page32_i89:pe3_tx_dn(10)" )
			)
			( pin "U5D1.DJ4"
				( objectStatus "@baseboard_fab2_lib.baseboard_fab2(sch_1):page32_i89:pe3_tx_dn(11)" )
			)
			( pin "U5D1.DJ6"
				( objectStatus "@baseboard_fab2_lib.baseboard_fab2(sch_1):page32_i89:pe3_tx_dn(12)" )
			)
			( pin "U5D1.DD5"
				( objectStatus "@baseboard_fab2_lib.baseboard_fab2(sch_1):page32_i89:pe3_tx_dn(13)" )
			)
			( pin "U5D1.DB5"
				( objectStatus "@baseboard_fab2_lib.baseboard_fab2(sch_1):page32_i89:pe3_tx_dn(14)" )
			)
			( pin "U5D1.CY5"
				( objectStatus "@baseboard_fab2_lib.baseboard_fab2(sch_1):page32_i89:pe3_tx_dn(15)" )
			)
			( pin "U5D1.EC14"
				( objectStatus "@baseboard_fab2_lib.baseboard_fab2(sch_1):page32_i89:pe3_tx_dp(0)" )
			)
			( pin "U5D1.ED13"
				( objectStatus "@baseboard_fab2_lib.baseboard_fab2(sch_1):page32_i89:pe3_tx_dp(1)" )
			)
			( pin "U5D1.EB11"
				( objectStatus "@baseboard_fab2_lib.baseboard_fab2(sch_1):page32_i89:pe3_tx_dp(2)" )
			)
			( pin "U5D1.EA10"
				( objectStatus "@baseboard_fab2_lib.baseboard_fab2(sch_1):page32_i89:pe3_tx_dp(3)" )
			)
			( pin "U5D1.DY9"
				( objectStatus "@baseboard_fab2_lib.baseboard_fab2(sch_1):page32_i89:pe3_tx_dp(4)" )
			)
			( pin "U5D1.DV9"
				( objectStatus "@baseboard_fab2_lib.baseboard_fab2(sch_1):page32_i89:pe3_tx_dp(5)" )
			)
			( pin "U5D1.DT9"
				( objectStatus "@baseboard_fab2_lib.baseboard_fab2(sch_1):page32_i89:pe3_tx_dp(6)" )
			)
			( pin "U5D1.DP7"
				( objectStatus "@baseboard_fab2_lib.baseboard_fab2(sch_1):page32_i89:pe3_tx_dp(7)" )
			)
			( pin "U5D1.DN6"
				( objectStatus "@baseboard_fab2_lib.baseboard_fab2(sch_1):page32_i89:pe3_tx_dp(8)" )
			)
			( pin "U5D1.DM5"
				( objectStatus "@baseboard_fab2_lib.baseboard_fab2(sch_1):page32_i89:pe3_tx_dp(9)" )
			)
			( pin "U5D1.DK5"
				( objectStatus "@baseboard_fab2_lib.baseboard_fab2(sch_1):page32_i89:pe3_tx_dp(10)" )
			)
			( pin "U5D1.DH5"
				( objectStatus "@baseboard_fab2_lib.baseboard_fab2(sch_1):page32_i89:pe3_tx_dp(11)" )
			)
			( pin "U5D1.DG6"
				( objectStatus "@baseboard_fab2_lib.baseboard_fab2(sch_1):page32_i89:pe3_tx_dp(12)" )
			)
			( pin "U5D1.DC6"
				( objectStatus "@baseboard_fab2_lib.baseboard_fab2(sch_1):page32_i89:pe3_tx_dp(13)" )
			)
			( pin "U5D1.DA4"
				( objectStatus "@baseboard_fab2_lib.baseboard_fab2(sch_1):page32_i89:pe3_tx_dp(14)" )
			)
			( pin "U5D1.CV5"
				( objectStatus "@baseboard_fab2_lib.baseboard_fab2(sch_1):page32_i89:pe3_tx_dp(15)" )
			)
			( pin "U5D1.AC10"
				( objectStatus "@baseboard_fab2_lib.baseboard_fab2(sch_1):page33_i86:upi0_rx_dn(0)" )
			)
			( pin "U5D1.AA8"
				( objectStatus "@baseboard_fab2_lib.baseboard_fab2(sch_1):page33_i86:upi0_rx_dn(1)" )
			)
			( pin "U5D1.AB7"
				( objectStatus "@baseboard_fab2_lib.baseboard_fab2(sch_1):page33_i86:upi0_rx_dn(2)" )
			)
			( pin "U5D1.AD5"
				( objectStatus "@baseboard_fab2_lib.baseboard_fab2(sch_1):page33_i86:upi0_rx_dn(3)" )
			)
			( pin "U5D1.AE6"
				( objectStatus "@baseboard_fab2_lib.baseboard_fab2(sch_1):page33_i86:upi0_rx_dn(4)" )
			)
			( pin "U5D1.AG8"
				( objectStatus "@baseboard_fab2_lib.baseboard_fab2(sch_1):page33_i86:upi0_rx_dn(5)" )
			)
			( pin "U5D1.AJ6"
				( objectStatus "@baseboard_fab2_lib.baseboard_fab2(sch_1):page33_i86:upi0_rx_dn(6)" )
			)
			( pin "U5D1.AL6"
				( objectStatus "@baseboard_fab2_lib.baseboard_fab2(sch_1):page33_i86:upi0_rx_dn(7)" )
			)
			( pin "U5D1.AK7"
				( objectStatus "@baseboard_fab2_lib.baseboard_fab2(sch_1):page33_i86:upi0_rx_dn(8)" )
			)
			( pin "U5D1.AM9"
				( objectStatus "@baseboard_fab2_lib.baseboard_fab2(sch_1):page33_i86:upi0_rx_dn(9)" )
			)
			( pin "U5D1.AP7"
				( objectStatus "@baseboard_fab2_lib.baseboard_fab2(sch_1):page33_i86:upi0_rx_dn(10)" )
			)
			( pin "U5D1.AR8"
				( objectStatus "@baseboard_fab2_lib.baseboard_fab2(sch_1):page33_i86:upi0_rx_dn(11)" )
			)
			( pin "U5D1.AU10"
				( objectStatus "@baseboard_fab2_lib.baseboard_fab2(sch_1):page33_i86:upi0_rx_dn(12)" )
			)
			( pin "U5D1.BA8"
				( objectStatus "@baseboard_fab2_lib.baseboard_fab2(sch_1):page33_i86:upi0_rx_dn(13)" )
			)
			( pin "U5D1.BC6"
				( objectStatus "@baseboard_fab2_lib.baseboard_fab2(sch_1):page33_i86:upi0_rx_dn(14)" )
			)
			( pin "U5D1.BD7"
				( objectStatus "@baseboard_fab2_lib.baseboard_fab2(sch_1):page33_i86:upi0_rx_dn(15)" )
			)
			( pin "U5D1.AW8"
				( objectStatus "@baseboard_fab2_lib.baseboard_fab2(sch_1):page33_i86:upi0_rx_dn(16)" )
			)
			( pin "U5D1.AY9"
				( objectStatus "@baseboard_fab2_lib.baseboard_fab2(sch_1):page33_i86:upi0_rx_dn(17)" )
			)
			( pin "U5D1.BD9"
				( objectStatus "@baseboard_fab2_lib.baseboard_fab2(sch_1):page33_i86:upi0_rx_dn(18)" )
			)
			( pin "U5D1.BB11"
				( objectStatus "@baseboard_fab2_lib.baseboard_fab2(sch_1):page33_i86:upi0_rx_dn(19)" )
			)
			( pin "U5D1.AB9"
				( objectStatus "@baseboard_fab2_lib.baseboard_fab2(sch_1):page33_i86:upi0_rx_dp(0)" )
			)
			( pin "U5D1.AC8"
				( objectStatus "@baseboard_fab2_lib.baseboard_fab2(sch_1):page33_i86:upi0_rx_dp(1)" )
			)
			( pin "U5D1.AA6"
				( objectStatus "@baseboard_fab2_lib.baseboard_fab2(sch_1):page33_i86:upi0_rx_dp(2)" )
			)
			( pin "U5D1.AC6"
				( objectStatus "@baseboard_fab2_lib.baseboard_fab2(sch_1):page33_i86:upi0_rx_dp(3)" )
			)
			( pin "U5D1.AG6"
				( objectStatus "@baseboard_fab2_lib.baseboard_fab2(sch_1):page33_i86:upi0_rx_dp(4)" )
			)
			( pin "U5D1.AF7"
				( objectStatus "@baseboard_fab2_lib.baseboard_fab2(sch_1):page33_i86:upi0_rx_dp(5)" )
			)
			( pin "U5D1.AH7"
				( objectStatus "@baseboard_fab2_lib.baseboard_fab2(sch_1):page33_i86:upi0_rx_dp(6)" )
			)
			( pin "U5D1.AK5"
				( objectStatus "@baseboard_fab2_lib.baseboard_fab2(sch_1):page33_i86:upi0_rx_dp(7)" )
			)
			( pin "U5D1.AM7"
				( objectStatus "@baseboard_fab2_lib.baseboard_fab2(sch_1):page33_i86:upi0_rx_dp(8)" )
			)
			( pin "U5D1.AL8"
				( objectStatus "@baseboard_fab2_lib.baseboard_fab2(sch_1):page33_i86:upi0_rx_dp(9)" )
			)
			( pin "U5D1.AN8"
				( objectStatus "@baseboard_fab2_lib.baseboard_fab2(sch_1):page33_i86:upi0_rx_dp(10)" )
			)
			( pin "U5D1.AU8"
				( objectStatus "@baseboard_fab2_lib.baseboard_fab2(sch_1):page33_i86:upi0_rx_dp(11)" )
			)
			( pin "U5D1.AT9"
				( objectStatus "@baseboard_fab2_lib.baseboard_fab2(sch_1):page33_i86:upi0_rx_dp(12)" )
			)
			( pin "U5D1.AY7"
				( objectStatus "@baseboard_fab2_lib.baseboard_fab2(sch_1):page33_i86:upi0_rx_dp(13)" )
			)
			( pin "U5D1.BB7"
				( objectStatus "@baseboard_fab2_lib.baseboard_fab2(sch_1):page33_i86:upi0_rx_dp(14)" )
			)
			( pin "U5D1.BF7"
				( objectStatus "@baseboard_fab2_lib.baseboard_fab2(sch_1):page33_i86:upi0_rx_dp(15)" )
			)
			( pin "U5D1.AV9"
				( objectStatus "@baseboard_fab2_lib.baseboard_fab2(sch_1):page33_i86:upi0_rx_dp(16)" )
			)
			( pin "U5D1.BB9"
				( objectStatus "@baseboard_fab2_lib.baseboard_fab2(sch_1):page33_i86:upi0_rx_dp(17)" )
			)
			( pin "U5D1.BC10"
				( objectStatus "@baseboard_fab2_lib.baseboard_fab2(sch_1):page33_i86:upi0_rx_dp(18)" )
			)
			( pin "U5D1.BA10"
				( objectStatus "@baseboard_fab2_lib.baseboard_fab2(sch_1):page33_i86:upi0_rx_dp(19)" )
			)
			( pin "U5D1.N2"
				( objectStatus "@baseboard_fab2_lib.baseboard_fab2(sch_1):page33_i86:upi0_tx_dn(0)" )
			)
			( pin "U5D1.P1"
				( objectStatus "@baseboard_fab2_lib.baseboard_fab2(sch_1):page33_i86:upi0_tx_dn(1)" )
			)
			( pin "U5D1.V3"
				( objectStatus "@baseboard_fab2_lib.baseboard_fab2(sch_1):page33_i86:upi0_tx_dn(2)" )
			)
			( pin "U5D1.Y1"
				( objectStatus "@baseboard_fab2_lib.baseboard_fab2(sch_1):page33_i86:upi0_tx_dn(3)" )
			)
			( pin "U5D1.AB3"
				( objectStatus "@baseboard_fab2_lib.baseboard_fab2(sch_1):page33_i86:upi0_tx_dn(4)" )
			)
			( pin "U5D1.AC2"
				( objectStatus "@baseboard_fab2_lib.baseboard_fab2(sch_1):page33_i86:upi0_tx_dn(5)" )
			)
			( pin "U5D1.AG4"
				( objectStatus "@baseboard_fab2_lib.baseboard_fab2(sch_1):page33_i86:upi0_tx_dn(6)" )
			)
			( pin "U5D1.AE2"
				( objectStatus "@baseboard_fab2_lib.baseboard_fab2(sch_1):page33_i86:upi0_tx_dn(7)" )
			)
			( pin "U5D1.AH3"
				( objectStatus "@baseboard_fab2_lib.baseboard_fab2(sch_1):page33_i86:upi0_tx_dn(8)" )
			)
			( pin "U5D1.AL2"
				( objectStatus "@baseboard_fab2_lib.baseboard_fab2(sch_1):page33_i86:upi0_tx_dn(9)" )
			)
			( pin "U5D1.AM3"
				( objectStatus "@baseboard_fab2_lib.baseboard_fab2(sch_1):page33_i86:upi0_tx_dn(10)" )
			)
			( pin "U5D1.AN4"
				( objectStatus "@baseboard_fab2_lib.baseboard_fab2(sch_1):page33_i86:upi0_tx_dn(11)" )
			)
			( pin "U5D1.AT1"
				( objectStatus "@baseboard_fab2_lib.baseboard_fab2(sch_1):page33_i86:upi0_tx_dn(12)" )
			)
			( pin "U5D1.AT3"
				( objectStatus "@baseboard_fab2_lib.baseboard_fab2(sch_1):page33_i86:upi0_tx_dn(13)" )
			)
			( pin "U5D1.AU4"
				( objectStatus "@baseboard_fab2_lib.baseboard_fab2(sch_1):page33_i86:upi0_tx_dn(14)" )
			)
			( pin "U5D1.AV5"
				( objectStatus "@baseboard_fab2_lib.baseboard_fab2(sch_1):page33_i86:upi0_tx_dn(15)" )
			)
			( pin "U5D1.BA4"
				( objectStatus "@baseboard_fab2_lib.baseboard_fab2(sch_1):page33_i86:upi0_tx_dn(16)" )
			)
			( pin "U5D1.BB3"
				( objectStatus "@baseboard_fab2_lib.baseboard_fab2(sch_1):page33_i86:upi0_tx_dn(17)" )
			)
			( pin "U5D1.BF3"
				( objectStatus "@baseboard_fab2_lib.baseboard_fab2(sch_1):page33_i86:upi0_tx_dn(18)" )
			)
			( pin "U5D1.BG4"
				( objectStatus "@baseboard_fab2_lib.baseboard_fab2(sch_1):page33_i86:upi0_tx_dn(19)" )
			)
			( pin "U5D1.M1"
				( objectStatus "@baseboard_fab2_lib.baseboard_fab2(sch_1):page33_i86:upi0_tx_dp(0)" )
			)
			( pin "U5D1.T1"
				( objectStatus "@baseboard_fab2_lib.baseboard_fab2(sch_1):page33_i86:upi0_tx_dp(1)" )
			)
			( pin "U5D1.Y3"
				( objectStatus "@baseboard_fab2_lib.baseboard_fab2(sch_1):page33_i86:upi0_tx_dp(2)" )
			)
			( pin "U5D1.W2"
				( objectStatus "@baseboard_fab2_lib.baseboard_fab2(sch_1):page33_i86:upi0_tx_dp(3)" )
			)
			( pin "U5D1.AA2"
				( objectStatus "@baseboard_fab2_lib.baseboard_fab2(sch_1):page33_i86:upi0_tx_dp(4)" )
			)
			( pin "U5D1.AD1"
				( objectStatus "@baseboard_fab2_lib.baseboard_fab2(sch_1):page33_i86:upi0_tx_dp(5)" )
			)
			( pin "U5D1.AF3"
				( objectStatus "@baseboard_fab2_lib.baseboard_fab2(sch_1):page33_i86:upi0_tx_dp(6)" )
			)
			( pin "U5D1.AG2"
				( objectStatus "@baseboard_fab2_lib.baseboard_fab2(sch_1):page33_i86:upi0_tx_dp(7)" )
			)
			( pin "U5D1.AJ2"
				( objectStatus "@baseboard_fab2_lib.baseboard_fab2(sch_1):page33_i86:upi0_tx_dp(8)" )
			)
			( pin "U5D1.AK1"
				( objectStatus "@baseboard_fab2_lib.baseboard_fab2(sch_1):page33_i86:upi0_tx_dp(9)" )
			)
			( pin "U5D1.AK3"
				( objectStatus "@baseboard_fab2_lib.baseboard_fab2(sch_1):page33_i86:upi0_tx_dp(10)" )
			)
			( pin "U5D1.AP3"
				( objectStatus "@baseboard_fab2_lib.baseboard_fab2(sch_1):page33_i86:upi0_tx_dp(11)" )
			)
			( pin "U5D1.AP1"
				( objectStatus "@baseboard_fab2_lib.baseboard_fab2(sch_1):page33_i86:upi0_tx_dp(12)" )
			)
			( pin "U5D1.AR2"
				( objectStatus "@baseboard_fab2_lib.baseboard_fab2(sch_1):page33_i86:upi0_tx_dp(13)" )
			)
			( pin "U5D1.AR4"
				( objectStatus "@baseboard_fab2_lib.baseboard_fab2(sch_1):page33_i86:upi0_tx_dp(14)" )
			)
			( pin "U5D1.AW4"
				( objectStatus "@baseboard_fab2_lib.baseboard_fab2(sch_1):page33_i86:upi0_tx_dp(15)" )
			)
			( pin "U5D1.AY3"
				( objectStatus "@baseboard_fab2_lib.baseboard_fab2(sch_1):page33_i86:upi0_tx_dp(16)" )
			)
			( pin "U5D1.BC2"
				( objectStatus "@baseboard_fab2_lib.baseboard_fab2(sch_1):page33_i86:upi0_tx_dp(17)" )
			)
			( pin "U5D1.BD3"
				( objectStatus "@baseboard_fab2_lib.baseboard_fab2(sch_1):page33_i86:upi0_tx_dp(18)" )
			)
			( pin "U5D1.BH3"
				( objectStatus "@baseboard_fab2_lib.baseboard_fab2(sch_1):page33_i86:upi0_tx_dp(19)" )
			)
			( pin "U5D1.T5"
				( objectStatus "@baseboard_fab2_lib.baseboard_fab2(sch_1):page34_i86:upi1_rx_dn(0)" )
			)
			( pin "U5D1.P7"
				( objectStatus "@baseboard_fab2_lib.baseboard_fab2(sch_1):page34_i86:upi1_rx_dn(1)" )
			)
			( pin "U5D1.V7"
				( objectStatus "@baseboard_fab2_lib.baseboard_fab2(sch_1):page34_i86:upi1_rx_dn(2)" )
			)
			( pin "U5D1.T9"
				( objectStatus "@baseboard_fab2_lib.baseboard_fab2(sch_1):page34_i86:upi1_rx_dn(3)" )
			)
			( pin "U5D1.P9"
				( objectStatus "@baseboard_fab2_lib.baseboard_fab2(sch_1):page34_i86:upi1_rx_dn(4)" )
			)
			( pin "U5D1.R10"
				( objectStatus "@baseboard_fab2_lib.baseboard_fab2(sch_1):page34_i86:upi1_rx_dn(5)" )
			)
			( pin "U5D1.U12"
				( objectStatus "@baseboard_fab2_lib.baseboard_fab2(sch_1):page34_i86:upi1_rx_dn(6)" )
			)
			( pin "U5D1.L12"
				( objectStatus "@baseboard_fab2_lib.baseboard_fab2(sch_1):page34_i86:upi1_rx_dn(7)" )
			)
			( pin "U5D1.N14"
				( objectStatus "@baseboard_fab2_lib.baseboard_fab2(sch_1):page34_i86:upi1_rx_dn(8)" )
			)
			( pin "U5D1.R12"
				( objectStatus "@baseboard_fab2_lib.baseboard_fab2(sch_1):page34_i86:upi1_rx_dn(9)" )
			)
			( pin "U5D1.R16"
				( objectStatus "@baseboard_fab2_lib.baseboard_fab2(sch_1):page34_i86:upi1_rx_dn(10)" )
			)
			( pin "U5D1.P17"
				( objectStatus "@baseboard_fab2_lib.baseboard_fab2(sch_1):page34_i86:upi1_rx_dn(11)" )
			)
			( pin "U5D1.U16"
				( objectStatus "@baseboard_fab2_lib.baseboard_fab2(sch_1):page34_i86:upi1_rx_dn(12)" )
			)
			( pin "U5D1.W18"
				( objectStatus "@baseboard_fab2_lib.baseboard_fab2(sch_1):page34_i86:upi1_rx_dn(13)" )
			)
			( pin "U5D1.R20"
				( objectStatus "@baseboard_fab2_lib.baseboard_fab2(sch_1):page34_i86:upi1_rx_dn(14)" )
			)
			( pin "U5D1.U18"
				( objectStatus "@baseboard_fab2_lib.baseboard_fab2(sch_1):page34_i86:upi1_rx_dn(15)" )
			)
			( pin "U5D1.P21"
				( objectStatus "@baseboard_fab2_lib.baseboard_fab2(sch_1):page34_i86:upi1_rx_dn(16)" )
			)
			( pin "U5D1.V19"
				( objectStatus "@baseboard_fab2_lib.baseboard_fab2(sch_1):page34_i86:upi1_rx_dn(17)" )
			)
			( pin "U5D1.Y21"
				( objectStatus "@baseboard_fab2_lib.baseboard_fab2(sch_1):page34_i86:upi1_rx_dn(18)" )
			)
			( pin "U5D1.AB19"
				( objectStatus "@baseboard_fab2_lib.baseboard_fab2(sch_1):page34_i86:upi1_rx_dn(19)" )
			)
			( pin "U5D1.R6"
				( objectStatus "@baseboard_fab2_lib.baseboard_fab2(sch_1):page34_i86:upi1_rx_dp(0)" )
			)
			( pin "U5D1.T7"
				( objectStatus "@baseboard_fab2_lib.baseboard_fab2(sch_1):page34_i86:upi1_rx_dp(1)" )
			)
			( pin "U5D1.U8"
				( objectStatus "@baseboard_fab2_lib.baseboard_fab2(sch_1):page34_i86:upi1_rx_dp(2)" )
			)
			( pin "U5D1.R8"
				( objectStatus "@baseboard_fab2_lib.baseboard_fab2(sch_1):page34_i86:upi1_rx_dp(3)" )
			)
			( pin "U5D1.N10"
				( objectStatus "@baseboard_fab2_lib.baseboard_fab2(sch_1):page34_i86:upi1_rx_dp(4)" )
			)
			( pin "U5D1.U10"
				( objectStatus "@baseboard_fab2_lib.baseboard_fab2(sch_1):page34_i86:upi1_rx_dp(5)" )
			)
			( pin "U5D1.T11"
				( objectStatus "@baseboard_fab2_lib.baseboard_fab2(sch_1):page34_i86:upi1_rx_dp(6)" )
			)
			( pin "U5D1.N12"
				( objectStatus "@baseboard_fab2_lib.baseboard_fab2(sch_1):page34_i86:upi1_rx_dp(7)" )
			)
			( pin "U5D1.M13"
				( objectStatus "@baseboard_fab2_lib.baseboard_fab2(sch_1):page34_i86:upi1_rx_dp(8)" )
			)
			( pin "U5D1.P13"
				( objectStatus "@baseboard_fab2_lib.baseboard_fab2(sch_1):page34_i86:upi1_rx_dp(9)" )
			)
			( pin "U5D1.T15"
				( objectStatus "@baseboard_fab2_lib.baseboard_fab2(sch_1):page34_i86:upi1_rx_dp(10)" )
			)
			( pin "U5D1.N16"
				( objectStatus "@baseboard_fab2_lib.baseboard_fab2(sch_1):page34_i86:upi1_rx_dp(11)" )
			)
			( pin "U5D1.W16"
				( objectStatus "@baseboard_fab2_lib.baseboard_fab2(sch_1):page34_i86:upi1_rx_dp(12)" )
			)
			( pin "U5D1.V17"
				( objectStatus "@baseboard_fab2_lib.baseboard_fab2(sch_1):page34_i86:upi1_rx_dp(13)" )
			)
			( pin "U5D1.P19"
				( objectStatus "@baseboard_fab2_lib.baseboard_fab2(sch_1):page34_i86:upi1_rx_dp(14)" )
			)
			( pin "U5D1.T19"
				( objectStatus "@baseboard_fab2_lib.baseboard_fab2(sch_1):page34_i86:upi1_rx_dp(15)" )
			)
			( pin "U5D1.T21"
				( objectStatus "@baseboard_fab2_lib.baseboard_fab2(sch_1):page34_i86:upi1_rx_dp(16)" )
			)
			( pin "U5D1.Y19"
				( objectStatus "@baseboard_fab2_lib.baseboard_fab2(sch_1):page34_i86:upi1_rx_dp(17)" )
			)
			( pin "U5D1.W20"
				( objectStatus "@baseboard_fab2_lib.baseboard_fab2(sch_1):page34_i86:upi1_rx_dp(18)" )
			)
			( pin "U5D1.AA20"
				( objectStatus "@baseboard_fab2_lib.baseboard_fab2(sch_1):page34_i86:upi1_rx_dp(19)" )
			)
			( pin "U5D1.M3"
				( objectStatus "@baseboard_fab2_lib.baseboard_fab2(sch_1):page34_i86:upi1_tx_dn(0)" )
			)
			( pin "U5D1.L4"
				( objectStatus "@baseboard_fab2_lib.baseboard_fab2(sch_1):page34_i86:upi1_tx_dn(1)" )
			)
			( pin "U5D1.K5"
				( objectStatus "@baseboard_fab2_lib.baseboard_fab2(sch_1):page34_i86:upi1_tx_dn(2)" )
			)
			( pin "U5D1.J6"
				( objectStatus "@baseboard_fab2_lib.baseboard_fab2(sch_1):page34_i86:upi1_tx_dn(3)" )
			)
			( pin "U5D1.G6"
				( objectStatus "@baseboard_fab2_lib.baseboard_fab2(sch_1):page34_i86:upi1_tx_dn(4)" )
			)
			( pin "U5D1.H7"
				( objectStatus "@baseboard_fab2_lib.baseboard_fab2(sch_1):page34_i86:upi1_tx_dn(5)" )
			)
			( pin "U5D1.K9"
				( objectStatus "@baseboard_fab2_lib.baseboard_fab2(sch_1):page34_i86:upi1_tx_dn(6)" )
			)
			( pin "U5D1.D9"
				( objectStatus "@baseboard_fab2_lib.baseboard_fab2(sch_1):page34_i86:upi1_tx_dn(7)" )
			)
			( pin "U5D1.F11"
				( objectStatus "@baseboard_fab2_lib.baseboard_fab2(sch_1):page34_i86:upi1_tx_dn(8)" )
			)
			( pin "U5D1.G10"
				( objectStatus "@baseboard_fab2_lib.baseboard_fab2(sch_1):page34_i86:upi1_tx_dn(9)" )
			)
			( pin "U5D1.E12"
				( objectStatus "@baseboard_fab2_lib.baseboard_fab2(sch_1):page34_i86:upi1_tx_dn(10)" )
			)
			( pin "U5D1.G14"
				( objectStatus "@baseboard_fab2_lib.baseboard_fab2(sch_1):page34_i86:upi1_tx_dn(11)" )
			)
			( pin "U5D1.D15"
				( objectStatus "@baseboard_fab2_lib.baseboard_fab2(sch_1):page34_i86:upi1_tx_dn(12)" )
			)
			( pin "U5D1.F15"
				( objectStatus "@baseboard_fab2_lib.baseboard_fab2(sch_1):page34_i86:upi1_tx_dn(13)" )
			)
			( pin "U5D1.H17"
				( objectStatus "@baseboard_fab2_lib.baseboard_fab2(sch_1):page34_i86:upi1_tx_dn(14)" )
			)
			( pin "U5D1.K19"
				( objectStatus "@baseboard_fab2_lib.baseboard_fab2(sch_1):page34_i86:upi1_tx_dn(15)" )
			)
			( pin "U5D1.G18"
				( objectStatus "@baseboard_fab2_lib.baseboard_fab2(sch_1):page34_i86:upi1_tx_dn(16)" )
			)
			( pin "U5D1.J20"
				( objectStatus "@baseboard_fab2_lib.baseboard_fab2(sch_1):page34_i86:upi1_tx_dn(17)" )
			)
			( pin "U5D1.F21"
				( objectStatus "@baseboard_fab2_lib.baseboard_fab2(sch_1):page34_i86:upi1_tx_dn(18)" )
			)
			( pin "U5D1.H21"
				( objectStatus "@baseboard_fab2_lib.baseboard_fab2(sch_1):page34_i86:upi1_tx_dn(19)" )
			)
			( pin "U5D1.P3"
				( objectStatus "@baseboard_fab2_lib.baseboard_fab2(sch_1):page34_i86:upi1_tx_dp(0)" )
			)
			( pin "U5D1.K3"
				( objectStatus "@baseboard_fab2_lib.baseboard_fab2(sch_1):page34_i86:upi1_tx_dp(1)" )
			)
			( pin "U5D1.M5"
				( objectStatus "@baseboard_fab2_lib.baseboard_fab2(sch_1):page34_i86:upi1_tx_dp(2)" )
			)
			( pin "U5D1.H5"
				( objectStatus "@baseboard_fab2_lib.baseboard_fab2(sch_1):page34_i86:upi1_tx_dp(3)" )
			)
			( pin "U5D1.F7"
				( objectStatus "@baseboard_fab2_lib.baseboard_fab2(sch_1):page34_i86:upi1_tx_dp(4)" )
			)
			( pin "U5D1.K7"
				( objectStatus "@baseboard_fab2_lib.baseboard_fab2(sch_1):page34_i86:upi1_tx_dp(5)" )
			)
			( pin "U5D1.J8"
				( objectStatus "@baseboard_fab2_lib.baseboard_fab2(sch_1):page34_i86:upi1_tx_dp(6)" )
			)
			( pin "U5D1.F9"
				( objectStatus "@baseboard_fab2_lib.baseboard_fab2(sch_1):page34_i86:upi1_tx_dp(7)" )
			)
			( pin "U5D1.E10"
				( objectStatus "@baseboard_fab2_lib.baseboard_fab2(sch_1):page34_i86:upi1_tx_dp(8)" )
			)
			( pin "U5D1.H9"
				( objectStatus "@baseboard_fab2_lib.baseboard_fab2(sch_1):page34_i86:upi1_tx_dp(9)" )
			)
			( pin "U5D1.G12"
				( objectStatus "@baseboard_fab2_lib.baseboard_fab2(sch_1):page34_i86:upi1_tx_dp(10)" )
			)
			( pin "U5D1.F13"
				( objectStatus "@baseboard_fab2_lib.baseboard_fab2(sch_1):page34_i86:upi1_tx_dp(11)" )
			)
			( pin "U5D1.E14"
				( objectStatus "@baseboard_fab2_lib.baseboard_fab2(sch_1):page34_i86:upi1_tx_dp(12)" )
			)
			( pin "U5D1.H15"
				( objectStatus "@baseboard_fab2_lib.baseboard_fab2(sch_1):page34_i86:upi1_tx_dp(13)" )
			)
			( pin "U5D1.G16"
				( objectStatus "@baseboard_fab2_lib.baseboard_fab2(sch_1):page34_i86:upi1_tx_dp(14)" )
			)
			( pin "U5D1.L18"
				( objectStatus "@baseboard_fab2_lib.baseboard_fab2(sch_1):page34_i86:upi1_tx_dp(15)" )
			)
			( pin "U5D1.J18"
				( objectStatus "@baseboard_fab2_lib.baseboard_fab2(sch_1):page34_i86:upi1_tx_dp(16)" )
			)
			( pin "U5D1.H19"
				( objectStatus "@baseboard_fab2_lib.baseboard_fab2(sch_1):page34_i86:upi1_tx_dp(17)" )
			)
			( pin "U5D1.G20"
				( objectStatus "@baseboard_fab2_lib.baseboard_fab2(sch_1):page34_i86:upi1_tx_dp(18)" )
			)
			( pin "U5D1.K21"
				( objectStatus "@baseboard_fab2_lib.baseboard_fab2(sch_1):page34_i86:upi1_tx_dp(19)" )
			)
			( pin "U5D1.DF23"
				( objectStatus "@baseboard_fab2_lib.baseboard_fab2(sch_1):page35_i3:upi2_rx_dn(0)" )
			)
			( pin "U5D1.DE22"
				( objectStatus "@baseboard_fab2_lib.baseboard_fab2(sch_1):page35_i3:upi2_rx_dn(1)" )
			)
			( pin "U5D1.DC22"
				( objectStatus "@baseboard_fab2_lib.baseboard_fab2(sch_1):page35_i3:upi2_rx_dn(2)" )
			)
			( pin "U5D1.DB21"
				( objectStatus "@baseboard_fab2_lib.baseboard_fab2(sch_1):page35_i3:upi2_rx_dn(3)" )
			)
			( pin "U5D1.DD19"
				( objectStatus "@baseboard_fab2_lib.baseboard_fab2(sch_1):page35_i3:upi2_rx_dn(4)" )
			)
			( pin "U5D1.DA20"
				( objectStatus "@baseboard_fab2_lib.baseboard_fab2(sch_1):page35_i3:upi2_rx_dn(5)" )
			)
			( pin "U5D1.CW20"
				( objectStatus "@baseboard_fab2_lib.baseboard_fab2(sch_1):page35_i3:upi2_rx_dn(6)" )
			)
			( pin "U5D1.CV19"
				( objectStatus "@baseboard_fab2_lib.baseboard_fab2(sch_1):page35_i3:upi2_rx_dn(7)" )
			)
			( pin "U5D1.CT21"
				( objectStatus "@baseboard_fab2_lib.baseboard_fab2(sch_1):page35_i3:upi2_rx_dn(8)" )
			)
			( pin "U5D1.CR18"
				( objectStatus "@baseboard_fab2_lib.baseboard_fab2(sch_1):page35_i3:upi2_rx_dn(9)" )
			)
			( pin "U5D1.CN20"
				( objectStatus "@baseboard_fab2_lib.baseboard_fab2(sch_1):page35_i3:upi2_rx_dn(10)" )
			)
			( pin "U5D1.CP21"
				( objectStatus "@baseboard_fab2_lib.baseboard_fab2(sch_1):page35_i3:upi2_rx_dn(11)" )
			)
			( pin "U5D1.CL16"
				( objectStatus "@baseboard_fab2_lib.baseboard_fab2(sch_1):page35_i3:upi2_rx_dn(12)" )
			)
			( pin "U5D1.CJ18"
				( objectStatus "@baseboard_fab2_lib.baseboard_fab2(sch_1):page35_i3:upi2_rx_dn(13)" )
			)
			( pin "U5D1.CH17"
				( objectStatus "@baseboard_fab2_lib.baseboard_fab2(sch_1):page35_i3:upi2_rx_dn(14)" )
			)
			( pin "U5D1.CE16"
				( objectStatus "@baseboard_fab2_lib.baseboard_fab2(sch_1):page35_i3:upi2_rx_dn(15)" )
			)
			( pin "U5D1.CD15"
				( objectStatus "@baseboard_fab2_lib.baseboard_fab2(sch_1):page35_i3:upi2_rx_dn(16)" )
			)
			( pin "U5D1.CF17"
				( objectStatus "@baseboard_fab2_lib.baseboard_fab2(sch_1):page35_i3:upi2_rx_dn(17)" )
			)
			( pin "U5D1.CB15"
				( objectStatus "@baseboard_fab2_lib.baseboard_fab2(sch_1):page35_i3:upi2_rx_dn(18)" )
			)
			( pin "U5D1.BY17"
				( objectStatus "@baseboard_fab2_lib.baseboard_fab2(sch_1):page35_i3:upi2_rx_dn(19)" )
			)
			( pin "U5D1.DG22"
				( objectStatus "@baseboard_fab2_lib.baseboard_fab2(sch_1):page35_i3:upi2_rx_dp(0)" )
			)
			( pin "U5D1.DD21"
				( objectStatus "@baseboard_fab2_lib.baseboard_fab2(sch_1):page35_i3:upi2_rx_dp(1)" )
			)
			( pin "U5D1.DA22"
				( objectStatus "@baseboard_fab2_lib.baseboard_fab2(sch_1):page35_i3:upi2_rx_dp(2)" )
			)
			( pin "U5D1.DC20"
				( objectStatus "@baseboard_fab2_lib.baseboard_fab2(sch_1):page35_i3:upi2_rx_dp(3)" )
			)
			( pin "U5D1.DB19"
				( objectStatus "@baseboard_fab2_lib.baseboard_fab2(sch_1):page35_i3:upi2_rx_dp(4)" )
			)
			( pin "U5D1.CY19"
				( objectStatus "@baseboard_fab2_lib.baseboard_fab2(sch_1):page35_i3:upi2_rx_dp(5)" )
			)
			( pin "U5D1.CU20"
				( objectStatus "@baseboard_fab2_lib.baseboard_fab2(sch_1):page35_i3:upi2_rx_dp(6)" )
			)
			( pin "U5D1.CW18"
				( objectStatus "@baseboard_fab2_lib.baseboard_fab2(sch_1):page35_i3:upi2_rx_dp(7)" )
			)
			( pin "U5D1.CR20"
				( objectStatus "@baseboard_fab2_lib.baseboard_fab2(sch_1):page35_i3:upi2_rx_dp(8)" )
			)
			( pin "U5D1.CN18"
				( objectStatus "@baseboard_fab2_lib.baseboard_fab2(sch_1):page35_i3:upi2_rx_dp(9)" )
			)
			( pin "U5D1.CP19"
				( objectStatus "@baseboard_fab2_lib.baseboard_fab2(sch_1):page35_i3:upi2_rx_dp(10)" )
			)
			( pin "U5D1.CM21"
				( objectStatus "@baseboard_fab2_lib.baseboard_fab2(sch_1):page35_i3:upi2_rx_dp(11)" )
			)
			( pin "U5D1.CJ16"
				( objectStatus "@baseboard_fab2_lib.baseboard_fab2(sch_1):page35_i3:upi2_rx_dp(12)" )
			)
			( pin "U5D1.CK17"
				( objectStatus "@baseboard_fab2_lib.baseboard_fab2(sch_1):page35_i3:upi2_rx_dp(13)" )
			)
			( pin "U5D1.CG16"
				( objectStatus "@baseboard_fab2_lib.baseboard_fab2(sch_1):page35_i3:upi2_rx_dp(14)" )
			)
			( pin "U5D1.CF15"
				( objectStatus "@baseboard_fab2_lib.baseboard_fab2(sch_1):page35_i3:upi2_rx_dp(15)" )
			)
			( pin "U5D1.CC14"
				( objectStatus "@baseboard_fab2_lib.baseboard_fab2(sch_1):page35_i3:upi2_rx_dp(16)" )
			)
			( pin "U5D1.CD17"
				( objectStatus "@baseboard_fab2_lib.baseboard_fab2(sch_1):page35_i3:upi2_rx_dp(17)" )
			)
			( pin "U5D1.BY15"
				( objectStatus "@baseboard_fab2_lib.baseboard_fab2(sch_1):page35_i3:upi2_rx_dp(18)" )
			)
			( pin "U5D1.CA16"
				( objectStatus "@baseboard_fab2_lib.baseboard_fab2(sch_1):page35_i3:upi2_rx_dp(19)" )
			)
			( pin "U5D1.DT21"
				( objectStatus "@baseboard_fab2_lib.baseboard_fab2(sch_1):page35_i3:upi2_tx_dn(0)" )
			)
			( pin "U5D1.DM21"
				( objectStatus "@baseboard_fab2_lib.baseboard_fab2(sch_1):page35_i3:upi2_tx_dn(1)" )
			)
			( pin "U5D1.DL20"
				( objectStatus "@baseboard_fab2_lib.baseboard_fab2(sch_1):page35_i3:upi2_tx_dn(2)" )
			)
			( pin "U5D1.DG20"
				( objectStatus "@baseboard_fab2_lib.baseboard_fab2(sch_1):page35_i3:upi2_tx_dn(3)" )
			)
			( pin "U5D1.DH19"
				( objectStatus "@baseboard_fab2_lib.baseboard_fab2(sch_1):page35_i3:upi2_tx_dn(4)" )
			)
			( pin "U5D1.DK17"
				( objectStatus "@baseboard_fab2_lib.baseboard_fab2(sch_1):page35_i3:upi2_tx_dn(5)" )
			)
			( pin "U5D1.DG18"
				( objectStatus "@baseboard_fab2_lib.baseboard_fab2(sch_1):page35_i3:upi2_tx_dn(6)" )
			)
			( pin "U5D1.DD17"
				( objectStatus "@baseboard_fab2_lib.baseboard_fab2(sch_1):page35_i3:upi2_tx_dn(7)" )
			)
			( pin "U5D1.DF15"
				( objectStatus "@baseboard_fab2_lib.baseboard_fab2(sch_1):page35_i3:upi2_tx_dn(8)" )
			)
			( pin "U5D1.DC16"
				( objectStatus "@baseboard_fab2_lib.baseboard_fab2(sch_1):page35_i3:upi2_tx_dn(9)" )
			)
			( pin "U5D1.DA16"
				( objectStatus "@baseboard_fab2_lib.baseboard_fab2(sch_1):page35_i3:upi2_tx_dn(10)" )
			)
			( pin "U5D1.CW14"
				( objectStatus "@baseboard_fab2_lib.baseboard_fab2(sch_1):page35_i3:upi2_tx_dn(11)" )
			)
			( pin "U5D1.CU14"
				( objectStatus "@baseboard_fab2_lib.baseboard_fab2(sch_1):page35_i3:upi2_tx_dn(12)" )
			)
			( pin "U5D1.CM13"
				( objectStatus "@baseboard_fab2_lib.baseboard_fab2(sch_1):page35_i3:upi2_tx_dn(13)" )
			)
			( pin "U5D1.CJ14"
				( objectStatus "@baseboard_fab2_lib.baseboard_fab2(sch_1):page35_i3:upi2_tx_dn(14)" )
			)
			( pin "U5D1.CF13"
				( objectStatus "@baseboard_fab2_lib.baseboard_fab2(sch_1):page35_i3:upi2_tx_dn(15)" )
			)
			( pin "U5D1.CH11"
				( objectStatus "@baseboard_fab2_lib.baseboard_fab2(sch_1):page35_i3:upi2_tx_dn(16)" )
			)
			( pin "U5D1.CE12"
				( objectStatus "@baseboard_fab2_lib.baseboard_fab2(sch_1):page35_i3:upi2_tx_dn(17)" )
			)
			( pin "U5D1.CC10"
				( objectStatus "@baseboard_fab2_lib.baseboard_fab2(sch_1):page35_i3:upi2_tx_dn(18)" )
			)
			( pin "U5D1.CC12"
				( objectStatus "@baseboard_fab2_lib.baseboard_fab2(sch_1):page35_i3:upi2_tx_dn(19)" )
			)
			( pin "U5D1.DP21"
				( objectStatus "@baseboard_fab2_lib.baseboard_fab2(sch_1):page35_i3:upi2_tx_dp(0)" )
			)
			( pin "U5D1.DN20"
				( objectStatus "@baseboard_fab2_lib.baseboard_fab2(sch_1):page35_i3:upi2_tx_dp(1)" )
			)
			( pin "U5D1.DK19"
				( objectStatus "@baseboard_fab2_lib.baseboard_fab2(sch_1):page35_i3:upi2_tx_dp(2)" )
			)
			( pin "U5D1.DJ20"
				( objectStatus "@baseboard_fab2_lib.baseboard_fab2(sch_1):page35_i3:upi2_tx_dp(3)" )
			)
			( pin "U5D1.DJ18"
				( objectStatus "@baseboard_fab2_lib.baseboard_fab2(sch_1):page35_i3:upi2_tx_dp(4)" )
			)
			( pin "U5D1.DH17"
				( objectStatus "@baseboard_fab2_lib.baseboard_fab2(sch_1):page35_i3:upi2_tx_dp(5)" )
			)
			( pin "U5D1.DF17"
				( objectStatus "@baseboard_fab2_lib.baseboard_fab2(sch_1):page35_i3:upi2_tx_dp(6)" )
			)
			( pin "U5D1.DE16"
				( objectStatus "@baseboard_fab2_lib.baseboard_fab2(sch_1):page35_i3:upi2_tx_dp(7)" )
			)
			( pin "U5D1.DD15"
				( objectStatus "@baseboard_fab2_lib.baseboard_fab2(sch_1):page35_i3:upi2_tx_dp(8)" )
			)
			( pin "U5D1.DB15"
				( objectStatus "@baseboard_fab2_lib.baseboard_fab2(sch_1):page35_i3:upi2_tx_dp(9)" )
			)
			( pin "U5D1.CW16"
				( objectStatus "@baseboard_fab2_lib.baseboard_fab2(sch_1):page35_i3:upi2_tx_dp(10)" )
			)
			( pin "U5D1.CV13"
				( objectStatus "@baseboard_fab2_lib.baseboard_fab2(sch_1):page35_i3:upi2_tx_dp(11)" )
			)
			( pin "U5D1.CR14"
				( objectStatus "@baseboard_fab2_lib.baseboard_fab2(sch_1):page35_i3:upi2_tx_dp(12)" )
			)
			( pin "U5D1.CK13"
				( objectStatus "@baseboard_fab2_lib.baseboard_fab2(sch_1):page35_i3:upi2_tx_dp(13)" )
			)
			( pin "U5D1.CH13"
				( objectStatus "@baseboard_fab2_lib.baseboard_fab2(sch_1):page35_i3:upi2_tx_dp(14)" )
			)
			( pin "U5D1.CG12"
				( objectStatus "@baseboard_fab2_lib.baseboard_fab2(sch_1):page35_i3:upi2_tx_dp(15)" )
			)
			( pin "U5D1.CF11"
				( objectStatus "@baseboard_fab2_lib.baseboard_fab2(sch_1):page35_i3:upi2_tx_dp(16)" )
			)
			( pin "U5D1.CD11"
				( objectStatus "@baseboard_fab2_lib.baseboard_fab2(sch_1):page35_i3:upi2_tx_dp(17)" )
			)
			( pin "U5D1.CB11"
				( objectStatus "@baseboard_fab2_lib.baseboard_fab2(sch_1):page35_i3:upi2_tx_dp(18)" )
			)
			( pin "U5D1.CA12"
				( objectStatus "@baseboard_fab2_lib.baseboard_fab2(sch_1):page35_i3:upi2_tx_dp(19)" )
			)
			( pin "U5D1.CH23"
				( objectStatus "@baseboard_fab2_lib.baseboard_fab2(sch_1):page36_i15:rsvd(92)" )
			)
			( pin "U5D1.CH21"
				( objectStatus "@baseboard_fab2_lib.baseboard_fab2(sch_1):page36_i15:rsvd(93)" )
			)
			( pin "U5D1.CG82"
				( objectStatus "@baseboard_fab2_lib.baseboard_fab2(sch_1):page36_i15:rsvd(94)" )
			)
			( pin "U5D1.CG78"
				( objectStatus "@baseboard_fab2_lib.baseboard_fab2(sch_1):page36_i15:rsvd(95)" )
			)
			( pin "U5D1.CG26"
				( objectStatus "@baseboard_fab2_lib.baseboard_fab2(sch_1):page36_i15:rsvd(96)" )
			)
			( pin "U5D1.CG24"
				( objectStatus "@baseboard_fab2_lib.baseboard_fab2(sch_1):page36_i15:rsvd(97)" )
			)
			( pin "U5D1.CG20"
				( objectStatus "@baseboard_fab2_lib.baseboard_fab2(sch_1):page36_i15:rsvd(98)" )
			)
			( pin "U5D1.CG10"
				( objectStatus "@baseboard_fab2_lib.baseboard_fab2(sch_1):page36_i15:rsvd(99)" )
			)
			( pin "U5D1.CF81"
				( objectStatus "@baseboard_fab2_lib.baseboard_fab2(sch_1):page36_i15:rsvd(100)" )
			)
			( pin "U5D1.CF79"
				( objectStatus "@baseboard_fab2_lib.baseboard_fab2(sch_1):page36_i15:rsvd(101)" )
			)
			( pin "U5D1.CF23"
				( objectStatus "@baseboard_fab2_lib.baseboard_fab2(sch_1):page36_i15:rsvd(102)" )
			)
			( pin "U5D1.CF21"
				( objectStatus "@baseboard_fab2_lib.baseboard_fab2(sch_1):page36_i15:rsvd(103)" )
			)
			( pin "U5D1.CF19"
				( objectStatus "@baseboard_fab2_lib.baseboard_fab2(sch_1):page36_i15:rsvd(104)" )
			)
			( pin "U5D1.CE80"
				( objectStatus "@baseboard_fab2_lib.baseboard_fab2(sch_1):page36_i15:rsvd(105)" )
			)
			( pin "U5D1.CE78"
				( objectStatus "@baseboard_fab2_lib.baseboard_fab2(sch_1):page36_i15:rsvd(106)" )
			)
			( pin "U5D1.CE22"
				( objectStatus "@baseboard_fab2_lib.baseboard_fab2(sch_1):page36_i15:rsvd(107)" )
			)
			( pin "U5D1.CD25"
				( objectStatus "@baseboard_fab2_lib.baseboard_fab2(sch_1):page36_i15:rsvd(108)" )
			)
			( pin "U5D1.CD21"
				( objectStatus "@baseboard_fab2_lib.baseboard_fab2(sch_1):page36_i15:rsvd(109)" )
			)
			( pin "U5D1.CD19"
				( objectStatus "@baseboard_fab2_lib.baseboard_fab2(sch_1):page36_i15:rsvd(110)" )
			)
			( pin "U5D1.CC6"
				( objectStatus "@baseboard_fab2_lib.baseboard_fab2(sch_1):page36_i15:rsvd(111)" )
			)
			( pin "U5D1.CC20"
				( objectStatus "@baseboard_fab2_lib.baseboard_fab2(sch_1):page36_i15:rsvd(112)" )
			)
			( pin "U5D1.CB5"
				( objectStatus "@baseboard_fab2_lib.baseboard_fab2(sch_1):page36_i15:rsvd(113)" )
			)
			( pin "U5D1.CB25"
				( objectStatus "@baseboard_fab2_lib.baseboard_fab2(sch_1):page36_i15:rsvd(114)" )
			)
			( pin "U5D1.CB21"
				( objectStatus "@baseboard_fab2_lib.baseboard_fab2(sch_1):page36_i15:rsvd(115)" )
			)
			( pin "U5D1.CB19"
				( objectStatus "@baseboard_fab2_lib.baseboard_fab2(sch_1):page36_i15:rsvd(116)" )
			)
			( pin "U5D1.CA24"
				( objectStatus "@baseboard_fab2_lib.baseboard_fab2(sch_1):page36_i15:rsvd(117)" )
			)
			( pin "U5D1.CA22"
				( objectStatus "@baseboard_fab2_lib.baseboard_fab2(sch_1):page36_i15:rsvd(118)" )
			)
			( pin "U5D1.BY25"
				( objectStatus "@baseboard_fab2_lib.baseboard_fab2(sch_1):page36_i15:rsvd(119)" )
			)
			( pin "U5D1.BY19"
				( objectStatus "@baseboard_fab2_lib.baseboard_fab2(sch_1):page36_i15:rsvd(120)" )
			)
			( pin "U5D1.BW22"
				( objectStatus "@baseboard_fab2_lib.baseboard_fab2(sch_1):page36_i15:rsvd(121)" )
			)
			( pin "U5D1.BW20"
				( objectStatus "@baseboard_fab2_lib.baseboard_fab2(sch_1):page36_i15:rsvd(122)" )
			)
			( pin "U5D1.BW10"
				( objectStatus "@baseboard_fab2_lib.baseboard_fab2(sch_1):page36_i15:rsvd(123)" )
			)
			( pin "U5D1.BV23"
				( objectStatus "@baseboard_fab2_lib.baseboard_fab2(sch_1):page36_i15:rsvd(124)" )
			)
			( pin "U5D1.BV21"
				( objectStatus "@baseboard_fab2_lib.baseboard_fab2(sch_1):page36_i15:rsvd(125)" )
			)
			( pin "U5D1.BV19"
				( objectStatus "@baseboard_fab2_lib.baseboard_fab2(sch_1):page36_i15:rsvd(126)" )
			)
			( pin "U5D1.BU22"
				( objectStatus "@baseboard_fab2_lib.baseboard_fab2(sch_1):page36_i15:rsvd(127)" )
			)
			( pin "U5D1.BU20"
				( objectStatus "@baseboard_fab2_lib.baseboard_fab2(sch_1):page36_i15:rsvd(128)" )
			)
			( pin "U5D1.BU18"
				( objectStatus "@baseboard_fab2_lib.baseboard_fab2(sch_1):page36_i15:rsvd(129)" )
			)
			( pin "U5D1.BR24"
				( objectStatus "@baseboard_fab2_lib.baseboard_fab2(sch_1):page36_i15:rsvd(130)" )
			)
			( pin "U5D1.BR22"
				( objectStatus "@baseboard_fab2_lib.baseboard_fab2(sch_1):page36_i15:rsvd(131)" )
			)
			( pin "U5D1.BP21"
				( objectStatus "@baseboard_fab2_lib.baseboard_fab2(sch_1):page36_i15:rsvd(132)" )
			)
			( pin "U5D1.BP17"
				( objectStatus "@baseboard_fab2_lib.baseboard_fab2(sch_1):page36_i15:rsvd(133)" )
			)
			( pin "U5D1.BN18"
				( objectStatus "@baseboard_fab2_lib.baseboard_fab2(sch_1):page36_i15:rsvd(134)" )
			)
			( pin "U5D1.BM19"
				( objectStatus "@baseboard_fab2_lib.baseboard_fab2(sch_1):page36_i15:rsvd(135)" )
			)
			( pin "U5D1.BM17"
				( objectStatus "@baseboard_fab2_lib.baseboard_fab2(sch_1):page36_i15:rsvd(136)" )
			)
			( pin "U5D1.BL20"
				( objectStatus "@baseboard_fab2_lib.baseboard_fab2(sch_1):page36_i15:rsvd(137)" )
			)
			( pin "U5D1.BL18"
				( objectStatus "@baseboard_fab2_lib.baseboard_fab2(sch_1):page36_i15:rsvd(138)" )
			)
			( pin "U5D1.BK17"
				( objectStatus "@baseboard_fab2_lib.baseboard_fab2(sch_1):page36_i15:rsvd(139)" )
			)
			( pin "U5D1.BJ20"
				( objectStatus "@baseboard_fab2_lib.baseboard_fab2(sch_1):page36_i15:rsvd(140)" )
			)
			( pin "U5D1.BJ18"
				( objectStatus "@baseboard_fab2_lib.baseboard_fab2(sch_1):page36_i15:rsvd(141)" )
			)
			( pin "U5D1.BJ16"
				( objectStatus "@baseboard_fab2_lib.baseboard_fab2(sch_1):page36_i15:rsvd(142)" )
			)
			( pin "U5D1.BH19"
				( objectStatus "@baseboard_fab2_lib.baseboard_fab2(sch_1):page36_i15:rsvd(143)" )
			)
			( pin "U5D1.BG20"
				( objectStatus "@baseboard_fab2_lib.baseboard_fab2(sch_1):page36_i15:rsvd(144)" )
			)
			( pin "U5D1.BG18"
				( objectStatus "@baseboard_fab2_lib.baseboard_fab2(sch_1):page36_i15:rsvd(145)" )
			)
			( pin "U5D1.BF21"
				( objectStatus "@baseboard_fab2_lib.baseboard_fab2(sch_1):page36_i15:rsvd(146)" )
			)
			( pin "U5D1.BE22"
				( objectStatus "@baseboard_fab2_lib.baseboard_fab2(sch_1):page36_i15:rsvd(147)" )
			)
			( pin "U5D1.BE20"
				( objectStatus "@baseboard_fab2_lib.baseboard_fab2(sch_1):page36_i15:rsvd(148)" )
			)
			( pin "U5D1.BE18"
				( objectStatus "@baseboard_fab2_lib.baseboard_fab2(sch_1):page36_i15:rsvd(149)" )
			)
			( pin "U5D1.BD69"
				( objectStatus "@baseboard_fab2_lib.baseboard_fab2(sch_1):page36_i15:rsvd(150)" )
			)
			( pin "U5D1.BD67"
				( objectStatus "@baseboard_fab2_lib.baseboard_fab2(sch_1):page36_i15:rsvd(151)" )
			)
			( pin "U5D1.BD65"
				( objectStatus "@baseboard_fab2_lib.baseboard_fab2(sch_1):page36_i15:rsvd(152)" )
			)
			( pin "U5D1.BD25"
				( objectStatus "@baseboard_fab2_lib.baseboard_fab2(sch_1):page36_i15:rsvd(153)" )
			)
			( pin "U5D1.BD19"
				( objectStatus "@baseboard_fab2_lib.baseboard_fab2(sch_1):page36_i15:rsvd(154)" )
			)
			( pin "U5D1.BD17"
				( objectStatus "@baseboard_fab2_lib.baseboard_fab2(sch_1):page36_i15:rsvd(155)" )
			)
			( pin "U5D1.BC68"
				( objectStatus "@baseboard_fab2_lib.baseboard_fab2(sch_1):page36_i15:rsvd(156)" )
			)
			( pin "U5D1.BC66"
				( objectStatus "@baseboard_fab2_lib.baseboard_fab2(sch_1):page36_i15:rsvd(157)" )
			)
			( pin "U5D1.BC64"
				( objectStatus "@baseboard_fab2_lib.baseboard_fab2(sch_1):page36_i15:rsvd(158)" )
			)
			( pin "U5D1.BC22"
				( objectStatus "@baseboard_fab2_lib.baseboard_fab2(sch_1):page36_i15:rsvd(159)" )
			)
			( pin "U5D1.BC20"
				( objectStatus "@baseboard_fab2_lib.baseboard_fab2(sch_1):page36_i15:rsvd(160)" )
			)
			( pin "U5D1.BC18"
				( objectStatus "@baseboard_fab2_lib.baseboard_fab2(sch_1):page36_i15:rsvd(161)" )
			)
			( pin "U5D1.BC14"
				( objectStatus "@baseboard_fab2_lib.baseboard_fab2(sch_1):page36_i15:rsvd(162)" )
			)
			( pin "U5D1.BB67"
				( objectStatus "@baseboard_fab2_lib.baseboard_fab2(sch_1):page36_i15:rsvd(163)" )
			)
			( pin "U5D1.BB65"
				( objectStatus "@baseboard_fab2_lib.baseboard_fab2(sch_1):page36_i15:rsvd(164)" )
			)
			( pin "U5D1.BB25"
				( objectStatus "@baseboard_fab2_lib.baseboard_fab2(sch_1):page36_i15:rsvd(165)" )
			)
			( pin "U5D1.BB21"
				( objectStatus "@baseboard_fab2_lib.baseboard_fab2(sch_1):page36_i15:rsvd(166)" )
			)
			( pin "U5D1.BB17"
				( objectStatus "@baseboard_fab2_lib.baseboard_fab2(sch_1):page36_i15:rsvd(167)" )
			)
			( pin "U5D1.BB15"
				( objectStatus "@baseboard_fab2_lib.baseboard_fab2(sch_1):page36_i15:rsvd(168)" )
			)
			( pin "U5D1.BB13"
				( objectStatus "@baseboard_fab2_lib.baseboard_fab2(sch_1):page36_i15:rsvd(169)" )
			)
			( pin "U5D1.BA82"
				( objectStatus "@baseboard_fab2_lib.baseboard_fab2(sch_1):page36_i15:rsvd(170)" )
			)
			( pin "U5D1.BA78"
				( objectStatus "@baseboard_fab2_lib.baseboard_fab2(sch_1):page36_i15:rsvd(171)" )
			)
			( pin "U5D1.AY83"
				( objectStatus "@baseboard_fab2_lib.baseboard_fab2(sch_1):page36_i15:rsvd(255)" )
			)
			( pin "U5D1.CL24"
				( objectStatus "@baseboard_fab2_lib.baseboard_fab2(sch_1):page36_i16:rsvd(81)" )
			)
			( pin "U5D1.CK77"
				( objectStatus "@baseboard_fab2_lib.baseboard_fab2(sch_1):page36_i16:rsvd(82)" )
			)
			( pin "U5D1.CK25"
				( objectStatus "@baseboard_fab2_lib.baseboard_fab2(sch_1):page36_i16:rsvd(83)" )
			)
			( pin "U5D1.CK23"
				( objectStatus "@baseboard_fab2_lib.baseboard_fab2(sch_1):page36_i16:rsvd(84)" )
			)
			( pin "U5D1.CK19"
				( objectStatus "@baseboard_fab2_lib.baseboard_fab2(sch_1):page36_i16:rsvd(85)" )
			)
			( pin "U5D1.CJ26"
				( objectStatus "@baseboard_fab2_lib.baseboard_fab2(sch_1):page36_i16:rsvd(86)" )
			)
			( pin "U5D1.CJ24"
				( objectStatus "@baseboard_fab2_lib.baseboard_fab2(sch_1):page36_i16:rsvd(87)" )
			)
			( pin "U5D1.CJ22"
				( objectStatus "@baseboard_fab2_lib.baseboard_fab2(sch_1):page36_i16:rsvd(88)" )
			)
			( pin "U5D1.CJ20"
				( objectStatus "@baseboard_fab2_lib.baseboard_fab2(sch_1):page36_i16:rsvd(89)" )
			)
			( pin "U5D1.CH77"
				( objectStatus "@baseboard_fab2_lib.baseboard_fab2(sch_1):page36_i16:rsvd(90)" )
			)
			( pin "U5D1.CH25"
				( objectStatus "@baseboard_fab2_lib.baseboard_fab2(sch_1):page36_i16:rsvd(91)" )
			)
			( pin "U5D1.AR16"
				( objectStatus "@baseboard_fab2_lib.baseboard_fab2(sch_1):page36_i16:test_6" )
			)
			( pin "U5D1.AU18"
				( objectStatus "@baseboard_fab2_lib.baseboard_fab2(sch_1):page36_i16:test_7" )
			)
			( pin "U5D1.AW16"
				( objectStatus "@baseboard_fab2_lib.baseboard_fab2(sch_1):page36_i16:test_8" )
			)
			( pin "U5D1.AW20"
				( objectStatus "@baseboard_fab2_lib.baseboard_fab2(sch_1):page36_i16:test_9" )
			)
			( pin "U5D1.AW22"
				( objectStatus "@baseboard_fab2_lib.baseboard_fab2(sch_1):page36_i16:test_10" )
			)
			( pin "R5D5.1"
				( objectStatus "@baseboard_fab2_lib.baseboard_fab2(sch_1):page37_i303:a" )
			)
			( pin "R5D5.2"
				( objectStatus "@baseboard_fab2_lib.baseboard_fab2(sch_1):page37_i303:b" )
			)
			( pin "R5P1.1"
				( objectStatus "@baseboard_fab2_lib.baseboard_fab2(sch_1):page37_i309:a" )
			)
			( pin "R5P1.2"
				( objectStatus "@baseboard_fab2_lib.baseboard_fab2(sch_1):page37_i309:b" )
			)
			( pin "U5D1.BN78"
				( objectStatus "@baseboard_fab2_lib.baseboard_fab2(sch_1):page37_i310:vccin(130)" )
			)
			( pin "U5D1.BN76"
				( objectStatus "@baseboard_fab2_lib.baseboard_fab2(sch_1):page37_i310:vccin(131)" )
			)
			( pin "U5D1.BN74"
				( objectStatus "@baseboard_fab2_lib.baseboard_fab2(sch_1):page37_i310:vccin(132)" )
			)
			( pin "U5D1.BN72"
				( objectStatus "@baseboard_fab2_lib.baseboard_fab2(sch_1):page37_i310:vccin(133)" )
			)
			( pin "U5D1.BN70"
				( objectStatus "@baseboard_fab2_lib.baseboard_fab2(sch_1):page37_i310:vccin(134)" )
			)
			( pin "U5D1.BN68"
				( objectStatus "@baseboard_fab2_lib.baseboard_fab2(sch_1):page37_i310:vccin(135)" )
			)
			( pin "U5D1.BN66"
				( objectStatus "@baseboard_fab2_lib.baseboard_fab2(sch_1):page37_i310:vccin(136)" )
			)
			( pin "U5D1.BN64"
				( objectStatus "@baseboard_fab2_lib.baseboard_fab2(sch_1):page37_i310:vccin(137)" )
			)
			( pin "U5D1.BN62"
				( objectStatus "@baseboard_fab2_lib.baseboard_fab2(sch_1):page37_i310:vccin(138)" )
			)
			( pin "U5D1.BN60"
				( objectStatus "@baseboard_fab2_lib.baseboard_fab2(sch_1):page37_i310:vccin(139)" )
			)
			( pin "U5D1.BM83"
				( objectStatus "@baseboard_fab2_lib.baseboard_fab2(sch_1):page37_i310:vccin(140)" )
			)
			( pin "U5D1.BM81"
				( objectStatus "@baseboard_fab2_lib.baseboard_fab2(sch_1):page37_i310:vccin(141)" )
			)
			( pin "U5D1.BM79"
				( objectStatus "@baseboard_fab2_lib.baseboard_fab2(sch_1):page37_i310:vccin(142)" )
			)
			( pin "U5D1.BM77"
				( objectStatus "@baseboard_fab2_lib.baseboard_fab2(sch_1):page37_i310:vccin(143)" )
			)
			( pin "U5D1.BM75"
				( objectStatus "@baseboard_fab2_lib.baseboard_fab2(sch_1):page37_i310:vccin(144)" )
			)
			( pin "U5D1.BM73"
				( objectStatus "@baseboard_fab2_lib.baseboard_fab2(sch_1):page37_i310:vccin(145)" )
			)
			( pin "U5D1.BM71"
				( objectStatus "@baseboard_fab2_lib.baseboard_fab2(sch_1):page37_i310:vccin(146)" )
			)
			( pin "U5D1.BM69"
				( objectStatus "@baseboard_fab2_lib.baseboard_fab2(sch_1):page37_i310:vccin(147)" )
			)
			( pin "U5D1.BM67"
				( objectStatus "@baseboard_fab2_lib.baseboard_fab2(sch_1):page37_i310:vccin(148)" )
			)
			( pin "U5D1.BM65"
				( objectStatus "@baseboard_fab2_lib.baseboard_fab2(sch_1):page37_i310:vccin(149)" )
			)
			( pin "U5D1.BM63"
				( objectStatus "@baseboard_fab2_lib.baseboard_fab2(sch_1):page37_i310:vccin(150)" )
			)
			( pin "U5D1.BM61"
				( objectStatus "@baseboard_fab2_lib.baseboard_fab2(sch_1):page37_i310:vccin(151)" )
			)
			( pin "U5D1.BL84"
				( objectStatus "@baseboard_fab2_lib.baseboard_fab2(sch_1):page37_i310:vccin(152)" )
			)
			( pin "U5D1.BL62"
				( objectStatus "@baseboard_fab2_lib.baseboard_fab2(sch_1):page37_i310:vccin(153)" )
			)
			( pin "U5D1.BL60"
				( objectStatus "@baseboard_fab2_lib.baseboard_fab2(sch_1):page37_i310:vccin(154)" )
			)
			( pin "U5D1.BK83"
				( objectStatus "@baseboard_fab2_lib.baseboard_fab2(sch_1):page37_i310:vccin(155)" )
			)
			( pin "U5D1.BK81"
				( objectStatus "@baseboard_fab2_lib.baseboard_fab2(sch_1):page37_i310:vccin(156)" )
			)
			( pin "U5D1.BK79"
				( objectStatus "@baseboard_fab2_lib.baseboard_fab2(sch_1):page37_i310:vccin(157)" )
			)
			( pin "U5D1.BK77"
				( objectStatus "@baseboard_fab2_lib.baseboard_fab2(sch_1):page37_i310:vccin(158)" )
			)
			( pin "U5D1.BK75"
				( objectStatus "@baseboard_fab2_lib.baseboard_fab2(sch_1):page37_i310:vccin(159)" )
			)
			( pin "U5D1.BK73"
				( objectStatus "@baseboard_fab2_lib.baseboard_fab2(sch_1):page37_i310:vccin(160)" )
			)
			( pin "U5D1.BK71"
				( objectStatus "@baseboard_fab2_lib.baseboard_fab2(sch_1):page37_i310:vccin(161)" )
			)
			( pin "U5D1.BK69"
				( objectStatus "@baseboard_fab2_lib.baseboard_fab2(sch_1):page37_i310:vccin(162)" )
			)
			( pin "U5D1.BK67"
				( objectStatus "@baseboard_fab2_lib.baseboard_fab2(sch_1):page37_i310:vccin(163)" )
			)
			( pin "U5D1.BK65"
				( objectStatus "@baseboard_fab2_lib.baseboard_fab2(sch_1):page37_i310:vccin(164)" )
			)
			( pin "U5D1.BK63"
				( objectStatus "@baseboard_fab2_lib.baseboard_fab2(sch_1):page37_i310:vccin(165)" )
			)
			( pin "U5D1.BK61"
				( objectStatus "@baseboard_fab2_lib.baseboard_fab2(sch_1):page37_i310:vccin(166)" )
			)
			( pin "U5D1.BJ84"
				( objectStatus "@baseboard_fab2_lib.baseboard_fab2(sch_1):page37_i310:vccin(167)" )
			)
			( pin "U5D1.BJ82"
				( objectStatus "@baseboard_fab2_lib.baseboard_fab2(sch_1):page37_i310:vccin(168)" )
			)
			( pin "U5D1.BJ80"
				( objectStatus "@baseboard_fab2_lib.baseboard_fab2(sch_1):page37_i310:vccin(169)" )
			)
			( pin "U5D1.BJ78"
				( objectStatus "@baseboard_fab2_lib.baseboard_fab2(sch_1):page37_i310:vccin(170)" )
			)
			( pin "U5D1.BJ76"
				( objectStatus "@baseboard_fab2_lib.baseboard_fab2(sch_1):page37_i310:vccin(171)" )
			)
			( pin "U5D1.BJ74"
				( objectStatus "@baseboard_fab2_lib.baseboard_fab2(sch_1):page37_i310:vccin(172)" )
			)
			( pin "U5D1.BJ72"
				( objectStatus "@baseboard_fab2_lib.baseboard_fab2(sch_1):page37_i310:vccin(173)" )
			)
			( pin "U5D1.BJ70"
				( objectStatus "@baseboard_fab2_lib.baseboard_fab2(sch_1):page37_i310:vccin(174)" )
			)
			( pin "U5D1.BJ68"
				( objectStatus "@baseboard_fab2_lib.baseboard_fab2(sch_1):page37_i310:vccin(175)" )
			)
			( pin "U5D1.BJ66"
				( objectStatus "@baseboard_fab2_lib.baseboard_fab2(sch_1):page37_i310:vccin(176)" )
			)
			( pin "U5D1.BJ64"
				( objectStatus "@baseboard_fab2_lib.baseboard_fab2(sch_1):page37_i310:vccin(177)" )
			)
			( pin "U5D1.BJ62"
				( objectStatus "@baseboard_fab2_lib.baseboard_fab2(sch_1):page37_i310:vccin(178)" )
			)
			( pin "U5D1.BJ60"
				( objectStatus "@baseboard_fab2_lib.baseboard_fab2(sch_1):page37_i310:vccin(179)" )
			)
			( pin "U5D1.BH83"
				( objectStatus "@baseboard_fab2_lib.baseboard_fab2(sch_1):page37_i310:vccin(180)" )
			)
			( pin "U5D1.BH81"
				( objectStatus "@baseboard_fab2_lib.baseboard_fab2(sch_1):page37_i310:vccin(181)" )
			)
			( pin "U5D1.BH79"
				( objectStatus "@baseboard_fab2_lib.baseboard_fab2(sch_1):page37_i310:vccin(182)" )
			)
			( pin "U5D1.BH77"
				( objectStatus "@baseboard_fab2_lib.baseboard_fab2(sch_1):page37_i310:vccin(183)" )
			)
			( pin "U5D1.BH75"
				( objectStatus "@baseboard_fab2_lib.baseboard_fab2(sch_1):page37_i310:vccin(184)" )
			)
			( pin "U5D1.BH73"
				( objectStatus "@baseboard_fab2_lib.baseboard_fab2(sch_1):page37_i310:vccin(185)" )
			)
			( pin "U5D1.BH71"
				( objectStatus "@baseboard_fab2_lib.baseboard_fab2(sch_1):page37_i310:vccin(186)" )
			)
			( pin "U5D1.BH69"
				( objectStatus "@baseboard_fab2_lib.baseboard_fab2(sch_1):page37_i310:vccin(187)" )
			)
			( pin "U5D1.BH67"
				( objectStatus "@baseboard_fab2_lib.baseboard_fab2(sch_1):page37_i310:vccin(188)" )
			)
			( pin "U5D1.BH65"
				( objectStatus "@baseboard_fab2_lib.baseboard_fab2(sch_1):page37_i310:vccin(189)" )
			)
			( pin "U5D1.BH63"
				( objectStatus "@baseboard_fab2_lib.baseboard_fab2(sch_1):page37_i310:vccin(190)" )
			)
			( pin "U5D1.BH61"
				( objectStatus "@baseboard_fab2_lib.baseboard_fab2(sch_1):page37_i310:vccin(191)" )
			)
			( pin "U5D1.BG84"
				( objectStatus "@baseboard_fab2_lib.baseboard_fab2(sch_1):page37_i310:vccin(192)" )
			)
			( pin "U5D1.BG70"
				( objectStatus "@baseboard_fab2_lib.baseboard_fab2(sch_1):page37_i310:vccin(193)" )
			)
			( pin "U5D1.BG68"
				( objectStatus "@baseboard_fab2_lib.baseboard_fab2(sch_1):page37_i310:vccin(194)" )
			)
			( pin "U5D1.BG66"
				( objectStatus "@baseboard_fab2_lib.baseboard_fab2(sch_1):page37_i310:vccin(195)" )
			)
			( pin "U5D1.BG64"
				( objectStatus "@baseboard_fab2_lib.baseboard_fab2(sch_1):page37_i310:vccin(196)" )
			)
			( pin "U5D1.BG62"
				( objectStatus "@baseboard_fab2_lib.baseboard_fab2(sch_1):page37_i310:vccin(197)" )
			)
			( pin "U5D1.BG60"
				( objectStatus "@baseboard_fab2_lib.baseboard_fab2(sch_1):page37_i310:vccin(198)" )
			)
			( pin "U5D1.BF85"
				( objectStatus "@baseboard_fab2_lib.baseboard_fab2(sch_1):page37_i310:vccin(199)" )
			)
			( pin "U5D1.BF83"
				( objectStatus "@baseboard_fab2_lib.baseboard_fab2(sch_1):page37_i310:vccin(200)" )
			)
			( pin "U5D1.BF81"
				( objectStatus "@baseboard_fab2_lib.baseboard_fab2(sch_1):page37_i310:vccin(201)" )
			)
			( pin "U5D1.BF79"
				( objectStatus "@baseboard_fab2_lib.baseboard_fab2(sch_1):page37_i310:vccin(202)" )
			)
			( pin "U5D1.BF77"
				( objectStatus "@baseboard_fab2_lib.baseboard_fab2(sch_1):page37_i310:vccin(203)" )
			)
			( pin "U5D1.BF75"
				( objectStatus "@baseboard_fab2_lib.baseboard_fab2(sch_1):page37_i310:vccin(204)" )
			)
			( pin "U5D1.BF73"
				( objectStatus "@baseboard_fab2_lib.baseboard_fab2(sch_1):page37_i310:vccin(205)" )
			)
			( pin "U5D1.BF61"
				( objectStatus "@baseboard_fab2_lib.baseboard_fab2(sch_1):page37_i310:vccin(206)" )
			)
			( pin "U5D1.BE84"
				( objectStatus "@baseboard_fab2_lib.baseboard_fab2(sch_1):page37_i310:vccin(207)" )
			)
			( pin "U5D1.BE82"
				( objectStatus "@baseboard_fab2_lib.baseboard_fab2(sch_1):page37_i310:vccin(208)" )
			)
			( pin "U5D1.BE80"
				( objectStatus "@baseboard_fab2_lib.baseboard_fab2(sch_1):page37_i310:vccin(209)" )
			)
			( pin "U5D1.BE78"
				( objectStatus "@baseboard_fab2_lib.baseboard_fab2(sch_1):page37_i310:vccin(210)" )
			)
			( pin "U5D1.BE76"
				( objectStatus "@baseboard_fab2_lib.baseboard_fab2(sch_1):page37_i310:vccin(211)" )
			)
			( pin "U5D1.BE74"
				( objectStatus "@baseboard_fab2_lib.baseboard_fab2(sch_1):page37_i310:vccin(212)" )
			)
			( pin "U5D1.BE72"
				( objectStatus "@baseboard_fab2_lib.baseboard_fab2(sch_1):page37_i310:vccin(213)" )
			)
			( pin "U5D1.BE62"
				( objectStatus "@baseboard_fab2_lib.baseboard_fab2(sch_1):page37_i310:vccin(214)" )
			)
			( pin "U5D1.BE60"
				( objectStatus "@baseboard_fab2_lib.baseboard_fab2(sch_1):page37_i310:vccin(215)" )
			)
			( pin "U5D1.BD85"
				( objectStatus "@baseboard_fab2_lib.baseboard_fab2(sch_1):page37_i310:vccin(216)" )
			)
			( pin "U5D1.BD83"
				( objectStatus "@baseboard_fab2_lib.baseboard_fab2(sch_1):page37_i310:vccin(217)" )
			)
			( pin "U5D1.BD81"
				( objectStatus "@baseboard_fab2_lib.baseboard_fab2(sch_1):page37_i310:vccin(218)" )
			)
			( pin "U5D1.BD79"
				( objectStatus "@baseboard_fab2_lib.baseboard_fab2(sch_1):page37_i310:vccin(219)" )
			)
			( pin "U5D1.BD77"
				( objectStatus "@baseboard_fab2_lib.baseboard_fab2(sch_1):page37_i310:vccin(220)" )
			)
			( pin "U5D1.BD75"
				( objectStatus "@baseboard_fab2_lib.baseboard_fab2(sch_1):page37_i310:vccin(221)" )
			)
			( pin "U5D1.BD73"
				( objectStatus "@baseboard_fab2_lib.baseboard_fab2(sch_1):page37_i310:vccin(222)" )
			)
			( pin "U5D1.BD61"
				( objectStatus "@baseboard_fab2_lib.baseboard_fab2(sch_1):page37_i310:vccin(223)" )
			)
			( pin "U5D1.BC84"
				( objectStatus "@baseboard_fab2_lib.baseboard_fab2(sch_1):page37_i310:vccin(224)" )
			)
			( pin "U5D1.BC62"
				( objectStatus "@baseboard_fab2_lib.baseboard_fab2(sch_1):page37_i310:vccin(225)" )
			)
			( pin "U5D1.BC60"
				( objectStatus "@baseboard_fab2_lib.baseboard_fab2(sch_1):page37_i310:vccin(226)" )
			)
			( pin "U5D1.BB85"
				( objectStatus "@baseboard_fab2_lib.baseboard_fab2(sch_1):page37_i310:vccin(227)" )
			)
			( pin "U5D1.BB61"
				( objectStatus "@baseboard_fab2_lib.baseboard_fab2(sch_1):page37_i310:vccin(228)" )
			)
			( pin "U5D1.BA60"
				( objectStatus "@baseboard_fab2_lib.baseboard_fab2(sch_1):page37_i310:vccin(229)" )
			)
			( pin "U5D1.AY61"
				( objectStatus "@baseboard_fab2_lib.baseboard_fab2(sch_1):page37_i310:vccin(230)" )
			)
			( pin "U5D1.AW60"
				( objectStatus "@baseboard_fab2_lib.baseboard_fab2(sch_1):page37_i310:vccin(231)" )
			)
			( pin "U5D1.AV61"
				( objectStatus "@baseboard_fab2_lib.baseboard_fab2(sch_1):page37_i310:vccin(232)" )
			)
			( pin "U5D1.AV59"
				( objectStatus "@baseboard_fab2_lib.baseboard_fab2(sch_1):page37_i310:vccin(233)" )
			)
			( pin "U5D1.AU60"
				( objectStatus "@baseboard_fab2_lib.baseboard_fab2(sch_1):page37_i310:vccin(234)" )
			)
			( pin "U5D1.AU58"
				( objectStatus "@baseboard_fab2_lib.baseboard_fab2(sch_1):page37_i310:vccin(235)" )
			)
			( pin "U5D1.AT59"
				( objectStatus "@baseboard_fab2_lib.baseboard_fab2(sch_1):page37_i310:vccin(236)" )
			)
			( pin "U5D1.AT57"
				( objectStatus "@baseboard_fab2_lib.baseboard_fab2(sch_1):page37_i310:vccin(237)" )
			)
			( pin "U5D1.AR58"
				( objectStatus "@baseboard_fab2_lib.baseboard_fab2(sch_1):page37_i310:vccin(238)" )
			)
			( pin "U5D1.AR56"
				( objectStatus "@baseboard_fab2_lib.baseboard_fab2(sch_1):page37_i310:vccin(239)" )
			)
			( pin "U5D1.AP57"
				( objectStatus "@baseboard_fab2_lib.baseboard_fab2(sch_1):page37_i310:vccin(240)" )
			)
			( pin "U5D1.AP55"
				( objectStatus "@baseboard_fab2_lib.baseboard_fab2(sch_1):page37_i310:vccin(241)" )
			)
			( pin "U5D1.AN56"
				( objectStatus "@baseboard_fab2_lib.baseboard_fab2(sch_1):page37_i310:vccin(242)" )
			)
			( pin "U5D1.AN54"
				( objectStatus "@baseboard_fab2_lib.baseboard_fab2(sch_1):page37_i310:vccin(243)" )
			)
			( pin "U5D1.AN32"
				( objectStatus "@baseboard_fab2_lib.baseboard_fab2(sch_1):page37_i310:vccin(244)" )
			)
			( pin "U5D1.AM55"
				( objectStatus "@baseboard_fab2_lib.baseboard_fab2(sch_1):page37_i310:vccin(245)" )
			)
			( pin "U5D1.AM53"
				( objectStatus "@baseboard_fab2_lib.baseboard_fab2(sch_1):page37_i310:vccin(246)" )
			)
			( pin "U5D1.AM33"
				( objectStatus "@baseboard_fab2_lib.baseboard_fab2(sch_1):page37_i310:vccin(247)" )
			)
			( pin "U5D1.AL54"
				( objectStatus "@baseboard_fab2_lib.baseboard_fab2(sch_1):page37_i310:vccin(248)" )
			)
			( pin "U5D1.AL52"
				( objectStatus "@baseboard_fab2_lib.baseboard_fab2(sch_1):page37_i310:vccin(249)" )
			)
			( pin "U5D1.AL50"
				( objectStatus "@baseboard_fab2_lib.baseboard_fab2(sch_1):page37_i310:vccin(250)" )
			)
			( pin "U5D1.AL48"
				( objectStatus "@baseboard_fab2_lib.baseboard_fab2(sch_1):page37_i310:vccin(251)" )
			)
			( pin "U5D1.AL46"
				( objectStatus "@baseboard_fab2_lib.baseboard_fab2(sch_1):page37_i310:vccin(252)" )
			)
			( pin "U5D1.AL34"
				( objectStatus "@baseboard_fab2_lib.baseboard_fab2(sch_1):page37_i310:vccin(253)" )
			)
			( pin "U5D1.AK53"
				( objectStatus "@baseboard_fab2_lib.baseboard_fab2(sch_1):page37_i310:vccin(254)" )
			)
			( pin "U5D1.AK51"
				( objectStatus "@baseboard_fab2_lib.baseboard_fab2(sch_1):page37_i310:vccin(255)" )
			)
			( pin "U5D1.AK49"
				( objectStatus "@baseboard_fab2_lib.baseboard_fab2(sch_1):page37_i310:vccin(256)" )
			)
			( pin "U5D1.AK47"
				( objectStatus "@baseboard_fab2_lib.baseboard_fab2(sch_1):page37_i310:vccin(257)" )
			)
			( pin "U5D1.AK45"
				( objectStatus "@baseboard_fab2_lib.baseboard_fab2(sch_1):page37_i310:vccin(258)" )
			)
			( pin "U5D1.AK35"
				( objectStatus "@baseboard_fab2_lib.baseboard_fab2(sch_1):page37_i310:vccin(259)" )
			)
			( pin "U5D1.AJ36"
				( objectStatus "@baseboard_fab2_lib.baseboard_fab2(sch_1):page37_i310:vccin(260)" )
			)
			( pin "U5D1.AH41"
				( objectStatus "@baseboard_fab2_lib.baseboard_fab2(sch_1):page37_i310:vccin(261)" )
			)
			( pin "U5D1.AH39"
				( objectStatus "@baseboard_fab2_lib.baseboard_fab2(sch_1):page37_i310:vccin(262)" )
			)
			( pin "U5D1.AH37"
				( objectStatus "@baseboard_fab2_lib.baseboard_fab2(sch_1):page37_i310:vccin(263)" )
			)
			( pin "U5D1.AG42"
				( objectStatus "@baseboard_fab2_lib.baseboard_fab2(sch_1):page37_i310:vccin(264)" )
			)
			( pin "U5D1.AG40"
				( objectStatus "@baseboard_fab2_lib.baseboard_fab2(sch_1):page37_i310:vccin(265)" )
			)
			( pin "U5D1.AG38"
				( objectStatus "@baseboard_fab2_lib.baseboard_fab2(sch_1):page37_i310:vccin(266)" )
			)
			( pin "U5D1.AF43"
				( objectStatus "@baseboard_fab2_lib.baseboard_fab2(sch_1):page37_i310:vccin(267)" )
			)
			( pin "U5D1.CY49"
				( objectStatus "@baseboard_fab2_lib.baseboard_fab2(sch_1):page37_i311:vccin(0)" )
			)
			( pin "U5D1.CY47"
				( objectStatus "@baseboard_fab2_lib.baseboard_fab2(sch_1):page37_i311:vccin(1)" )
			)
			( pin "U5D1.CW50"
				( objectStatus "@baseboard_fab2_lib.baseboard_fab2(sch_1):page37_i311:vccin(2)" )
			)
			( pin "U5D1.CW48"
				( objectStatus "@baseboard_fab2_lib.baseboard_fab2(sch_1):page37_i311:vccin(3)" )
			)
			( pin "U5D1.CW46"
				( objectStatus "@baseboard_fab2_lib.baseboard_fab2(sch_1):page37_i311:vccin(4)" )
			)
			( pin "U5D1.CV51"
				( objectStatus "@baseboard_fab2_lib.baseboard_fab2(sch_1):page37_i311:vccin(5)" )
			)
			( pin "U5D1.CU54"
				( objectStatus "@baseboard_fab2_lib.baseboard_fab2(sch_1):page37_i311:vccin(6)" )
			)
			( pin "U5D1.CU52"
				( objectStatus "@baseboard_fab2_lib.baseboard_fab2(sch_1):page37_i311:vccin(7)" )
			)
			( pin "U5D1.CU42"
				( objectStatus "@baseboard_fab2_lib.baseboard_fab2(sch_1):page37_i311:vccin(8)" )
			)
			( pin "U5D1.CU40"
				( objectStatus "@baseboard_fab2_lib.baseboard_fab2(sch_1):page37_i311:vccin(9)" )
			)
			( pin "U5D1.CU38"
				( objectStatus "@baseboard_fab2_lib.baseboard_fab2(sch_1):page37_i311:vccin(10)" )
			)
			( pin "U5D1.CT55"
				( objectStatus "@baseboard_fab2_lib.baseboard_fab2(sch_1):page37_i311:vccin(11)" )
			)
			( pin "U5D1.CT53"
				( objectStatus "@baseboard_fab2_lib.baseboard_fab2(sch_1):page37_i311:vccin(12)" )
			)
			( pin "U5D1.CT41"
				( objectStatus "@baseboard_fab2_lib.baseboard_fab2(sch_1):page37_i311:vccin(13)" )
			)
			( pin "U5D1.CT39"
				( objectStatus "@baseboard_fab2_lib.baseboard_fab2(sch_1):page37_i311:vccin(14)" )
			)
			( pin "U5D1.CT37"
				( objectStatus "@baseboard_fab2_lib.baseboard_fab2(sch_1):page37_i311:vccin(15)" )
			)
			( pin "U5D1.CR56"
				( objectStatus "@baseboard_fab2_lib.baseboard_fab2(sch_1):page37_i311:vccin(16)" )
			)
			( pin "U5D1.CR54"
				( objectStatus "@baseboard_fab2_lib.baseboard_fab2(sch_1):page37_i311:vccin(17)" )
			)
			( pin "U5D1.CR34"
				( objectStatus "@baseboard_fab2_lib.baseboard_fab2(sch_1):page37_i311:vccin(18)" )
			)
			( pin "U5D1.CP57"
				( objectStatus "@baseboard_fab2_lib.baseboard_fab2(sch_1):page37_i311:vccin(19)" )
			)
			( pin "U5D1.CP55"
				( objectStatus "@baseboard_fab2_lib.baseboard_fab2(sch_1):page37_i311:vccin(20)" )
			)
			( pin "U5D1.CP33"
				( objectStatus "@baseboard_fab2_lib.baseboard_fab2(sch_1):page37_i311:vccin(21)" )
			)
			( pin "U5D1.CN58"
				( objectStatus "@baseboard_fab2_lib.baseboard_fab2(sch_1):page37_i311:vccin(22)" )
			)
			( pin "U5D1.CN56"
				( objectStatus "@baseboard_fab2_lib.baseboard_fab2(sch_1):page37_i311:vccin(23)" )
			)
			( pin "U5D1.CM59"
				( objectStatus "@baseboard_fab2_lib.baseboard_fab2(sch_1):page37_i311:vccin(24)" )
			)
			( pin "U5D1.CM57"
				( objectStatus "@baseboard_fab2_lib.baseboard_fab2(sch_1):page37_i311:vccin(25)" )
			)
			( pin "U5D1.CL60"
				( objectStatus "@baseboard_fab2_lib.baseboard_fab2(sch_1):page37_i311:vccin(26)" )
			)
			( pin "U5D1.CL58"
				( objectStatus "@baseboard_fab2_lib.baseboard_fab2(sch_1):page37_i311:vccin(27)" )
			)
			( pin "U5D1.CK61"
				( objectStatus "@baseboard_fab2_lib.baseboard_fab2(sch_1):page37_i311:vccin(28)" )
			)
			( pin "U5D1.CK59"
				( objectStatus "@baseboard_fab2_lib.baseboard_fab2(sch_1):page37_i311:vccin(29)" )
			)
			( pin "U5D1.CJ60"
				( objectStatus "@baseboard_fab2_lib.baseboard_fab2(sch_1):page37_i311:vccin(30)" )
			)
			( pin "U5D1.CH85"
				( objectStatus "@baseboard_fab2_lib.baseboard_fab2(sch_1):page37_i311:vccin(31)" )
			)
			( pin "U5D1.CH61"
				( objectStatus "@baseboard_fab2_lib.baseboard_fab2(sch_1):page37_i311:vccin(32)" )
			)
			( pin "U5D1.CG84"
				( objectStatus "@baseboard_fab2_lib.baseboard_fab2(sch_1):page37_i311:vccin(33)" )
			)
			( pin "U5D1.CG60"
				( objectStatus "@baseboard_fab2_lib.baseboard_fab2(sch_1):page37_i311:vccin(34)" )
			)
			( pin "U5D1.CF85"
				( objectStatus "@baseboard_fab2_lib.baseboard_fab2(sch_1):page37_i311:vccin(35)" )
			)
			( pin "U5D1.CF61"
				( objectStatus "@baseboard_fab2_lib.baseboard_fab2(sch_1):page37_i311:vccin(36)" )
			)
			( pin "U5D1.CE84"
				( objectStatus "@baseboard_fab2_lib.baseboard_fab2(sch_1):page37_i311:vccin(37)" )
			)
			( pin "U5D1.CE60"
				( objectStatus "@baseboard_fab2_lib.baseboard_fab2(sch_1):page37_i311:vccin(38)" )
			)
			( pin "U5D1.CD85"
				( objectStatus "@baseboard_fab2_lib.baseboard_fab2(sch_1):page37_i311:vccin(39)" )
			)
			( pin "U5D1.CD83"
				( objectStatus "@baseboard_fab2_lib.baseboard_fab2(sch_1):page37_i311:vccin(40)" )
			)
			( pin "U5D1.CD61"
				( objectStatus "@baseboard_fab2_lib.baseboard_fab2(sch_1):page37_i311:vccin(41)" )
			)
			( pin "U5D1.CC84"
				( objectStatus "@baseboard_fab2_lib.baseboard_fab2(sch_1):page37_i311:vccin(42)" )
			)
			( pin "U5D1.CC62"
				( objectStatus "@baseboard_fab2_lib.baseboard_fab2(sch_1):page37_i311:vccin(43)" )
			)
			( pin "U5D1.CC60"
				( objectStatus "@baseboard_fab2_lib.baseboard_fab2(sch_1):page37_i311:vccin(44)" )
			)
			( pin "U5D1.CB83"
				( objectStatus "@baseboard_fab2_lib.baseboard_fab2(sch_1):page37_i311:vccin(45)" )
			)
			( pin "U5D1.CB81"
				( objectStatus "@baseboard_fab2_lib.baseboard_fab2(sch_1):page37_i311:vccin(46)" )
			)
			( pin "U5D1.CB79"
				( objectStatus "@baseboard_fab2_lib.baseboard_fab2(sch_1):page37_i311:vccin(47)" )
			)
			( pin "U5D1.CB77"
				( objectStatus "@baseboard_fab2_lib.baseboard_fab2(sch_1):page37_i311:vccin(48)" )
			)
			( pin "U5D1.CB75"
				( objectStatus "@baseboard_fab2_lib.baseboard_fab2(sch_1):page37_i311:vccin(49)" )
			)
			( pin "U5D1.CB73"
				( objectStatus "@baseboard_fab2_lib.baseboard_fab2(sch_1):page37_i311:vccin(50)" )
			)
			( pin "U5D1.CB61"
				( objectStatus "@baseboard_fab2_lib.baseboard_fab2(sch_1):page37_i311:vccin(51)" )
			)
			( pin "U5D1.CA84"
				( objectStatus "@baseboard_fab2_lib.baseboard_fab2(sch_1):page37_i311:vccin(52)" )
			)
			( pin "U5D1.CA82"
				( objectStatus "@baseboard_fab2_lib.baseboard_fab2(sch_1):page37_i311:vccin(53)" )
			)
			( pin "U5D1.CA80"
				( objectStatus "@baseboard_fab2_lib.baseboard_fab2(sch_1):page37_i311:vccin(54)" )
			)
			( pin "U5D1.CA78"
				( objectStatus "@baseboard_fab2_lib.baseboard_fab2(sch_1):page37_i311:vccin(55)" )
			)
			( pin "U5D1.CA76"
				( objectStatus "@baseboard_fab2_lib.baseboard_fab2(sch_1):page37_i311:vccin(56)" )
			)
			( pin "U5D1.CA74"
				( objectStatus "@baseboard_fab2_lib.baseboard_fab2(sch_1):page37_i311:vccin(57)" )
			)
			( pin "U5D1.CA72"
				( objectStatus "@baseboard_fab2_lib.baseboard_fab2(sch_1):page37_i311:vccin(58)" )
			)
			( pin "U5D1.CA62"
				( objectStatus "@baseboard_fab2_lib.baseboard_fab2(sch_1):page37_i311:vccin(59)" )
			)
			( pin "U5D1.CA60"
				( objectStatus "@baseboard_fab2_lib.baseboard_fab2(sch_1):page37_i311:vccin(60)" )
			)
			( pin "U5D1.BY83"
				( objectStatus "@baseboard_fab2_lib.baseboard_fab2(sch_1):page37_i311:vccin(61)" )
			)
			( pin "U5D1.BY81"
				( objectStatus "@baseboard_fab2_lib.baseboard_fab2(sch_1):page37_i311:vccin(62)" )
			)
			( pin "U5D1.BY79"
				( objectStatus "@baseboard_fab2_lib.baseboard_fab2(sch_1):page37_i311:vccin(63)" )
			)
			( pin "U5D1.BY77"
				( objectStatus "@baseboard_fab2_lib.baseboard_fab2(sch_1):page37_i311:vccin(64)" )
			)
			( pin "U5D1.BY75"
				( objectStatus "@baseboard_fab2_lib.baseboard_fab2(sch_1):page37_i311:vccin(65)" )
			)
			( pin "U5D1.BY73"
				( objectStatus "@baseboard_fab2_lib.baseboard_fab2(sch_1):page37_i311:vccin(66)" )
			)
			( pin "U5D1.BY61"
				( objectStatus "@baseboard_fab2_lib.baseboard_fab2(sch_1):page37_i311:vccin(67)" )
			)
			( pin "U5D1.BW84"
				( objectStatus "@baseboard_fab2_lib.baseboard_fab2(sch_1):page37_i311:vccin(68)" )
			)
			( pin "U5D1.BW70"
				( objectStatus "@baseboard_fab2_lib.baseboard_fab2(sch_1):page37_i311:vccin(69)" )
			)
			( pin "U5D1.BW68"
				( objectStatus "@baseboard_fab2_lib.baseboard_fab2(sch_1):page37_i311:vccin(70)" )
			)
			( pin "U5D1.BW66"
				( objectStatus "@baseboard_fab2_lib.baseboard_fab2(sch_1):page37_i311:vccin(71)" )
			)
			( pin "U5D1.BW64"
				( objectStatus "@baseboard_fab2_lib.baseboard_fab2(sch_1):page37_i311:vccin(72)" )
			)
			( pin "U5D1.BW62"
				( objectStatus "@baseboard_fab2_lib.baseboard_fab2(sch_1):page37_i311:vccin(73)" )
			)
			( pin "U5D1.BW60"
				( objectStatus "@baseboard_fab2_lib.baseboard_fab2(sch_1):page37_i311:vccin(74)" )
			)
			( pin "U5D1.BV83"
				( objectStatus "@baseboard_fab2_lib.baseboard_fab2(sch_1):page37_i311:vccin(75)" )
			)
			( pin "U5D1.BV81"
				( objectStatus "@baseboard_fab2_lib.baseboard_fab2(sch_1):page37_i311:vccin(76)" )
			)
			( pin "U5D1.BV79"
				( objectStatus "@baseboard_fab2_lib.baseboard_fab2(sch_1):page37_i311:vccin(77)" )
			)
			( pin "U5D1.BV77"
				( objectStatus "@baseboard_fab2_lib.baseboard_fab2(sch_1):page37_i311:vccin(78)" )
			)
			( pin "U5D1.BV75"
				( objectStatus "@baseboard_fab2_lib.baseboard_fab2(sch_1):page37_i311:vccin(79)" )
			)
			( pin "U5D1.BV73"
				( objectStatus "@baseboard_fab2_lib.baseboard_fab2(sch_1):page37_i311:vccin(80)" )
			)
			( pin "U5D1.BV71"
				( objectStatus "@baseboard_fab2_lib.baseboard_fab2(sch_1):page37_i311:vccin(81)" )
			)
			( pin "U5D1.BV69"
				( objectStatus "@baseboard_fab2_lib.baseboard_fab2(sch_1):page37_i311:vccin(82)" )
			)
			( pin "U5D1.BV67"
				( objectStatus "@baseboard_fab2_lib.baseboard_fab2(sch_1):page37_i311:vccin(83)" )
			)
			( pin "U5D1.BV65"
				( objectStatus "@baseboard_fab2_lib.baseboard_fab2(sch_1):page37_i311:vccin(84)" )
			)
			( pin "U5D1.BV63"
				( objectStatus "@baseboard_fab2_lib.baseboard_fab2(sch_1):page37_i311:vccin(85)" )
			)
			( pin "U5D1.BV61"
				( objectStatus "@baseboard_fab2_lib.baseboard_fab2(sch_1):page37_i311:vccin(86)" )
			)
			( pin "U5D1.BU84"
				( objectStatus "@baseboard_fab2_lib.baseboard_fab2(sch_1):page37_i311:vccin(87)" )
			)
			( pin "U5D1.BU82"
				( objectStatus "@baseboard_fab2_lib.baseboard_fab2(sch_1):page37_i311:vccin(88)" )
			)
			( pin "U5D1.BU80"
				( objectStatus "@baseboard_fab2_lib.baseboard_fab2(sch_1):page37_i311:vccin(89)" )
			)
			( pin "U5D1.BU78"
				( objectStatus "@baseboard_fab2_lib.baseboard_fab2(sch_1):page37_i311:vccin(90)" )
			)
			( pin "U5D1.BU76"
				( objectStatus "@baseboard_fab2_lib.baseboard_fab2(sch_1):page37_i311:vccin(91)" )
			)
			( pin "U5D1.BU74"
				( objectStatus "@baseboard_fab2_lib.baseboard_fab2(sch_1):page37_i311:vccin(92)" )
			)
			( pin "U5D1.BU72"
				( objectStatus "@baseboard_fab2_lib.baseboard_fab2(sch_1):page37_i311:vccin(93)" )
			)
			( pin "U5D1.BU70"
				( objectStatus "@baseboard_fab2_lib.baseboard_fab2(sch_1):page37_i311:vccin(94)" )
			)
			( pin "U5D1.BU68"
				( objectStatus "@baseboard_fab2_lib.baseboard_fab2(sch_1):page37_i311:vccin(95)" )
			)
			( pin "U5D1.BU66"
				( objectStatus "@baseboard_fab2_lib.baseboard_fab2(sch_1):page37_i311:vccin(96)" )
			)
			( pin "U5D1.BU64"
				( objectStatus "@baseboard_fab2_lib.baseboard_fab2(sch_1):page37_i311:vccin(97)" )
			)
			( pin "U5D1.BU62"
				( objectStatus "@baseboard_fab2_lib.baseboard_fab2(sch_1):page37_i311:vccin(98)" )
			)
			( pin "U5D1.BU60"
				( objectStatus "@baseboard_fab2_lib.baseboard_fab2(sch_1):page37_i311:vccin(99)" )
			)
			( pin "U5D1.BT83"
				( objectStatus "@baseboard_fab2_lib.baseboard_fab2(sch_1):page37_i311:vccin(100)" )
			)
			( pin "U5D1.BT81"
				( objectStatus "@baseboard_fab2_lib.baseboard_fab2(sch_1):page37_i311:vccin(101)" )
			)
			( pin "U5D1.BT79"
				( objectStatus "@baseboard_fab2_lib.baseboard_fab2(sch_1):page37_i311:vccin(102)" )
			)
			( pin "U5D1.BT77"
				( objectStatus "@baseboard_fab2_lib.baseboard_fab2(sch_1):page37_i311:vccin(103)" )
			)
			( pin "U5D1.BT75"
				( objectStatus "@baseboard_fab2_lib.baseboard_fab2(sch_1):page37_i311:vccin(104)" )
			)
			( pin "U5D1.BT73"
				( objectStatus "@baseboard_fab2_lib.baseboard_fab2(sch_1):page37_i311:vccin(105)" )
			)
			( pin "U5D1.BT71"
				( objectStatus "@baseboard_fab2_lib.baseboard_fab2(sch_1):page37_i311:vccin(106)" )
			)
			( pin "U5D1.BT69"
				( objectStatus "@baseboard_fab2_lib.baseboard_fab2(sch_1):page37_i311:vccin(107)" )
			)
			( pin "U5D1.BT67"
				( objectStatus "@baseboard_fab2_lib.baseboard_fab2(sch_1):page37_i311:vccin(108)" )
			)
			( pin "U5D1.BT65"
				( objectStatus "@baseboard_fab2_lib.baseboard_fab2(sch_1):page37_i311:vccin(109)" )
			)
			( pin "U5D1.BT63"
				( objectStatus "@baseboard_fab2_lib.baseboard_fab2(sch_1):page37_i311:vccin(110)" )
			)
			( pin "U5D1.BT61"
				( objectStatus "@baseboard_fab2_lib.baseboard_fab2(sch_1):page37_i311:vccin(111)" )
			)
			( pin "U5D1.BR84"
				( objectStatus "@baseboard_fab2_lib.baseboard_fab2(sch_1):page37_i311:vccin(112)" )
			)
			( pin "U5D1.BR62"
				( objectStatus "@baseboard_fab2_lib.baseboard_fab2(sch_1):page37_i311:vccin(113)" )
			)
			( pin "U5D1.BR60"
				( objectStatus "@baseboard_fab2_lib.baseboard_fab2(sch_1):page37_i311:vccin(114)" )
			)
			( pin "U5D1.BP83"
				( objectStatus "@baseboard_fab2_lib.baseboard_fab2(sch_1):page37_i311:vccin(115)" )
			)
			( pin "U5D1.BP81"
				( objectStatus "@baseboard_fab2_lib.baseboard_fab2(sch_1):page37_i311:vccin(116)" )
			)
			( pin "U5D1.BP79"
				( objectStatus "@baseboard_fab2_lib.baseboard_fab2(sch_1):page37_i311:vccin(117)" )
			)
			( pin "U5D1.BP77"
				( objectStatus "@baseboard_fab2_lib.baseboard_fab2(sch_1):page37_i311:vccin(118)" )
			)
			( pin "U5D1.BP75"
				( objectStatus "@baseboard_fab2_lib.baseboard_fab2(sch_1):page37_i311:vccin(119)" )
			)
			( pin "U5D1.BP73"
				( objectStatus "@baseboard_fab2_lib.baseboard_fab2(sch_1):page37_i311:vccin(120)" )
			)
			( pin "U5D1.BP71"
				( objectStatus "@baseboard_fab2_lib.baseboard_fab2(sch_1):page37_i311:vccin(121)" )
			)
			( pin "U5D1.BP69"
				( objectStatus "@baseboard_fab2_lib.baseboard_fab2(sch_1):page37_i311:vccin(122)" )
			)
			( pin "U5D1.BP67"
				( objectStatus "@baseboard_fab2_lib.baseboard_fab2(sch_1):page37_i311:vccin(123)" )
			)
			( pin "U5D1.BP65"
				( objectStatus "@baseboard_fab2_lib.baseboard_fab2(sch_1):page37_i311:vccin(124)" )
			)
			( pin "U5D1.BP63"
				( objectStatus "@baseboard_fab2_lib.baseboard_fab2(sch_1):page37_i311:vccin(125)" )
			)
			( pin "U5D1.BP61"
				( objectStatus "@baseboard_fab2_lib.baseboard_fab2(sch_1):page37_i311:vccin(126)" )
			)
			( pin "U5D1.BN84"
				( objectStatus "@baseboard_fab2_lib.baseboard_fab2(sch_1):page37_i311:vccin(127)" )
			)
			( pin "U5D1.BN82"
				( objectStatus "@baseboard_fab2_lib.baseboard_fab2(sch_1):page37_i311:vccin(128)" )
			)
			( pin "U5D1.BN80"
				( objectStatus "@baseboard_fab2_lib.baseboard_fab2(sch_1):page37_i311:vccin(129)" )
			)
			( pin "U5D1.BA86"
				( objectStatus "@baseboard_fab2_lib.baseboard_fab2(sch_1):page37_i311:vccin_sense" )
			)
			( pin "U5D1.AW86"
				( objectStatus "@baseboard_fab2_lib.baseboard_fab2(sch_1):page37_i311:vccinpmax(0)" )
			)
			( pin "U5D1.AV85"
				( objectStatus "@baseboard_fab2_lib.baseboard_fab2(sch_1):page37_i311:vccinpmax(1)" )
			)
			( pin "U5D1.AD41"
				( objectStatus "@baseboard_fab2_lib.baseboard_fab2(sch_1):page37_i311:vsensepmax" )
			)
			( pin "U5D1.AY85"
				( objectStatus "@baseboard_fab2_lib.baseboard_fab2(sch_1):page37_i311:vss_vccin_sense" )
			)
			( pin "R5D6.1"
				( objectStatus "@baseboard_fab2_lib.baseboard_fab2(sch_1):page37_i312:a" )
			)
			( pin "R5D6.2"
				( objectStatus "@baseboard_fab2_lib.baseboard_fab2(sch_1):page37_i312:b" )
			)
			( pin "C6D1.1"
				( objectStatus "@baseboard_fab2_lib.baseboard_fab2(sch_1):page38_i19:a" )
			)
			( pin "C6D1.2"
				( objectStatus "@baseboard_fab2_lib.baseboard_fab2(sch_1):page38_i19:b" )
			)
			( pin "U5D1.B49"
				( objectStatus "@baseboard_fab2_lib.baseboard_fab2(sch_1):page38_i33:vccd012(0)" )
			)
			( pin "U5D1.B53"
				( objectStatus "@baseboard_fab2_lib.baseboard_fab2(sch_1):page38_i33:vccd012(1)" )
			)
			( pin "U5D1.B59"
				( objectStatus "@baseboard_fab2_lib.baseboard_fab2(sch_1):page38_i33:vccd012(2)" )
			)
			( pin "U5D1.E46"
				( objectStatus "@baseboard_fab2_lib.baseboard_fab2(sch_1):page38_i33:vccd012(3)" )
			)
			( pin "U5D1.E48"
				( objectStatus "@baseboard_fab2_lib.baseboard_fab2(sch_1):page38_i33:vccd012(4)" )
			)
			( pin "U5D1.E50"
				( objectStatus "@baseboard_fab2_lib.baseboard_fab2(sch_1):page38_i33:vccd012(5)" )
			)
			( pin "U5D1.E52"
				( objectStatus "@baseboard_fab2_lib.baseboard_fab2(sch_1):page38_i33:vccd012(6)" )
			)
			( pin "U5D1.E54"
				( objectStatus "@baseboard_fab2_lib.baseboard_fab2(sch_1):page38_i33:vccd012(7)" )
			)
			( pin "U5D1.E56"
				( objectStatus "@baseboard_fab2_lib.baseboard_fab2(sch_1):page38_i33:vccd012(8)" )
			)
			( pin "U5D1.E58"
				( objectStatus "@baseboard_fab2_lib.baseboard_fab2(sch_1):page38_i33:vccd012(9)" )
			)
			( pin "U5D1.E60"
				( objectStatus "@baseboard_fab2_lib.baseboard_fab2(sch_1):page38_i33:vccd012(10)" )
			)
			( pin "U5D1.E62"
				( objectStatus "@baseboard_fab2_lib.baseboard_fab2(sch_1):page38_i33:vccd012(11)" )
			)
			( pin "U5D1.E64"
				( objectStatus "@baseboard_fab2_lib.baseboard_fab2(sch_1):page38_i33:vccd012(12)" )
			)
			( pin "U5D1.L46"
				( objectStatus "@baseboard_fab2_lib.baseboard_fab2(sch_1):page38_i33:vccd012(13)" )
			)
			( pin "U5D1.L48"
				( objectStatus "@baseboard_fab2_lib.baseboard_fab2(sch_1):page38_i33:vccd012(14)" )
			)
			( pin "U5D1.L50"
				( objectStatus "@baseboard_fab2_lib.baseboard_fab2(sch_1):page38_i33:vccd012(15)" )
			)
			( pin "U5D1.L52"
				( objectStatus "@baseboard_fab2_lib.baseboard_fab2(sch_1):page38_i33:vccd012(16)" )
			)
			( pin "U5D1.L54"
				( objectStatus "@baseboard_fab2_lib.baseboard_fab2(sch_1):page38_i33:vccd012(17)" )
			)
			( pin "U5D1.L56"
				( objectStatus "@baseboard_fab2_lib.baseboard_fab2(sch_1):page38_i33:vccd012(18)" )
			)
			( pin "U5D1.L58"
				( objectStatus "@baseboard_fab2_lib.baseboard_fab2(sch_1):page38_i33:vccd012(19)" )
			)
			( pin "U5D1.L60"
				( objectStatus "@baseboard_fab2_lib.baseboard_fab2(sch_1):page38_i33:vccd012(20)" )
			)
			( pin "U5D1.L62"
				( objectStatus "@baseboard_fab2_lib.baseboard_fab2(sch_1):page38_i33:vccd012(21)" )
			)
			( pin "U5D1.N64"
				( objectStatus "@baseboard_fab2_lib.baseboard_fab2(sch_1):page38_i33:vccd012(22)" )
			)
			( pin "U5D1.U46"
				( objectStatus "@baseboard_fab2_lib.baseboard_fab2(sch_1):page38_i33:vccd012(23)" )
			)
			( pin "U5D1.U48"
				( objectStatus "@baseboard_fab2_lib.baseboard_fab2(sch_1):page38_i33:vccd012(24)" )
			)
			( pin "U5D1.U50"
				( objectStatus "@baseboard_fab2_lib.baseboard_fab2(sch_1):page38_i33:vccd012(25)" )
			)
			( pin "U5D1.U52"
				( objectStatus "@baseboard_fab2_lib.baseboard_fab2(sch_1):page38_i33:vccd012(26)" )
			)
			( pin "U5D1.U54"
				( objectStatus "@baseboard_fab2_lib.baseboard_fab2(sch_1):page38_i33:vccd012(27)" )
			)
			( pin "U5D1.U56"
				( objectStatus "@baseboard_fab2_lib.baseboard_fab2(sch_1):page38_i33:vccd012(28)" )
			)
			( pin "U5D1.U58"
				( objectStatus "@baseboard_fab2_lib.baseboard_fab2(sch_1):page38_i33:vccd012(29)" )
			)
			( pin "U5D1.U60"
				( objectStatus "@baseboard_fab2_lib.baseboard_fab2(sch_1):page38_i33:vccd012(30)" )
			)
			( pin "U5D1.U62"
				( objectStatus "@baseboard_fab2_lib.baseboard_fab2(sch_1):page38_i33:vccd012(31)" )
			)
			( pin "U5D1.W64"
				( objectStatus "@baseboard_fab2_lib.baseboard_fab2(sch_1):page38_i33:vccd012(32)" )
			)
			( pin "U5D1.Y45"
				( objectStatus "@baseboard_fab2_lib.baseboard_fab2(sch_1):page38_i33:vccd012(33)" )
			)
			( pin "U5D1.Y47"
				( objectStatus "@baseboard_fab2_lib.baseboard_fab2(sch_1):page38_i33:vccd012(34)" )
			)
			( pin "U5D1.Y49"
				( objectStatus "@baseboard_fab2_lib.baseboard_fab2(sch_1):page38_i33:vccd012(35)" )
			)
			( pin "U5D1.Y51"
				( objectStatus "@baseboard_fab2_lib.baseboard_fab2(sch_1):page38_i33:vccd012(36)" )
			)
			( pin "U5D1.Y53"
				( objectStatus "@baseboard_fab2_lib.baseboard_fab2(sch_1):page38_i33:vccd012(37)" )
			)
			( pin "U5D1.Y55"
				( objectStatus "@baseboard_fab2_lib.baseboard_fab2(sch_1):page38_i33:vccd012(38)" )
			)
			( pin "U5D1.Y57"
				( objectStatus "@baseboard_fab2_lib.baseboard_fab2(sch_1):page38_i33:vccd012(39)" )
			)
			( pin "U5D1.Y59"
				( objectStatus "@baseboard_fab2_lib.baseboard_fab2(sch_1):page38_i33:vccd012(40)" )
			)
			( pin "U5D1.Y61"
				( objectStatus "@baseboard_fab2_lib.baseboard_fab2(sch_1):page38_i33:vccd012(41)" )
			)
			( pin "U5D1.Y63"
				( objectStatus "@baseboard_fab2_lib.baseboard_fab2(sch_1):page38_i33:vccd012(42)" )
			)
			( pin "U5D1.AD45"
				( objectStatus "@baseboard_fab2_lib.baseboard_fab2(sch_1):page38_i33:vccd012(43)" )
			)
			( pin "U5D1.AF55"
				( objectStatus "@baseboard_fab2_lib.baseboard_fab2(sch_1):page38_i33:vccd012(44)" )
			)
			( pin "U5D1.AF57"
				( objectStatus "@baseboard_fab2_lib.baseboard_fab2(sch_1):page38_i33:vccd012(45)" )
			)
			( pin "U5D1.AF59"
				( objectStatus "@baseboard_fab2_lib.baseboard_fab2(sch_1):page38_i33:vccd012(46)" )
			)
			( pin "U5D1.AF61"
				( objectStatus "@baseboard_fab2_lib.baseboard_fab2(sch_1):page38_i33:vccd012(47)" )
			)
			( pin "U5D1.AF63"
				( objectStatus "@baseboard_fab2_lib.baseboard_fab2(sch_1):page38_i33:vccd012(48)" )
			)
			( pin "U5D1.D45"
				( objectStatus "@baseboard_fab2_lib.baseboard_fab2(sch_1):page38_i33:vccd012(49)" )
			)
			( pin "U5D1.C46"
				( objectStatus "@baseboard_fab2_lib.baseboard_fab2(sch_1):page38_i33:vccd012(50)" )
			)
			( pin "U5D1.B47"
				( objectStatus "@baseboard_fab2_lib.baseboard_fab2(sch_1):page38_i33:vccd012(51)" )
			)
			( pin "U5D1.EF59"
				( objectStatus "@baseboard_fab2_lib.baseboard_fab2(sch_1):page38_i33:vccd345(0)" )
			)
			( pin "U5D1.EF53"
				( objectStatus "@baseboard_fab2_lib.baseboard_fab2(sch_1):page38_i33:vccd345(1)" )
			)
			( pin "U5D1.EF49"
				( objectStatus "@baseboard_fab2_lib.baseboard_fab2(sch_1):page38_i33:vccd345(2)" )
			)
			( pin "U5D1.EC62"
				( objectStatus "@baseboard_fab2_lib.baseboard_fab2(sch_1):page38_i33:vccd345(3)" )
			)
			( pin "U5D1.EC60"
				( objectStatus "@baseboard_fab2_lib.baseboard_fab2(sch_1):page38_i33:vccd345(4)" )
			)
			( pin "U5D1.EC58"
				( objectStatus "@baseboard_fab2_lib.baseboard_fab2(sch_1):page38_i33:vccd345(5)" )
			)
			( pin "U5D1.EC56"
				( objectStatus "@baseboard_fab2_lib.baseboard_fab2(sch_1):page38_i33:vccd345(6)" )
			)
			( pin "U5D1.EC54"
				( objectStatus "@baseboard_fab2_lib.baseboard_fab2(sch_1):page38_i33:vccd345(7)" )
			)
			( pin "U5D1.EC52"
				( objectStatus "@baseboard_fab2_lib.baseboard_fab2(sch_1):page38_i33:vccd345(8)" )
			)
			( pin "U5D1.EC50"
				( objectStatus "@baseboard_fab2_lib.baseboard_fab2(sch_1):page38_i33:vccd345(9)" )
			)
			( pin "U5D1.EC48"
				( objectStatus "@baseboard_fab2_lib.baseboard_fab2(sch_1):page38_i33:vccd345(10)" )
			)
			( pin "U5D1.EC46"
				( objectStatus "@baseboard_fab2_lib.baseboard_fab2(sch_1):page38_i33:vccd345(11)" )
			)
			( pin "U5D1.DU64"
				( objectStatus "@baseboard_fab2_lib.baseboard_fab2(sch_1):page38_i33:vccd345(12)" )
			)
			( pin "U5D1.DU62"
				( objectStatus "@baseboard_fab2_lib.baseboard_fab2(sch_1):page38_i33:vccd345(13)" )
			)
			( pin "U5D1.DU60"
				( objectStatus "@baseboard_fab2_lib.baseboard_fab2(sch_1):page38_i33:vccd345(14)" )
			)
			( pin "U5D1.DU58"
				( objectStatus "@baseboard_fab2_lib.baseboard_fab2(sch_1):page38_i33:vccd345(15)" )
			)
			( pin "U5D1.DU56"
				( objectStatus "@baseboard_fab2_lib.baseboard_fab2(sch_1):page38_i33:vccd345(16)" )
			)
			( pin "U5D1.DU54"
				( objectStatus "@baseboard_fab2_lib.baseboard_fab2(sch_1):page38_i33:vccd345(17)" )
			)
			( pin "U5D1.DU52"
				( objectStatus "@baseboard_fab2_lib.baseboard_fab2(sch_1):page38_i33:vccd345(18)" )
			)
			( pin "U5D1.DU50"
				( objectStatus "@baseboard_fab2_lib.baseboard_fab2(sch_1):page38_i33:vccd345(19)" )
			)
			( pin "U5D1.DU48"
				( objectStatus "@baseboard_fab2_lib.baseboard_fab2(sch_1):page38_i33:vccd345(20)" )
			)
			( pin "U5D1.DU46"
				( objectStatus "@baseboard_fab2_lib.baseboard_fab2(sch_1):page38_i33:vccd345(21)" )
			)
			( pin "U5D1.DL62"
				( objectStatus "@baseboard_fab2_lib.baseboard_fab2(sch_1):page38_i33:vccd345(22)" )
			)
			( pin "U5D1.DL60"
				( objectStatus "@baseboard_fab2_lib.baseboard_fab2(sch_1):page38_i33:vccd345(23)" )
			)
			( pin "U5D1.DL58"
				( objectStatus "@baseboard_fab2_lib.baseboard_fab2(sch_1):page38_i33:vccd345(24)" )
			)
			( pin "U5D1.DL56"
				( objectStatus "@baseboard_fab2_lib.baseboard_fab2(sch_1):page38_i33:vccd345(25)" )
			)
			( pin "U5D1.DL54"
				( objectStatus "@baseboard_fab2_lib.baseboard_fab2(sch_1):page38_i33:vccd345(26)" )
			)
			( pin "U5D1.DL52"
				( objectStatus "@baseboard_fab2_lib.baseboard_fab2(sch_1):page38_i33:vccd345(27)" )
			)
			( pin "U5D1.DL50"
				( objectStatus "@baseboard_fab2_lib.baseboard_fab2(sch_1):page38_i33:vccd345(28)" )
			)
			( pin "U5D1.DL48"
				( objectStatus "@baseboard_fab2_lib.baseboard_fab2(sch_1):page38_i33:vccd345(29)" )
			)
			( pin "U5D1.DL46"
				( objectStatus "@baseboard_fab2_lib.baseboard_fab2(sch_1):page38_i33:vccd345(30)" )
			)
			( pin "U5D1.DJ64"
				( objectStatus "@baseboard_fab2_lib.baseboard_fab2(sch_1):page38_i33:vccd345(31)" )
			)
			( pin "U5D1.DH63"
				( objectStatus "@baseboard_fab2_lib.baseboard_fab2(sch_1):page38_i33:vccd345(32)" )
			)
			( pin "U5D1.DH61"
				( objectStatus "@baseboard_fab2_lib.baseboard_fab2(sch_1):page38_i33:vccd345(33)" )
			)
			( pin "U5D1.DH59"
				( objectStatus "@baseboard_fab2_lib.baseboard_fab2(sch_1):page38_i33:vccd345(34)" )
			)
			( pin "U5D1.DH57"
				( objectStatus "@baseboard_fab2_lib.baseboard_fab2(sch_1):page38_i33:vccd345(35)" )
			)
			( pin "U5D1.DH55"
				( objectStatus "@baseboard_fab2_lib.baseboard_fab2(sch_1):page38_i33:vccd345(36)" )
			)
			( pin "U5D1.DH53"
				( objectStatus "@baseboard_fab2_lib.baseboard_fab2(sch_1):page38_i33:vccd345(37)" )
			)
			( pin "U5D1.DH51"
				( objectStatus "@baseboard_fab2_lib.baseboard_fab2(sch_1):page38_i33:vccd345(38)" )
			)
			( pin "U5D1.DH49"
				( objectStatus "@baseboard_fab2_lib.baseboard_fab2(sch_1):page38_i33:vccd345(39)" )
			)
			( pin "U5D1.DH47"
				( objectStatus "@baseboard_fab2_lib.baseboard_fab2(sch_1):page38_i33:vccd345(40)" )
			)
			( pin "U5D1.DH45"
				( objectStatus "@baseboard_fab2_lib.baseboard_fab2(sch_1):page38_i33:vccd345(41)" )
			)
			( pin "U5D1.DD45"
				( objectStatus "@baseboard_fab2_lib.baseboard_fab2(sch_1):page38_i33:vccd345(42)" )
			)
			( pin "U5D1.DB63"
				( objectStatus "@baseboard_fab2_lib.baseboard_fab2(sch_1):page38_i33:vccd345(43)" )
			)
			( pin "U5D1.DB61"
				( objectStatus "@baseboard_fab2_lib.baseboard_fab2(sch_1):page38_i33:vccd345(44)" )
			)
			( pin "U5D1.DB59"
				( objectStatus "@baseboard_fab2_lib.baseboard_fab2(sch_1):page38_i33:vccd345(45)" )
			)
			( pin "U5D1.DB57"
				( objectStatus "@baseboard_fab2_lib.baseboard_fab2(sch_1):page38_i33:vccd345(46)" )
			)
			( pin "U5D1.DB55"
				( objectStatus "@baseboard_fab2_lib.baseboard_fab2(sch_1):page38_i33:vccd345(47)" )
			)
			( pin "U5D1.DB53"
				( objectStatus "@baseboard_fab2_lib.baseboard_fab2(sch_1):page38_i33:vccd345(48)" )
			)
			( pin "U5D1.EF45"
				( objectStatus "@baseboard_fab2_lib.baseboard_fab2(sch_1):page38_i33:vccd345(49)" )
			)
			( pin "U5D1.EE44"
				( objectStatus "@baseboard_fab2_lib.baseboard_fab2(sch_1):page38_i33:vccd345(50)" )
			)
			( pin "U5D1.BL14"
				( objectStatus "@baseboard_fab2_lib.baseboard_fab2(sch_1):page38_i34:cd_vcc_core(0)" )
			)
			( pin "U5D1.BK15"
				( objectStatus "@baseboard_fab2_lib.baseboard_fab2(sch_1):page38_i34:cd_vcc_core(1)" )
			)
			( pin "U5D1.BK13"
				( objectStatus "@baseboard_fab2_lib.baseboard_fab2(sch_1):page38_i34:cd_vcc_core(2)" )
			)
			( pin "U5D1.BJ14"
				( objectStatus "@baseboard_fab2_lib.baseboard_fab2(sch_1):page38_i34:cd_vcc_core(3)" )
			)
			( pin "U5D1.BJ12"
				( objectStatus "@baseboard_fab2_lib.baseboard_fab2(sch_1):page38_i34:cd_vcc_core(4)" )
			)
			( pin "U5D1.BH13"
				( objectStatus "@baseboard_fab2_lib.baseboard_fab2(sch_1):page38_i34:cd_vcc_core(5)" )
			)
			( pin "U5D1.BG14"
				( objectStatus "@baseboard_fab2_lib.baseboard_fab2(sch_1):page38_i34:cd_vcc_core(6)" )
			)
			( pin "U5D1.BG12"
				( objectStatus "@baseboard_fab2_lib.baseboard_fab2(sch_1):page38_i34:cd_vcc_core(7)" )
			)
			( pin "U5D1.BF13"
				( objectStatus "@baseboard_fab2_lib.baseboard_fab2(sch_1):page38_i34:cd_vcc_core(8)" )
			)
			( pin "U5D1.BF11"
				( objectStatus "@baseboard_fab2_lib.baseboard_fab2(sch_1):page38_i34:cd_vcc_core(9)" )
			)
			( pin "U5D1.BE14"
				( objectStatus "@baseboard_fab2_lib.baseboard_fab2(sch_1):page38_i34:cd_vcc_core(10)" )
			)
			( pin "U5D1.BE12"
				( objectStatus "@baseboard_fab2_lib.baseboard_fab2(sch_1):page38_i34:cd_vcc_core(11)" )
			)
			( pin "U5D1.BD13"
				( objectStatus "@baseboard_fab2_lib.baseboard_fab2(sch_1):page38_i34:cd_vcc_core(12)" )
			)
			( pin "U5D1.BT27"
				( objectStatus "@baseboard_fab2_lib.baseboard_fab2(sch_1):page38_i34:cd_vccin(0)" )
			)
			( pin "U5D1.BU26"
				( objectStatus "@baseboard_fab2_lib.baseboard_fab2(sch_1):page38_i34:cd_vccin(1)" )
			)
			( pin "U5D1.BV27"
				( objectStatus "@baseboard_fab2_lib.baseboard_fab2(sch_1):page38_i34:cd_vccin(2)" )
			)
			( pin "U5D1.BY27"
				( objectStatus "@baseboard_fab2_lib.baseboard_fab2(sch_1):page38_i34:cd_vccin(3)" )
			)
			( pin "U5D1.BV15"
				( objectStatus "@baseboard_fab2_lib.baseboard_fab2(sch_1):page38_i34:cd_vccp(0)" )
			)
			( pin "U5D1.BV13"
				( objectStatus "@baseboard_fab2_lib.baseboard_fab2(sch_1):page38_i34:cd_vccp(1)" )
			)
			( pin "U5D1.BV11"
				( objectStatus "@baseboard_fab2_lib.baseboard_fab2(sch_1):page38_i34:cd_vccp(2)" )
			)
			( pin "U5D1.BU14"
				( objectStatus "@baseboard_fab2_lib.baseboard_fab2(sch_1):page38_i34:cd_vccp(3)" )
			)
			( pin "U5D1.BU12"
				( objectStatus "@baseboard_fab2_lib.baseboard_fab2(sch_1):page38_i34:cd_vccp(4)" )
			)
			( pin "U5D1.BT15"
				( objectStatus "@baseboard_fab2_lib.baseboard_fab2(sch_1):page38_i34:cd_vccp(5)" )
			)
			( pin "U5D1.BT13"
				( objectStatus "@baseboard_fab2_lib.baseboard_fab2(sch_1):page38_i34:cd_vccp(6)" )
			)
			( pin "U5D1.BT11"
				( objectStatus "@baseboard_fab2_lib.baseboard_fab2(sch_1):page38_i34:cd_vccp(7)" )
			)
			( pin "U5D1.BR14"
				( objectStatus "@baseboard_fab2_lib.baseboard_fab2(sch_1):page38_i34:cd_vccp(8)" )
			)
			( pin "U5D1.BR12"
				( objectStatus "@baseboard_fab2_lib.baseboard_fab2(sch_1):page38_i34:cd_vccp(9)" )
			)
			( pin "U5D1.BP15"
				( objectStatus "@baseboard_fab2_lib.baseboard_fab2(sch_1):page38_i34:cd_vccp(10)" )
			)
			( pin "U5D1.BP13"
				( objectStatus "@baseboard_fab2_lib.baseboard_fab2(sch_1):page38_i34:cd_vccp(11)" )
			)
			( pin "U5D1.BP11"
				( objectStatus "@baseboard_fab2_lib.baseboard_fab2(sch_1):page38_i34:cd_vccp(12)" )
			)
			( pin "U5D1.BN14"
				( objectStatus "@baseboard_fab2_lib.baseboard_fab2(sch_1):page38_i34:cd_vccp(13)" )
			)
			( pin "U5D1.BN12"
				( objectStatus "@baseboard_fab2_lib.baseboard_fab2(sch_1):page38_i34:cd_vccp(14)" )
			)
			( pin "U5D1.BM11"
				( objectStatus "@baseboard_fab2_lib.baseboard_fab2(sch_1):page38_i34:cd_vccp(15)" )
			)
			( pin "U5D1.B11"
				( objectStatus "@baseboard_fab2_lib.baseboard_fab2(sch_1):page38_i34:cd_vpp(0)" )
			)
			( pin "U5D1.A12"
				( objectStatus "@baseboard_fab2_lib.baseboard_fab2(sch_1):page38_i34:cd_vpp(1)" )
			)
			( pin "U5D1.A10"
				( objectStatus "@baseboard_fab2_lib.baseboard_fab2(sch_1):page38_i34:cd_vpp(2)" )
			)
			( pin "U5D1.A8"
				( objectStatus "@baseboard_fab2_lib.baseboard_fab2(sch_1):page38_i34:cd_vpp(3)" )
			)
			( pin "U5D1.CY55"
				( objectStatus "@baseboard_fab2_lib.baseboard_fab2(sch_1):page38_i34:vcc33" )
			)
			( pin "U5D1.CM15"
				( objectStatus "@baseboard_fab2_lib.baseboard_fab2(sch_1):page38_i34:vccio(20)" )
			)
			( pin "U5D1.CL12"
				( objectStatus "@baseboard_fab2_lib.baseboard_fab2(sch_1):page38_i34:vccio(21)" )
			)
			( pin "U5D1.CK5"
				( objectStatus "@baseboard_fab2_lib.baseboard_fab2(sch_1):page38_i34:vccio(22)" )
			)
			( pin "U5D1.CV7"
				( objectStatus "@baseboard_fab2_lib.baseboard_fab2(sch_1):page38_i34:vccio(23)" )
			)
			( pin "U5D1.CH9"
				( objectStatus "@baseboard_fab2_lib.baseboard_fab2(sch_1):page38_i34:vccio(24)" )
			)
			( pin "U5D1.D7"
				( objectStatus "@baseboard_fab2_lib.baseboard_fab2(sch_1):page38_i34:vccio(25)" )
			)
			( pin "U5D1.CE18"
				( objectStatus "@baseboard_fab2_lib.baseboard_fab2(sch_1):page38_i34:vccio(26)" )
			)
			( pin "U5D1.CD9"
				( objectStatus "@baseboard_fab2_lib.baseboard_fab2(sch_1):page38_i34:vccio(27)" )
			)
			( pin "U5D1.CB17"
				( objectStatus "@baseboard_fab2_lib.baseboard_fab2(sch_1):page38_i34:vccio(28)" )
			)
			( pin "U5D1.CB13"
				( objectStatus "@baseboard_fab2_lib.baseboard_fab2(sch_1):page38_i34:vccio(29)" )
			)
			( pin "U5D1.BP25"
				( objectStatus "@baseboard_fab2_lib.baseboard_fab2(sch_1):page38_i34:vccio(30)" )
			)
			( pin "U5D1.BJ24"
				( objectStatus "@baseboard_fab2_lib.baseboard_fab2(sch_1):page38_i34:vccio(31)" )
			)
			( pin "U5D1.BF23"
				( objectStatus "@baseboard_fab2_lib.baseboard_fab2(sch_1):page38_i34:vccio(32)" )
			)
			( pin "U5D1.DA14"
				( objectStatus "@baseboard_fab2_lib.baseboard_fab2(sch_1):page38_i34:vccio(33)" )
			)
			( pin "U5D1.BB5"
				( objectStatus "@baseboard_fab2_lib.baseboard_fab2(sch_1):page38_i34:vccio(34)" )
			)
			( pin "U5D1.BA24"
				( objectStatus "@baseboard_fab2_lib.baseboard_fab2(sch_1):page38_i34:vccio(35)" )
			)
			( pin "U5D1.AY11"
				( objectStatus "@baseboard_fab2_lib.baseboard_fab2(sch_1):page38_i34:vccio(36)" )
			)
			( pin "U5D1.AW6"
				( objectStatus "@baseboard_fab2_lib.baseboard_fab2(sch_1):page38_i34:vccio(37)" )
			)
			( pin "U5D1.AT11"
				( objectStatus "@baseboard_fab2_lib.baseboard_fab2(sch_1):page38_i34:vccio(38)" )
			)
			( pin "U5D1.DD7"
				( objectStatus "@baseboard_fab2_lib.baseboard_fab2(sch_1):page38_i34:vccio(39)" )
			)
			( pin "U5D1.AN10"
				( objectStatus "@baseboard_fab2_lib.baseboard_fab2(sch_1):page38_i34:vccio(40)" )
			)
			( pin "U5D1.DF13"
				( objectStatus "@baseboard_fab2_lib.baseboard_fab2(sch_1):page38_i34:vccio(41)" )
			)
			( pin "U5D1.AH9"
				( objectStatus "@baseboard_fab2_lib.baseboard_fab2(sch_1):page38_i34:vccio(42)" )
			)
			( pin "U5D1.AC4"
				( objectStatus "@baseboard_fab2_lib.baseboard_fab2(sch_1):page38_i34:vccio(43)" )
			)
			( pin "U5D1.AC20"
				( objectStatus "@baseboard_fab2_lib.baseboard_fab2(sch_1):page38_i34:vccio(44)" )
			)
			( pin "U5D1.AA10"
				( objectStatus "@baseboard_fab2_lib.baseboard_fab2(sch_1):page38_i34:vccio(45)" )
			)
			( pin "U5D1.W6"
				( objectStatus "@baseboard_fab2_lib.baseboard_fab2(sch_1):page38_i34:vccio(46)" )
			)
			( pin "U5D1.W4"
				( objectStatus "@baseboard_fab2_lib.baseboard_fab2(sch_1):page38_i34:vccio(47)" )
			)
			( pin "U5D1.DF21"
				( objectStatus "@baseboard_fab2_lib.baseboard_fab2(sch_1):page38_i34:vccio(48)" )
			)
			( pin "U5D1.U14"
				( objectStatus "@baseboard_fab2_lib.baseboard_fab2(sch_1):page38_i34:vccio(49)" )
			)
			( pin "U5D1.T3"
				( objectStatus "@baseboard_fab2_lib.baseboard_fab2(sch_1):page38_i34:vccio(50)" )
			)
			( pin "U5D1.P5"
				( objectStatus "@baseboard_fab2_lib.baseboard_fab2(sch_1):page38_i34:vccio(51)" )
			)
			( pin "U5D1.M21"
				( objectStatus "@baseboard_fab2_lib.baseboard_fab2(sch_1):page38_i34:vccio(52)" )
			)
			( pin "U5D1.M11"
				( objectStatus "@baseboard_fab2_lib.baseboard_fab2(sch_1):page38_i34:vccio(53)" )
			)
			( pin "U5D1.DG8"
				( objectStatus "@baseboard_fab2_lib.baseboard_fab2(sch_1):page38_i34:vccio(54)" )
			)
			( pin "U5D1.DH7"
				( objectStatus "@baseboard_fab2_lib.baseboard_fab2(sch_1):page38_i34:vccio(55)" )
			)
			( pin "U5D1.L16"
				( objectStatus "@baseboard_fab2_lib.baseboard_fab2(sch_1):page38_i34:vccio(56)" )
			)
			( pin "U5D1.L14"
				( objectStatus "@baseboard_fab2_lib.baseboard_fab2(sch_1):page38_i34:vccio(57)" )
			)
			( pin "U5D1.J10"
				( objectStatus "@baseboard_fab2_lib.baseboard_fab2(sch_1):page38_i34:vccio(58)" )
			)
			( pin "U5D1.H13"
				( objectStatus "@baseboard_fab2_lib.baseboard_fab2(sch_1):page38_i34:vccio(59)" )
			)
			( pin "U5D1.DJ16"
				( objectStatus "@baseboard_fab2_lib.baseboard_fab2(sch_1):page38_i34:vccio(60)" )
			)
			( pin "U5D1.DM17"
				( objectStatus "@baseboard_fab2_lib.baseboard_fab2(sch_1):page38_i34:vccio(61)" )
			)
			( pin "U5D1.DN8"
				( objectStatus "@baseboard_fab2_lib.baseboard_fab2(sch_1):page38_i34:vccio(62)" )
			)
			( pin "U5D1.DP19"
				( objectStatus "@baseboard_fab2_lib.baseboard_fab2(sch_1):page38_i34:vccio(63)" )
			)
			( pin "U5D1.DR10"
				( objectStatus "@baseboard_fab2_lib.baseboard_fab2(sch_1):page38_i34:vccio(64)" )
			)
			( pin "U5D1.DR2"
				( objectStatus "@baseboard_fab2_lib.baseboard_fab2(sch_1):page38_i34:vccio(65)" )
			)
			( pin "U5D1.DU20"
				( objectStatus "@baseboard_fab2_lib.baseboard_fab2(sch_1):page38_i34:vccio(66)" )
			)
			( pin "U5D1.EA12"
				( objectStatus "@baseboard_fab2_lib.baseboard_fab2(sch_1):page38_i34:vccio(67)" )
			)
			( pin "U5D1.EB15"
				( objectStatus "@baseboard_fab2_lib.baseboard_fab2(sch_1):page38_i34:vccio(68)" )
			)
			( pin "U5D1.J2"
				( objectStatus "@baseboard_fab2_lib.baseboard_fab2(sch_1):page38_i34:vccio(69)" )
			)
			( pin "U5D1.K15"
				( objectStatus "@baseboard_fab2_lib.baseboard_fab2(sch_1):page38_i34:vccio(70)" )
			)
			( pin "U5D1.M7"
				( objectStatus "@baseboard_fab2_lib.baseboard_fab2(sch_1):page38_i34:vccio(71)" )
			)
			( pin "U5D1.M9"
				( objectStatus "@baseboard_fab2_lib.baseboard_fab2(sch_1):page38_i34:vccio(72)" )
			)
			( pin "U5D1.N18"
				( objectStatus "@baseboard_fab2_lib.baseboard_fab2(sch_1):page38_i34:vccio(73)" )
			)
			( pin "U5D1.W10"
				( objectStatus "@baseboard_fab2_lib.baseboard_fab2(sch_1):page38_i34:vccio(74)" )
			)
			( pin "U5D1.BC26"
				( objectStatus "@baseboard_fab2_lib.baseboard_fab2(sch_1):page38_i34:vccio(75)" )
			)
			( pin "U5D1.BB27"
				( objectStatus "@baseboard_fab2_lib.baseboard_fab2(sch_1):page38_i34:vccio(76)" )
			)
			( pin "U5D1.BA26"
				( objectStatus "@baseboard_fab2_lib.baseboard_fab2(sch_1):page38_i34:vccio(77)" )
			)
			( pin "U5D1.AY27"
				( objectStatus "@baseboard_fab2_lib.baseboard_fab2(sch_1):page38_i34:vccio(78)" )
			)
			( pin "U5D1.AW26"
				( objectStatus "@baseboard_fab2_lib.baseboard_fab2(sch_1):page38_i34:vccio(79)" )
			)
			( pin "U5D1.AV27"
				( objectStatus "@baseboard_fab2_lib.baseboard_fab2(sch_1):page38_i34:vccio(80)" )
			)
			( pin "U5D1.CF27"
				( objectStatus "@baseboard_fab2_lib.baseboard_fab2(sch_1):page38_i34:vccio(81)" )
			)
			( pin "U5D1.CD27"
				( objectStatus "@baseboard_fab2_lib.baseboard_fab2(sch_1):page38_i34:vccio(82)" )
			)
			( pin "U5D1.CC26"
				( objectStatus "@baseboard_fab2_lib.baseboard_fab2(sch_1):page38_i34:vccio(83)" )
			)
			( pin "U5D1.CJ28"
				( objectStatus "@baseboard_fab2_lib.baseboard_fab2(sch_1):page38_i34:vccio(84)" )
			)
			( pin "U5D1.CH27"
				( objectStatus "@baseboard_fab2_lib.baseboard_fab2(sch_1):page38_i34:vccio(85)" )
			)
			( pin "U5D1.BM27"
				( objectStatus "@baseboard_fab2_lib.baseboard_fab2(sch_1):page38_i34:vccio(86)" )
			)
			( pin "U5D1.BL26"
				( objectStatus "@baseboard_fab2_lib.baseboard_fab2(sch_1):page38_i34:vccio(87)" )
			)
			( pin "U5D1.BK27"
				( objectStatus "@baseboard_fab2_lib.baseboard_fab2(sch_1):page38_i34:vccio(88)" )
			)
			( pin "U5D1.BK25"
				( objectStatus "@baseboard_fab2_lib.baseboard_fab2(sch_1):page38_i34:vccio(89)" )
			)
			( pin "U5D1.BJ26"
				( objectStatus "@baseboard_fab2_lib.baseboard_fab2(sch_1):page38_i34:vccio(90)" )
			)
			( pin "U5D1.BH27"
				( objectStatus "@baseboard_fab2_lib.baseboard_fab2(sch_1):page38_i34:vccio(91)" )
			)
			( pin "U5D1.BH25"
				( objectStatus "@baseboard_fab2_lib.baseboard_fab2(sch_1):page38_i34:vccio(92)" )
			)
			( pin "U5D1.BG26"
				( objectStatus "@baseboard_fab2_lib.baseboard_fab2(sch_1):page38_i34:vccio(93)" )
			)
			( pin "U5D1.BF27"
				( objectStatus "@baseboard_fab2_lib.baseboard_fab2(sch_1):page38_i34:vccio(94)" )
			)
			( pin "U5D1.AE36"
				( objectStatus "@baseboard_fab2_lib.baseboard_fab2(sch_1):page38_i34:vccio(95)" )
			)
			( pin "U5D1.AD37"
				( objectStatus "@baseboard_fab2_lib.baseboard_fab2(sch_1):page38_i34:vccio(96)" )
			)
			( pin "U5D1.AC36"
				( objectStatus "@baseboard_fab2_lib.baseboard_fab2(sch_1):page38_i34:vccio(97)" )
			)
			( pin "U5D1.AF35"
				( objectStatus "@baseboard_fab2_lib.baseboard_fab2(sch_1):page38_i34:vccio(98)" )
			)
			( pin "U5D1.AD35"
				( objectStatus "@baseboard_fab2_lib.baseboard_fab2(sch_1):page38_i34:vccio(99)" )
			)
			( pin "U5D1.AE34"
				( objectStatus "@baseboard_fab2_lib.baseboard_fab2(sch_1):page38_i34:vccio(100)" )
			)
			( pin "U5D1.AG34"
				( objectStatus "@baseboard_fab2_lib.baseboard_fab2(sch_1):page38_i34:vccio(101)" )
			)
			( pin "U5D1.AM29"
				( objectStatus "@baseboard_fab2_lib.baseboard_fab2(sch_1):page38_i34:vccio(102)" )
			)
			( pin "U5D1.AL28"
				( objectStatus "@baseboard_fab2_lib.baseboard_fab2(sch_1):page38_i34:vccio(103)" )
			)
			( pin "U5D1.AR28"
				( objectStatus "@baseboard_fab2_lib.baseboard_fab2(sch_1):page38_i34:vccio(104)" )
			)
			( pin "U5D1.CJ66"
				( objectStatus "@baseboard_fab2_lib.baseboard_fab2(sch_1):page38_i34:vccsa(0)" )
			)
			( pin "U5D1.CJ64"
				( objectStatus "@baseboard_fab2_lib.baseboard_fab2(sch_1):page38_i34:vccsa(1)" )
			)
			( pin "U5D1.CH75"
				( objectStatus "@baseboard_fab2_lib.baseboard_fab2(sch_1):page38_i34:vccsa(2)" )
			)
			( pin "U5D1.CH65"
				( objectStatus "@baseboard_fab2_lib.baseboard_fab2(sch_1):page38_i34:vccsa(3)" )
			)
			( pin "U5D1.CG74"
				( objectStatus "@baseboard_fab2_lib.baseboard_fab2(sch_1):page38_i34:vccsa(4)" )
			)
			( pin "U5D1.CG66"
				( objectStatus "@baseboard_fab2_lib.baseboard_fab2(sch_1):page38_i34:vccsa(5)" )
			)
			( pin "U5D1.CG64"
				( objectStatus "@baseboard_fab2_lib.baseboard_fab2(sch_1):page38_i34:vccsa(6)" )
			)
			( pin "U5D1.CF75"
				( objectStatus "@baseboard_fab2_lib.baseboard_fab2(sch_1):page38_i34:vccsa(7)" )
			)
			( pin "U5D1.CF73"
				( objectStatus "@baseboard_fab2_lib.baseboard_fab2(sch_1):page38_i34:vccsa(8)" )
			)
			( pin "U5D1.CF67"
				( objectStatus "@baseboard_fab2_lib.baseboard_fab2(sch_1):page38_i34:vccsa(9)" )
			)
			( pin "U5D1.CF65"
				( objectStatus "@baseboard_fab2_lib.baseboard_fab2(sch_1):page38_i34:vccsa(10)" )
			)
			( pin "U5D1.CE74"
				( objectStatus "@baseboard_fab2_lib.baseboard_fab2(sch_1):page38_i34:vccsa(11)" )
			)
			( pin "U5D1.CE72"
				( objectStatus "@baseboard_fab2_lib.baseboard_fab2(sch_1):page38_i34:vccsa(12)" )
			)
			( pin "U5D1.CE68"
				( objectStatus "@baseboard_fab2_lib.baseboard_fab2(sch_1):page38_i34:vccsa(13)" )
			)
			( pin "U5D1.CE66"
				( objectStatus "@baseboard_fab2_lib.baseboard_fab2(sch_1):page38_i34:vccsa(14)" )
			)
			( pin "U5D1.CE64"
				( objectStatus "@baseboard_fab2_lib.baseboard_fab2(sch_1):page38_i34:vccsa(15)" )
			)
			( pin "U5D1.CD71"
				( objectStatus "@baseboard_fab2_lib.baseboard_fab2(sch_1):page38_i34:vccsa(16)" )
			)
			( pin "U5D1.CD69"
				( objectStatus "@baseboard_fab2_lib.baseboard_fab2(sch_1):page38_i34:vccsa(17)" )
			)
			( pin "U5D1.CD67"
				( objectStatus "@baseboard_fab2_lib.baseboard_fab2(sch_1):page38_i34:vccsa(18)" )
			)
			( pin "U5D1.CD65"
				( objectStatus "@baseboard_fab2_lib.baseboard_fab2(sch_1):page38_i34:vccsa(19)" )
			)
			( pin "U5D1.CC70"
				( objectStatus "@baseboard_fab2_lib.baseboard_fab2(sch_1):page38_i34:vccsa(20)" )
			)
			( pin "U5D1.CC68"
				( objectStatus "@baseboard_fab2_lib.baseboard_fab2(sch_1):page38_i34:vccsa(21)" )
			)
			( pin "U5D1.CC66"
				( objectStatus "@baseboard_fab2_lib.baseboard_fab2(sch_1):page38_i34:vccsa(22)" )
			)
			( pin "U5D1.CB69"
				( objectStatus "@baseboard_fab2_lib.baseboard_fab2(sch_1):page38_i34:vccsa(23)" )
			)
			( pin "U5D1.CB67"
				( objectStatus "@baseboard_fab2_lib.baseboard_fab2(sch_1):page38_i34:vccsa(24)" )
			)
			( pin "U5D1.CB65"
				( objectStatus "@baseboard_fab2_lib.baseboard_fab2(sch_1):page38_i34:vccsa(25)" )
			)
			( pin "U5D1.BN16"
				( objectStatus "@baseboard_fab2_lib.baseboard_fab2(sch_1):page39_i127:cd_vcc_core_sense" )
			)
			( pin "U5D1.BU16"
				( objectStatus "@baseboard_fab2_lib.baseboard_fab2(sch_1):page39_i127:cd_vccp_sense(0)" )
			)
			( pin "U5D1.BT17"
				( objectStatus "@baseboard_fab2_lib.baseboard_fab2(sch_1):page39_i127:cd_vccp_sense(1)" )
			)
			( pin "U5D1.BL16"
				( objectStatus "@baseboard_fab2_lib.baseboard_fab2(sch_1):page39_i127:cd_vss_vcc_core_sense" )
			)
			( pin "U5D1.EF83"
				( objectStatus "@baseboard_fab2_lib.baseboard_fab2(sch_1):page39_i127:rsvd(0)" )
			)
			( pin "U5D1.EF81"
				( objectStatus "@baseboard_fab2_lib.baseboard_fab2(sch_1):page39_i127:rsvd(1)" )
			)
			( pin "U5D1.EF77"
				( objectStatus "@baseboard_fab2_lib.baseboard_fab2(sch_1):page39_i127:rsvd(2)" )
			)
			( pin "U5D1.EF47"
				( objectStatus "@baseboard_fab2_lib.baseboard_fab2(sch_1):page39_i127:rsvd(3)" )
			)
			( pin "U5D1.EE84"
				( objectStatus "@baseboard_fab2_lib.baseboard_fab2(sch_1):page39_i127:rsvd(4)" )
			)
			( pin "U5D1.EE82"
				( objectStatus "@baseboard_fab2_lib.baseboard_fab2(sch_1):page39_i127:rsvd(5)" )
			)
			( pin "U5D1.EE6"
				( objectStatus "@baseboard_fab2_lib.baseboard_fab2(sch_1):page39_i127:rsvd(6)" )
			)
			( pin "U5D1.EE46"
				( objectStatus "@baseboard_fab2_lib.baseboard_fab2(sch_1):page39_i127:rsvd(7)" )
			)
			( pin "U5D1.EE16"
				( objectStatus "@baseboard_fab2_lib.baseboard_fab2(sch_1):page39_i127:rsvd(8)" )
			)
			( pin "U5D1.ED83"
				( objectStatus "@baseboard_fab2_lib.baseboard_fab2(sch_1):page39_i127:rsvd(9)" )
			)
			( pin "U5D1.ED5"
				( objectStatus "@baseboard_fab2_lib.baseboard_fab2(sch_1):page39_i127:rsvd(10)" )
			)
			( pin "U5D1.ED45"
				( objectStatus "@baseboard_fab2_lib.baseboard_fab2(sch_1):page39_i127:rsvd(11)" )
			)
			( pin "U5D1.EC84"
				( objectStatus "@baseboard_fab2_lib.baseboard_fab2(sch_1):page39_i127:rsvd(12)" )
			)
			( pin "U5D1.EC44"
				( objectStatus "@baseboard_fab2_lib.baseboard_fab2(sch_1):page39_i127:rsvd(13)" )
			)
			( pin "U5D1.EC4"
				( objectStatus "@baseboard_fab2_lib.baseboard_fab2(sch_1):page39_i127:rsvd(14)" )
			)
			( pin "U5D1.EC16"
				( objectStatus "@baseboard_fab2_lib.baseboard_fab2(sch_1):page39_i127:rsvd(15)" )
			)
			( pin "U5D1.EB85"
				( objectStatus "@baseboard_fab2_lib.baseboard_fab2(sch_1):page39_i127:rsvd(16)" )
			)
			( pin "U5D1.EB5"
				( objectStatus "@baseboard_fab2_lib.baseboard_fab2(sch_1):page39_i127:rsvd(17)" )
			)
			( pin "U5D1.EB3"
				( objectStatus "@baseboard_fab2_lib.baseboard_fab2(sch_1):page39_i127:rsvd(18)" )
			)
			( pin "U5D1.EA44"
				( objectStatus "@baseboard_fab2_lib.baseboard_fab2(sch_1):page39_i127:rsvd(19)" )
			)
			( pin "U5D1.EA4"
				( objectStatus "@baseboard_fab2_lib.baseboard_fab2(sch_1):page39_i127:rsvd(20)" )
			)
			( pin "U5D1.DY3"
				( objectStatus "@baseboard_fab2_lib.baseboard_fab2(sch_1):page39_i127:rsvd(21)" )
			)
			( pin "U5D1.DW46"
				( objectStatus "@baseboard_fab2_lib.baseboard_fab2(sch_1):page39_i127:rsvd(22)" )
			)
			( pin "U5D1.DW44"
				( objectStatus "@baseboard_fab2_lib.baseboard_fab2(sch_1):page39_i127:rsvd(23)" )
			)
			( pin "U5D1.DV71"
				( objectStatus "@baseboard_fab2_lib.baseboard_fab2(sch_1):page39_i127:rsvd(24)" )
			)
			( pin "U5D1.DV61"
				( objectStatus "@baseboard_fab2_lib.baseboard_fab2(sch_1):page39_i127:rsvd(25)" )
			)
			( pin "U5D1.DU44"
				( objectStatus "@baseboard_fab2_lib.baseboard_fab2(sch_1):page39_i127:rsvd(26)" )
			)
			( pin "U5D1.DT71"
				( objectStatus "@baseboard_fab2_lib.baseboard_fab2(sch_1):page39_i127:rsvd(27)" )
			)
			( pin "U5D1.DR44"
				( objectStatus "@baseboard_fab2_lib.baseboard_fab2(sch_1):page39_i127:rsvd(28)" )
			)
			( pin "U5D1.DP65"
				( objectStatus "@baseboard_fab2_lib.baseboard_fab2(sch_1):page39_i127:rsvd(29)" )
			)
			( pin "U5D1.DP17"
				( objectStatus "@baseboard_fab2_lib.baseboard_fab2(sch_1):page39_i127:rsvd(30)" )
			)
			( pin "U5D1.DN66"
				( objectStatus "@baseboard_fab2_lib.baseboard_fab2(sch_1):page39_i127:rsvd(31)" )
			)
			( pin "U5D1.DN62"
				( objectStatus "@baseboard_fab2_lib.baseboard_fab2(sch_1):page39_i127:rsvd(32)" )
			)
			( pin "U5D1.DM67"
				( objectStatus "@baseboard_fab2_lib.baseboard_fab2(sch_1):page39_i127:rsvd(33)" )
			)
			( pin "U5D1.DL66"
				( objectStatus "@baseboard_fab2_lib.baseboard_fab2(sch_1):page39_i127:rsvd(34)" )
			)
			( pin "U5D1.DL38"
				( objectStatus "@baseboard_fab2_lib.baseboard_fab2(sch_1):page39_i127:rsvd(35)" )
			)
			( pin "U5D1.DK67"
				( objectStatus "@baseboard_fab2_lib.baseboard_fab2(sch_1):page39_i127:rsvd(36)" )
			)
			( pin "U5D1.DK65"
				( objectStatus "@baseboard_fab2_lib.baseboard_fab2(sch_1):page39_i127:rsvd(37)" )
			)
			( pin "U5D1.DK37"
				( objectStatus "@baseboard_fab2_lib.baseboard_fab2(sch_1):page39_i127:rsvd(38)" )
			)
			( pin "U5D1.DK15"
				( objectStatus "@baseboard_fab2_lib.baseboard_fab2(sch_1):page39_i127:rsvd(39)" )
			)
			( pin "U5D1.DJ66"
				( objectStatus "@baseboard_fab2_lib.baseboard_fab2(sch_1):page39_i127:rsvd(40)" )
			)
			( pin "U5D1.DJ36"
				( objectStatus "@baseboard_fab2_lib.baseboard_fab2(sch_1):page39_i127:rsvd(41)" )
			)
			( pin "U5D1.DH65"
				( objectStatus "@baseboard_fab2_lib.baseboard_fab2(sch_1):page39_i127:rsvd(42)" )
			)
			( pin "U5D1.DG64"
				( objectStatus "@baseboard_fab2_lib.baseboard_fab2(sch_1):page39_i127:rsvd(43)" )
			)
			( pin "U5D1.DG36"
				( objectStatus "@baseboard_fab2_lib.baseboard_fab2(sch_1):page39_i127:rsvd(44)" )
			)
			( pin "U5D1.DD51"
				( objectStatus "@baseboard_fab2_lib.baseboard_fab2(sch_1):page39_i127:rsvd(45)" )
			)
			( pin "U5D1.DC52"
				( objectStatus "@baseboard_fab2_lib.baseboard_fab2(sch_1):page39_i127:rsvd(46)" )
			)
			( pin "U5D1.DC46"
				( objectStatus "@baseboard_fab2_lib.baseboard_fab2(sch_1):page39_i127:rsvd(47)" )
			)
			( pin "U5D1.DA56"
				( objectStatus "@baseboard_fab2_lib.baseboard_fab2(sch_1):page39_i127:rsvd(48)" )
			)
			( pin "U5D1.DA54"
				( objectStatus "@baseboard_fab2_lib.baseboard_fab2(sch_1):page39_i127:rsvd(49)" )
			)
			( pin "U5D1.DA52"
				( objectStatus "@baseboard_fab2_lib.baseboard_fab2(sch_1):page39_i127:rsvd(50)" )
			)
			( pin "U5D1.DA40"
				( objectStatus "@baseboard_fab2_lib.baseboard_fab2(sch_1):page39_i127:rsvd(51)" )
			)
			( pin "U5D1.DA24"
				( objectStatus "@baseboard_fab2_lib.baseboard_fab2(sch_1):page39_i127:rsvd(52)" )
			)
			( pin "U5D1.CY73"
				( objectStatus "@baseboard_fab2_lib.baseboard_fab2(sch_1):page39_i127:rsvd(53)" )
			)
			( pin "U5D1.CY63"
				( objectStatus "@baseboard_fab2_lib.baseboard_fab2(sch_1):page39_i127:rsvd(54)" )
			)
			( pin "U5D1.CY57"
				( objectStatus "@baseboard_fab2_lib.baseboard_fab2(sch_1):page39_i127:rsvd(55)" )
			)
			( pin "U5D1.CY53"
				( objectStatus "@baseboard_fab2_lib.baseboard_fab2(sch_1):page39_i127:rsvd(56)" )
			)
			( pin "U5D1.CY39"
				( objectStatus "@baseboard_fab2_lib.baseboard_fab2(sch_1):page39_i127:rsvd(57)" )
			)
			( pin "U5D1.CY25"
				( objectStatus "@baseboard_fab2_lib.baseboard_fab2(sch_1):page39_i127:rsvd(58)" )
			)
			( pin "U5D1.CY23"
				( objectStatus "@baseboard_fab2_lib.baseboard_fab2(sch_1):page39_i127:rsvd(59)" )
			)
			( pin "U5D1.CW62"
				( objectStatus "@baseboard_fab2_lib.baseboard_fab2(sch_1):page39_i127:rsvd(60)" )
			)
			( pin "U5D1.CW60"
				( objectStatus "@baseboard_fab2_lib.baseboard_fab2(sch_1):page39_i127:rsvd(61)" )
			)
			( pin "U5D1.CW24"
				( objectStatus "@baseboard_fab2_lib.baseboard_fab2(sch_1):page39_i127:rsvd(62)" )
			)
			( pin "U5D1.CW22"
				( objectStatus "@baseboard_fab2_lib.baseboard_fab2(sch_1):page39_i127:rsvd(63)" )
			)
			( pin "U5D1.CV69"
				( objectStatus "@baseboard_fab2_lib.baseboard_fab2(sch_1):page39_i127:rsvd(64)" )
			)
			( pin "U5D1.CV23"
				( objectStatus "@baseboard_fab2_lib.baseboard_fab2(sch_1):page39_i127:rsvd(65)" )
			)
			( pin "U5D1.CU60"
				( objectStatus "@baseboard_fab2_lib.baseboard_fab2(sch_1):page39_i127:rsvd(66)" )
			)
			( pin "U5D1.CU6"
				( objectStatus "@baseboard_fab2_lib.baseboard_fab2(sch_1):page39_i127:rsvd(67)" )
			)
			( pin "U5D1.CU24"
				( objectStatus "@baseboard_fab2_lib.baseboard_fab2(sch_1):page39_i127:rsvd(68)" )
			)
			( pin "U5D1.CT69"
				( objectStatus "@baseboard_fab2_lib.baseboard_fab2(sch_1):page39_i127:rsvd(69)" )
			)
			( pin "U5D1.CT5"
				( objectStatus "@baseboard_fab2_lib.baseboard_fab2(sch_1):page39_i127:rsvd(70)" )
			)
			( pin "U5D1.CT23"
				( objectStatus "@baseboard_fab2_lib.baseboard_fab2(sch_1):page39_i127:rsvd(71)" )
			)
			( pin "U5D1.CR60"
				( objectStatus "@baseboard_fab2_lib.baseboard_fab2(sch_1):page39_i127:rsvd(72)" )
			)
			( pin "U5D1.CP31"
				( objectStatus "@baseboard_fab2_lib.baseboard_fab2(sch_1):page39_i127:rsvd(73)" )
			)
			( pin "U5D1.CP23"
				( objectStatus "@baseboard_fab2_lib.baseboard_fab2(sch_1):page39_i127:rsvd(74)" )
			)
			( pin "U5D1.CN28"
				( objectStatus "@baseboard_fab2_lib.baseboard_fab2(sch_1):page39_i127:rsvd(75)" )
			)
			( pin "U5D1.CN24"
				( objectStatus "@baseboard_fab2_lib.baseboard_fab2(sch_1):page39_i127:rsvd(76)" )
			)
			( pin "U5D1.CN22"
				( objectStatus "@baseboard_fab2_lib.baseboard_fab2(sch_1):page39_i127:rsvd(77)" )
			)
			( pin "U5D1.CM25"
				( objectStatus "@baseboard_fab2_lib.baseboard_fab2(sch_1):page39_i127:rsvd(78)" )
			)
			( pin "U5D1.CM23"
				( objectStatus "@baseboard_fab2_lib.baseboard_fab2(sch_1):page39_i127:rsvd(79)" )
			)
			( pin "U5D1.CL26"
				( objectStatus "@baseboard_fab2_lib.baseboard_fab2(sch_1):page39_i127:rsvd(80)" )
			)
			( pin "U5D1.EE10"
				( objectStatus "@baseboard_fab2_lib.baseboard_fab2(sch_1):page39_i127:vccio(0)" )
			)
			( pin "U5D1.AE10"
				( objectStatus "@baseboard_fab2_lib.baseboard_fab2(sch_1):page39_i127:vccio(1)" )
			)
			( pin "U5D1.AF5"
				( objectStatus "@baseboard_fab2_lib.baseboard_fab2(sch_1):page39_i127:vccio(2)" )
			)
			( pin "U5D1.DV11"
				( objectStatus "@baseboard_fab2_lib.baseboard_fab2(sch_1):page39_i127:vccio(3)" )
			)
			( pin "U5D1.AM5"
				( objectStatus "@baseboard_fab2_lib.baseboard_fab2(sch_1):page39_i127:vccio(4)" )
			)
			( pin "U5D1.AT5"
				( objectStatus "@baseboard_fab2_lib.baseboard_fab2(sch_1):page39_i127:vccio(5)" )
			)
			( pin "U5D1.AT7"
				( objectStatus "@baseboard_fab2_lib.baseboard_fab2(sch_1):page39_i127:vccio(6)" )
			)
			( pin "U5D1.BE24"
				( objectStatus "@baseboard_fab2_lib.baseboard_fab2(sch_1):page39_i127:vccio(7)" )
			)
			( pin "U5D1.DK21"
				( objectStatus "@baseboard_fab2_lib.baseboard_fab2(sch_1):page39_i127:vccio(8)" )
			)
			( pin "U5D1.CF5"
				( objectStatus "@baseboard_fab2_lib.baseboard_fab2(sch_1):page39_i127:vccio(9)" )
			)
			( pin "U5D1.CG14"
				( objectStatus "@baseboard_fab2_lib.baseboard_fab2(sch_1):page39_i127:vccio(10)" )
			)
			( pin "U5D1.CL20"
				( objectStatus "@baseboard_fab2_lib.baseboard_fab2(sch_1):page39_i127:vccio(11)" )
			)
			( pin "U5D1.CP13"
				( objectStatus "@baseboard_fab2_lib.baseboard_fab2(sch_1):page39_i127:vccio(12)" )
			)
			( pin "U5D1.DE14"
				( objectStatus "@baseboard_fab2_lib.baseboard_fab2(sch_1):page39_i127:vccio(13)" )
			)
			( pin "U5D1.DC18"
				( objectStatus "@baseboard_fab2_lib.baseboard_fab2(sch_1):page39_i127:vccio(14)" )
			)
			( pin "U5D1.CY17"
				( objectStatus "@baseboard_fab2_lib.baseboard_fab2(sch_1):page39_i127:vccio(15)" )
			)
			( pin "U5D1.CU18"
				( objectStatus "@baseboard_fab2_lib.baseboard_fab2(sch_1):page39_i127:vccio(16)" )
			)
			( pin "U5D1.CV21"
				( objectStatus "@baseboard_fab2_lib.baseboard_fab2(sch_1):page39_i127:vccio(17)" )
			)
			( pin "U5D1.CU12"
				( objectStatus "@baseboard_fab2_lib.baseboard_fab2(sch_1):page39_i127:vccio(18)" )
			)
			( pin "U5D1.CN6"
				( objectStatus "@baseboard_fab2_lib.baseboard_fab2(sch_1):page39_i127:vccio(19)" )
			)
			( pin "U5D1.BH5"
				( objectStatus "@baseboard_fab2_lib.baseboard_fab2(sch_1):page39_i127:vccio_sense" )
			)
			( pin "U5D1.CE76"
				( objectStatus "@baseboard_fab2_lib.baseboard_fab2(sch_1):page39_i127:vccsa_sense" )
			)
			( pin "U5D1.BF5"
				( objectStatus "@baseboard_fab2_lib.baseboard_fab2(sch_1):page39_i127:vss_vccio_sense" )
			)
			( pin "U5D1.CG76"
				( objectStatus "@baseboard_fab2_lib.baseboard_fab2(sch_1):page39_i127:vss_vccsa_sense" )
			)
			( pin "U5D1.J74"
				( objectStatus "@baseboard_fab2_lib.baseboard_fab2(sch_1):page40_i20:vss(1094)" )
			)
			( pin "U5D1.J72"
				( objectStatus "@baseboard_fab2_lib.baseboard_fab2(sch_1):page40_i20:vss(1095)" )
			)
			( pin "U5D1.J40"
				( objectStatus "@baseboard_fab2_lib.baseboard_fab2(sch_1):page40_i20:vss(1096)" )
			)
			( pin "U5D1.J38"
				( objectStatus "@baseboard_fab2_lib.baseboard_fab2(sch_1):page40_i20:vss(1097)" )
			)
			( pin "U5D1.J34"
				( objectStatus "@baseboard_fab2_lib.baseboard_fab2(sch_1):page40_i20:vss(1098)" )
			)
			( pin "U5D1.J32"
				( objectStatus "@baseboard_fab2_lib.baseboard_fab2(sch_1):page40_i20:vss(1099)" )
			)
			( pin "U5D1.J28"
				( objectStatus "@baseboard_fab2_lib.baseboard_fab2(sch_1):page40_i20:vss(1100)" )
			)
			( pin "U5D1.J26"
				( objectStatus "@baseboard_fab2_lib.baseboard_fab2(sch_1):page40_i20:vss(1101)" )
			)
			( pin "U5D1.J22"
				( objectStatus "@baseboard_fab2_lib.baseboard_fab2(sch_1):page40_i20:vss(1102)" )
			)
			( pin "U5D1.J14"
				( objectStatus "@baseboard_fab2_lib.baseboard_fab2(sch_1):page40_i20:vss(1103)" )
			)
			( pin "U5D1.J12"
				( objectStatus "@baseboard_fab2_lib.baseboard_fab2(sch_1):page40_i20:vss(1104)" )
			)
			( pin "U5D1.J4"
				( objectStatus "@baseboard_fab2_lib.baseboard_fab2(sch_1):page40_i20:vss(1105)" )
			)
			( pin "U5D1.DN44"
				( objectStatus "@baseboard_fab2_lib.baseboard_fab2(sch_1):page40_i20:vss(1106)" )
			)
			( pin "U5D1.H75"
				( objectStatus "@baseboard_fab2_lib.baseboard_fab2(sch_1):page40_i20:vss(1107)" )
			)
			( pin "U5D1.H71"
				( objectStatus "@baseboard_fab2_lib.baseboard_fab2(sch_1):page40_i20:vss(1108)" )
			)
			( pin "U5D1.H65"
				( objectStatus "@baseboard_fab2_lib.baseboard_fab2(sch_1):page40_i20:vss(1109)" )
			)
			( pin "U5D1.H41"
				( objectStatus "@baseboard_fab2_lib.baseboard_fab2(sch_1):page40_i20:vss(1110)" )
			)
			( pin "U5D1.H39"
				( objectStatus "@baseboard_fab2_lib.baseboard_fab2(sch_1):page40_i20:vss(1111)" )
			)
			( pin "U5D1.H37"
				( objectStatus "@baseboard_fab2_lib.baseboard_fab2(sch_1):page40_i20:vss(1112)" )
			)
			( pin "U5D1.H35"
				( objectStatus "@baseboard_fab2_lib.baseboard_fab2(sch_1):page40_i20:vss(1113)" )
			)
			( pin "U5D1.H33"
				( objectStatus "@baseboard_fab2_lib.baseboard_fab2(sch_1):page40_i20:vss(1114)" )
			)
			( pin "U5D1.H31"
				( objectStatus "@baseboard_fab2_lib.baseboard_fab2(sch_1):page40_i20:vss(1115)" )
			)
			( pin "U5D1.H29"
				( objectStatus "@baseboard_fab2_lib.baseboard_fab2(sch_1):page40_i20:vss(1116)" )
			)
			( pin "U5D1.H27"
				( objectStatus "@baseboard_fab2_lib.baseboard_fab2(sch_1):page40_i20:vss(1117)" )
			)
			( pin "U5D1.H25"
				( objectStatus "@baseboard_fab2_lib.baseboard_fab2(sch_1):page40_i20:vss(1118)" )
			)
			( pin "U5D1.H11"
				( objectStatus "@baseboard_fab2_lib.baseboard_fab2(sch_1):page40_i20:vss(1119)" )
			)
			( pin "U5D1.H3"
				( objectStatus "@baseboard_fab2_lib.baseboard_fab2(sch_1):page40_i20:vss(1120)" )
			)
			( pin "U5D1.G82"
				( objectStatus "@baseboard_fab2_lib.baseboard_fab2(sch_1):page40_i20:vss(1121)" )
			)
			( pin "U5D1.G80"
				( objectStatus "@baseboard_fab2_lib.baseboard_fab2(sch_1):page40_i20:vss(1122)" )
			)
			( pin "U5D1.G78"
				( objectStatus "@baseboard_fab2_lib.baseboard_fab2(sch_1):page40_i20:vss(1123)" )
			)
			( pin "U5D1.G76"
				( objectStatus "@baseboard_fab2_lib.baseboard_fab2(sch_1):page40_i20:vss(1124)" )
			)
			( pin "U5D1.G70"
				( objectStatus "@baseboard_fab2_lib.baseboard_fab2(sch_1):page40_i20:vss(1125)" )
			)
			( pin "U5D1.G66"
				( objectStatus "@baseboard_fab2_lib.baseboard_fab2(sch_1):page40_i20:vss(1126)" )
			)
			( pin "U5D1.G42"
				( objectStatus "@baseboard_fab2_lib.baseboard_fab2(sch_1):page40_i20:vss(1127)" )
			)
			( pin "U5D1.G38"
				( objectStatus "@baseboard_fab2_lib.baseboard_fab2(sch_1):page40_i20:vss(1128)" )
			)
			( pin "U5D1.G36"
				( objectStatus "@baseboard_fab2_lib.baseboard_fab2(sch_1):page40_i20:vss(1129)" )
			)
			( pin "U5D1.G32"
				( objectStatus "@baseboard_fab2_lib.baseboard_fab2(sch_1):page40_i20:vss(1130)" )
			)
			( pin "U5D1.G30"
				( objectStatus "@baseboard_fab2_lib.baseboard_fab2(sch_1):page40_i20:vss(1131)" )
			)
			( pin "U5D1.G26"
				( objectStatus "@baseboard_fab2_lib.baseboard_fab2(sch_1):page40_i20:vss(1132)" )
			)
			( pin "U5D1.G24"
				( objectStatus "@baseboard_fab2_lib.baseboard_fab2(sch_1):page40_i20:vss(1133)" )
			)
			( pin "U5D1.G22"
				( objectStatus "@baseboard_fab2_lib.baseboard_fab2(sch_1):page40_i20:vss(1134)" )
			)
			( pin "U5D1.G8"
				( objectStatus "@baseboard_fab2_lib.baseboard_fab2(sch_1):page40_i20:vss(1135)" )
			)
			( pin "U5D1.G4"
				( objectStatus "@baseboard_fab2_lib.baseboard_fab2(sch_1):page40_i20:vss(1136)" )
			)
			( pin "U5D1.F69"
				( objectStatus "@baseboard_fab2_lib.baseboard_fab2(sch_1):page40_i20:vss(1137)" )
			)
			( pin "U5D1.F67"
				( objectStatus "@baseboard_fab2_lib.baseboard_fab2(sch_1):page40_i20:vss(1138)" )
			)
			( pin "U5D1.F43"
				( objectStatus "@baseboard_fab2_lib.baseboard_fab2(sch_1):page40_i20:vss(1139)" )
			)
			( pin "U5D1.F37"
				( objectStatus "@baseboard_fab2_lib.baseboard_fab2(sch_1):page40_i20:vss(1140)" )
			)
			( pin "U5D1.F31"
				( objectStatus "@baseboard_fab2_lib.baseboard_fab2(sch_1):page40_i20:vss(1141)" )
			)
			( pin "U5D1.F25"
				( objectStatus "@baseboard_fab2_lib.baseboard_fab2(sch_1):page40_i20:vss(1142)" )
			)
			( pin "U5D1.F19"
				( objectStatus "@baseboard_fab2_lib.baseboard_fab2(sch_1):page40_i20:vss(1143)" )
			)
			( pin "U5D1.F17"
				( objectStatus "@baseboard_fab2_lib.baseboard_fab2(sch_1):page40_i20:vss(1144)" )
			)
			( pin "U5D1.F5"
				( objectStatus "@baseboard_fab2_lib.baseboard_fab2(sch_1):page40_i20:vss(1145)" )
			)
			( pin "U5D1.E76"
				( objectStatus "@baseboard_fab2_lib.baseboard_fab2(sch_1):page40_i20:vss(1146)" )
			)
			( pin "U5D1.E74"
				( objectStatus "@baseboard_fab2_lib.baseboard_fab2(sch_1):page40_i20:vss(1147)" )
			)
			( pin "U5D1.E72"
				( objectStatus "@baseboard_fab2_lib.baseboard_fab2(sch_1):page40_i20:vss(1148)" )
			)
			( pin "U5D1.E22"
				( objectStatus "@baseboard_fab2_lib.baseboard_fab2(sch_1):page40_i20:vss(1149)" )
			)
			( pin "U5D1.E20"
				( objectStatus "@baseboard_fab2_lib.baseboard_fab2(sch_1):page40_i20:vss(1150)" )
			)
			( pin "U5D1.E18"
				( objectStatus "@baseboard_fab2_lib.baseboard_fab2(sch_1):page40_i20:vss(1151)" )
			)
			( pin "U5D1.E16"
				( objectStatus "@baseboard_fab2_lib.baseboard_fab2(sch_1):page40_i20:vss(1152)" )
			)
			( pin "U5D1.E8"
				( objectStatus "@baseboard_fab2_lib.baseboard_fab2(sch_1):page40_i20:vss(1153)" )
			)
			( pin "U5D1.E6"
				( objectStatus "@baseboard_fab2_lib.baseboard_fab2(sch_1):page40_i20:vss(1154)" )
			)
			( pin "U5D1.D77"
				( objectStatus "@baseboard_fab2_lib.baseboard_fab2(sch_1):page40_i20:vss(1155)" )
			)
			( pin "U5D1.D43"
				( objectStatus "@baseboard_fab2_lib.baseboard_fab2(sch_1):page40_i20:vss(1156)" )
			)
			( pin "U5D1.D41"
				( objectStatus "@baseboard_fab2_lib.baseboard_fab2(sch_1):page40_i20:vss(1157)" )
			)
			( pin "U5D1.D39"
				( objectStatus "@baseboard_fab2_lib.baseboard_fab2(sch_1):page40_i20:vss(1158)" )
			)
			( pin "U5D1.D37"
				( objectStatus "@baseboard_fab2_lib.baseboard_fab2(sch_1):page40_i20:vss(1159)" )
			)
			( pin "U5D1.D35"
				( objectStatus "@baseboard_fab2_lib.baseboard_fab2(sch_1):page40_i20:vss(1160)" )
			)
			( pin "U5D1.D33"
				( objectStatus "@baseboard_fab2_lib.baseboard_fab2(sch_1):page40_i20:vss(1161)" )
			)
			( pin "U5D1.D31"
				( objectStatus "@baseboard_fab2_lib.baseboard_fab2(sch_1):page40_i20:vss(1162)" )
			)
			( pin "U5D1.D29"
				( objectStatus "@baseboard_fab2_lib.baseboard_fab2(sch_1):page40_i20:vss(1163)" )
			)
			( pin "U5D1.D27"
				( objectStatus "@baseboard_fab2_lib.baseboard_fab2(sch_1):page40_i20:vss(1164)" )
			)
			( pin "U5D1.D25"
				( objectStatus "@baseboard_fab2_lib.baseboard_fab2(sch_1):page40_i20:vss(1165)" )
			)
			( pin "U5D1.D13"
				( objectStatus "@baseboard_fab2_lib.baseboard_fab2(sch_1):page40_i20:vss(1166)" )
			)
			( pin "U5D1.D11"
				( objectStatus "@baseboard_fab2_lib.baseboard_fab2(sch_1):page40_i20:vss(1167)" )
			)
			( pin "U5D1.CM27"
				( objectStatus "@baseboard_fab2_lib.baseboard_fab2(sch_1):page40_i20:vss(1168)" )
			)
			( pin "U5D1.C78"
				( objectStatus "@baseboard_fab2_lib.baseboard_fab2(sch_1):page40_i20:vss(1169)" )
			)
			( pin "U5D1.C76"
				( objectStatus "@baseboard_fab2_lib.baseboard_fab2(sch_1):page40_i20:vss(1170)" )
			)
			( pin "U5D1.C16"
				( objectStatus "@baseboard_fab2_lib.baseboard_fab2(sch_1):page40_i20:vss(1171)" )
			)
			( pin "U5D1.C14"
				( objectStatus "@baseboard_fab2_lib.baseboard_fab2(sch_1):page40_i20:vss(1172)" )
			)
			( pin "U5D1.C12"
				( objectStatus "@baseboard_fab2_lib.baseboard_fab2(sch_1):page40_i20:vss(1173)" )
			)
			( pin "U5D1.C10"
				( objectStatus "@baseboard_fab2_lib.baseboard_fab2(sch_1):page40_i20:vss(1174)" )
			)
			( pin "U5D1.C8"
				( objectStatus "@baseboard_fab2_lib.baseboard_fab2(sch_1):page40_i20:vss(1175)" )
			)
			( pin "U5D1.B75"
				( objectStatus "@baseboard_fab2_lib.baseboard_fab2(sch_1):page40_i20:vss(1176)" )
			)
			( pin "U5D1.B71"
				( objectStatus "@baseboard_fab2_lib.baseboard_fab2(sch_1):page40_i20:vss(1177)" )
			)
			( pin "U5D1.B37"
				( objectStatus "@baseboard_fab2_lib.baseboard_fab2(sch_1):page40_i20:vss(1178)" )
			)
			( pin "U5D1.B31"
				( objectStatus "@baseboard_fab2_lib.baseboard_fab2(sch_1):page40_i20:vss(1179)" )
			)
			( pin "U5D1.B25"
				( objectStatus "@baseboard_fab2_lib.baseboard_fab2(sch_1):page40_i20:vss(1180)" )
			)
			( pin "U5D1.A38"
				( objectStatus "@baseboard_fab2_lib.baseboard_fab2(sch_1):page40_i20:vss(1181)" )
			)
			( pin "U5D1.A36"
				( objectStatus "@baseboard_fab2_lib.baseboard_fab2(sch_1):page40_i20:vss(1182)" )
			)
			( pin "U5D1.A32"
				( objectStatus "@baseboard_fab2_lib.baseboard_fab2(sch_1):page40_i20:vss(1183)" )
			)
			( pin "U5D1.A30"
				( objectStatus "@baseboard_fab2_lib.baseboard_fab2(sch_1):page40_i20:vss(1184)" )
			)
			( pin "U5D1.A26"
				( objectStatus "@baseboard_fab2_lib.baseboard_fab2(sch_1):page40_i20:vss(1185)" )
			)
			( pin "U5D1.AC58"
				( objectStatus "@baseboard_fab2_lib.baseboard_fab2(sch_1):page40_i20:vss(1186)" )
			)
			( pin "U5D1.AC60"
				( objectStatus "@baseboard_fab2_lib.baseboard_fab2(sch_1):page40_i20:vss(1187)" )
			)
			( pin "U5D1.AC62"
				( objectStatus "@baseboard_fab2_lib.baseboard_fab2(sch_1):page40_i20:vss(1188)" )
			)
			( pin "U5D1.AJ4"
				( objectStatus "@baseboard_fab2_lib.baseboard_fab2(sch_1):page40_i20:vss(1189)" )
			)
			( pin "U5D1.AR6"
				( objectStatus "@baseboard_fab2_lib.baseboard_fab2(sch_1):page40_i20:vss(1190)" )
			)
			( pin "U5D1.CG6"
				( objectStatus "@baseboard_fab2_lib.baseboard_fab2(sch_1):page40_i20:vss(1191)" )
			)
			( pin "U5D1.CW6"
				( objectStatus "@baseboard_fab2_lib.baseboard_fab2(sch_1):page40_i20:vss(1192)" )
			)
			( pin "U5D1.DE48"
				( objectStatus "@baseboard_fab2_lib.baseboard_fab2(sch_1):page40_i20:vss(1193)" )
			)
			( pin "U5D1.DE50"
				( objectStatus "@baseboard_fab2_lib.baseboard_fab2(sch_1):page40_i20:vss(1194)" )
			)
			( pin "U5D1.DE52"
				( objectStatus "@baseboard_fab2_lib.baseboard_fab2(sch_1):page40_i20:vss(1195)" )
			)
			( pin "U5D1.DE54"
				( objectStatus "@baseboard_fab2_lib.baseboard_fab2(sch_1):page40_i20:vss(1196)" )
			)
			( pin "U5D1.DE56"
				( objectStatus "@baseboard_fab2_lib.baseboard_fab2(sch_1):page40_i20:vss(1197)" )
			)
			( pin "U5D1.DE58"
				( objectStatus "@baseboard_fab2_lib.baseboard_fab2(sch_1):page40_i20:vss(1198)" )
			)
			( pin "U5D1.DE60"
				( objectStatus "@baseboard_fab2_lib.baseboard_fab2(sch_1):page40_i20:vss(1199)" )
			)
			( pin "U5D1.DE62"
				( objectStatus "@baseboard_fab2_lib.baseboard_fab2(sch_1):page40_i20:vss(1200)" )
			)
			( pin "U5D1.DL8"
				( objectStatus "@baseboard_fab2_lib.baseboard_fab2(sch_1):page40_i20:vss(1201)" )
			)
			( pin "U5D1.DN18"
				( objectStatus "@baseboard_fab2_lib.baseboard_fab2(sch_1):page40_i20:vss(1202)" )
			)
			( pin "U5D1.DP45"
				( objectStatus "@baseboard_fab2_lib.baseboard_fab2(sch_1):page40_i20:vss(1203)" )
			)
			( pin "U5D1.DP47"
				( objectStatus "@baseboard_fab2_lib.baseboard_fab2(sch_1):page40_i20:vss(1204)" )
			)
			( pin "U5D1.DP49"
				( objectStatus "@baseboard_fab2_lib.baseboard_fab2(sch_1):page40_i20:vss(1205)" )
			)
			( pin "U5D1.DP51"
				( objectStatus "@baseboard_fab2_lib.baseboard_fab2(sch_1):page40_i20:vss(1206)" )
			)
			( pin "U5D1.DP53"
				( objectStatus "@baseboard_fab2_lib.baseboard_fab2(sch_1):page40_i20:vss(1207)" )
			)
			( pin "U5D1.DP55"
				( objectStatus "@baseboard_fab2_lib.baseboard_fab2(sch_1):page40_i20:vss(1208)" )
			)
			( pin "U5D1.DP57"
				( objectStatus "@baseboard_fab2_lib.baseboard_fab2(sch_1):page40_i20:vss(1209)" )
			)
			( pin "U5D1.DP59"
				( objectStatus "@baseboard_fab2_lib.baseboard_fab2(sch_1):page40_i20:vss(1210)" )
			)
			( pin "U5D1.DP61"
				( objectStatus "@baseboard_fab2_lib.baseboard_fab2(sch_1):page40_i20:vss(1211)" )
			)
			( pin "U5D1.DP63"
				( objectStatus "@baseboard_fab2_lib.baseboard_fab2(sch_1):page40_i20:vss(1212)" )
			)
			( pin "U5D1.DP9"
				( objectStatus "@baseboard_fab2_lib.baseboard_fab2(sch_1):page40_i20:vss(1213)" )
			)
			( pin "U5D1.DV19"
				( objectStatus "@baseboard_fab2_lib.baseboard_fab2(sch_1):page40_i20:vss(1214)" )
			)
			( pin "U5D1.DY45"
				( objectStatus "@baseboard_fab2_lib.baseboard_fab2(sch_1):page40_i20:vss(1215)" )
			)
			( pin "U5D1.DY47"
				( objectStatus "@baseboard_fab2_lib.baseboard_fab2(sch_1):page40_i20:vss(1216)" )
			)
			( pin "U5D1.DY49"
				( objectStatus "@baseboard_fab2_lib.baseboard_fab2(sch_1):page40_i20:vss(1217)" )
			)
			( pin "U5D1.DY51"
				( objectStatus "@baseboard_fab2_lib.baseboard_fab2(sch_1):page40_i20:vss(1218)" )
			)
			( pin "U5D1.DY53"
				( objectStatus "@baseboard_fab2_lib.baseboard_fab2(sch_1):page40_i20:vss(1219)" )
			)
			( pin "U5D1.DY55"
				( objectStatus "@baseboard_fab2_lib.baseboard_fab2(sch_1):page40_i20:vss(1220)" )
			)
			( pin "U5D1.DY57"
				( objectStatus "@baseboard_fab2_lib.baseboard_fab2(sch_1):page40_i20:vss(1221)" )
			)
			( pin "U5D1.DY59"
				( objectStatus "@baseboard_fab2_lib.baseboard_fab2(sch_1):page40_i20:vss(1222)" )
			)
			( pin "U5D1.DY61"
				( objectStatus "@baseboard_fab2_lib.baseboard_fab2(sch_1):page40_i20:vss(1223)" )
			)
			( pin "U5D1.DY63"
				( objectStatus "@baseboard_fab2_lib.baseboard_fab2(sch_1):page40_i20:vss(1224)" )
			)
			( pin "U5D1.EA14"
				( objectStatus "@baseboard_fab2_lib.baseboard_fab2(sch_1):page40_i20:vss(1225)" )
			)
			( pin "U5D1.L8"
				( objectStatus "@baseboard_fab2_lib.baseboard_fab2(sch_1):page40_i20:vss(1226)" )
			)
			( pin "U5D1.V11"
				( objectStatus "@baseboard_fab2_lib.baseboard_fab2(sch_1):page40_i20:vss(1227)" )
			)
			( pin "U5D1.E66"
				( objectStatus "@baseboard_fab2_lib.baseboard_fab2(sch_1):page40_i20:vss(1228)" )
			)
			( pin "U5D1.ED69"
				( objectStatus "@baseboard_fab2_lib.baseboard_fab2(sch_1):page40_i20:vss(1229)" )
			)
			( pin "U5D1.EE80"
				( objectStatus "@baseboard_fab2_lib.baseboard_fab2(sch_1):page40_i20:vss(1230)" )
			)
			( pin "U5D1.EE8"
				( objectStatus "@baseboard_fab2_lib.baseboard_fab2(sch_1):page40_i20:vss(1231)" )
			)
			( pin "U5D1.EE40"
				( objectStatus "@baseboard_fab2_lib.baseboard_fab2(sch_1):page40_i20:vss(1232)" )
			)
			( pin "U5D1.ED81"
				( objectStatus "@baseboard_fab2_lib.baseboard_fab2(sch_1):page40_i20:vss(1233)" )
			)
			( pin "U5D1.ED7"
				( objectStatus "@baseboard_fab2_lib.baseboard_fab2(sch_1):page40_i20:vss(1234)" )
			)
			( pin "U5D1.ED41"
				( objectStatus "@baseboard_fab2_lib.baseboard_fab2(sch_1):page40_i20:vss(1235)" )
			)
			( pin "U5D1.EC82"
				( objectStatus "@baseboard_fab2_lib.baseboard_fab2(sch_1):page40_i20:vss(1236)" )
			)
			( pin "U5D1.EC6"
				( objectStatus "@baseboard_fab2_lib.baseboard_fab2(sch_1):page40_i20:vss(1237)" )
			)
			( pin "U5D1.EC42"
				( objectStatus "@baseboard_fab2_lib.baseboard_fab2(sch_1):page40_i20:vss(1238)" )
			)
			( pin "U5D1.DW2"
				( objectStatus "@baseboard_fab2_lib.baseboard_fab2(sch_1):page40_i20:vss(1239)" )
			)
			( pin "U5D1.EB83"
				( objectStatus "@baseboard_fab2_lib.baseboard_fab2(sch_1):page40_i20:vss(1240)" )
			)
			( pin "U5D1.EA84"
				( objectStatus "@baseboard_fab2_lib.baseboard_fab2(sch_1):page40_i20:vss(1241)" )
			)
			( pin "U5D1.DY85"
				( objectStatus "@baseboard_fab2_lib.baseboard_fab2(sch_1):page40_i20:vss(1242)" )
			)
			( pin "U5D1.J86"
				( objectStatus "@baseboard_fab2_lib.baseboard_fab2(sch_1):page40_i20:vss(1243)" )
			)
			( pin "U5D1.E82"
				( objectStatus "@baseboard_fab2_lib.baseboard_fab2(sch_1):page40_i20:vss(1244)" )
			)
			( pin "U5D1.D81"
				( objectStatus "@baseboard_fab2_lib.baseboard_fab2(sch_1):page40_i20:vss(1245)" )
			)
			( pin "U5D1.D3"
				( objectStatus "@baseboard_fab2_lib.baseboard_fab2(sch_1):page40_i20:vss(1246)" )
			)
			( pin "U5D1.C80"
				( objectStatus "@baseboard_fab2_lib.baseboard_fab2(sch_1):page40_i20:vss(1247)" )
			)
			( pin "U5D1.C4"
				( objectStatus "@baseboard_fab2_lib.baseboard_fab2(sch_1):page40_i20:vss(1248)" )
			)
			( pin "U5D1.B79"
				( objectStatus "@baseboard_fab2_lib.baseboard_fab2(sch_1):page40_i20:vss(1249)" )
			)
			( pin "U5D1.B5"
				( objectStatus "@baseboard_fab2_lib.baseboard_fab2(sch_1):page40_i20:vss(1250)" )
			)
			( pin "U5D1.B43"
				( objectStatus "@baseboard_fab2_lib.baseboard_fab2(sch_1):page40_i20:vss(1251)" )
			)
			( pin "U5D1.A42"
				( objectStatus "@baseboard_fab2_lib.baseboard_fab2(sch_1):page40_i20:vss(1252)" )
			)
			( pin "U5D1.B9"
				( objectStatus "@baseboard_fab2_lib.baseboard_fab2(sch_1):page40_i20:vss(1253)" )
			)
			( pin "U5D1.AA16"
				( objectStatus "@baseboard_fab2_lib.baseboard_fab2(sch_1):page40_i21:vss(934)" )
			)
			( pin "U5D1.AA4"
				( objectStatus "@baseboard_fab2_lib.baseboard_fab2(sch_1):page40_i21:vss(935)" )
			)
			( pin "U5D1.Y85"
				( objectStatus "@baseboard_fab2_lib.baseboard_fab2(sch_1):page40_i21:vss(936)" )
			)
			( pin "U5D1.Y83"
				( objectStatus "@baseboard_fab2_lib.baseboard_fab2(sch_1):page40_i21:vss(937)" )
			)
			( pin "U5D1.Y81"
				( objectStatus "@baseboard_fab2_lib.baseboard_fab2(sch_1):page40_i21:vss(938)" )
			)
			( pin "U5D1.Y79"
				( objectStatus "@baseboard_fab2_lib.baseboard_fab2(sch_1):page40_i21:vss(939)" )
			)
			( pin "U5D1.Y73"
				( objectStatus "@baseboard_fab2_lib.baseboard_fab2(sch_1):page40_i21:vss(940)" )
			)
			( pin "U5D1.Y71"
				( objectStatus "@baseboard_fab2_lib.baseboard_fab2(sch_1):page40_i21:vss(941)" )
			)
			( pin "U5D1.Y9"
				( objectStatus "@baseboard_fab2_lib.baseboard_fab2(sch_1):page40_i21:vss(942)" )
			)
			( pin "U5D1.Y7"
				( objectStatus "@baseboard_fab2_lib.baseboard_fab2(sch_1):page40_i21:vss(943)" )
			)
			( pin "U5D1.Y67"
				( objectStatus "@baseboard_fab2_lib.baseboard_fab2(sch_1):page40_i21:vss(944)" )
			)
			( pin "U5D1.Y5"
				( objectStatus "@baseboard_fab2_lib.baseboard_fab2(sch_1):page40_i21:vss(945)" )
			)
			( pin "U5D1.Y17"
				( objectStatus "@baseboard_fab2_lib.baseboard_fab2(sch_1):page40_i21:vss(946)" )
			)
			( pin "U5D1.Y15"
				( objectStatus "@baseboard_fab2_lib.baseboard_fab2(sch_1):page40_i21:vss(947)" )
			)
			( pin "U5D1.W82"
				( objectStatus "@baseboard_fab2_lib.baseboard_fab2(sch_1):page40_i21:vss(948)" )
			)
			( pin "U5D1.W78"
				( objectStatus "@baseboard_fab2_lib.baseboard_fab2(sch_1):page40_i21:vss(949)" )
			)
			( pin "U5D1.W74"
				( objectStatus "@baseboard_fab2_lib.baseboard_fab2(sch_1):page40_i21:vss(950)" )
			)
			( pin "U5D1.W68"
				( objectStatus "@baseboard_fab2_lib.baseboard_fab2(sch_1):page40_i21:vss(951)" )
			)
			( pin "U5D1.W42"
				( objectStatus "@baseboard_fab2_lib.baseboard_fab2(sch_1):page40_i21:vss(952)" )
			)
			( pin "U5D1.W40"
				( objectStatus "@baseboard_fab2_lib.baseboard_fab2(sch_1):page40_i21:vss(953)" )
			)
			( pin "U5D1.W38"
				( objectStatus "@baseboard_fab2_lib.baseboard_fab2(sch_1):page40_i21:vss(954)" )
			)
			( pin "U5D1.W36"
				( objectStatus "@baseboard_fab2_lib.baseboard_fab2(sch_1):page40_i21:vss(955)" )
			)
			( pin "U5D1.W34"
				( objectStatus "@baseboard_fab2_lib.baseboard_fab2(sch_1):page40_i21:vss(956)" )
			)
			( pin "U5D1.W32"
				( objectStatus "@baseboard_fab2_lib.baseboard_fab2(sch_1):page40_i21:vss(957)" )
			)
			( pin "U5D1.W30"
				( objectStatus "@baseboard_fab2_lib.baseboard_fab2(sch_1):page40_i21:vss(958)" )
			)
			( pin "U5D1.W28"
				( objectStatus "@baseboard_fab2_lib.baseboard_fab2(sch_1):page40_i21:vss(959)" )
			)
			( pin "U5D1.W26"
				( objectStatus "@baseboard_fab2_lib.baseboard_fab2(sch_1):page40_i21:vss(960)" )
			)
			( pin "U5D1.W24"
				( objectStatus "@baseboard_fab2_lib.baseboard_fab2(sch_1):page40_i21:vss(961)" )
			)
			( pin "U5D1.W22"
				( objectStatus "@baseboard_fab2_lib.baseboard_fab2(sch_1):page40_i21:vss(962)" )
			)
			( pin "U5D1.W12"
				( objectStatus "@baseboard_fab2_lib.baseboard_fab2(sch_1):page40_i21:vss(963)" )
			)
			( pin "U5D1.AC56"
				( objectStatus "@baseboard_fab2_lib.baseboard_fab2(sch_1):page40_i21:vss(964)" )
			)
			( pin "U5D1.W8"
				( objectStatus "@baseboard_fab2_lib.baseboard_fab2(sch_1):page40_i21:vss(965)" )
			)
			( pin "U5D1.V83"
				( objectStatus "@baseboard_fab2_lib.baseboard_fab2(sch_1):page40_i21:vss(966)" )
			)
			( pin "U5D1.V77"
				( objectStatus "@baseboard_fab2_lib.baseboard_fab2(sch_1):page40_i21:vss(967)" )
			)
			( pin "U5D1.V75"
				( objectStatus "@baseboard_fab2_lib.baseboard_fab2(sch_1):page40_i21:vss(968)" )
			)
			( pin "U5D1.V73"
				( objectStatus "@baseboard_fab2_lib.baseboard_fab2(sch_1):page40_i21:vss(969)" )
			)
			( pin "U5D1.V43"
				( objectStatus "@baseboard_fab2_lib.baseboard_fab2(sch_1):page40_i21:vss(970)" )
			)
			( pin "U5D1.V23"
				( objectStatus "@baseboard_fab2_lib.baseboard_fab2(sch_1):page40_i21:vss(971)" )
			)
			( pin "U5D1.V21"
				( objectStatus "@baseboard_fab2_lib.baseboard_fab2(sch_1):page40_i21:vss(972)" )
			)
			( pin "U5D1.V15"
				( objectStatus "@baseboard_fab2_lib.baseboard_fab2(sch_1):page40_i21:vss(973)" )
			)
			( pin "U5D1.V13"
				( objectStatus "@baseboard_fab2_lib.baseboard_fab2(sch_1):page40_i21:vss(974)" )
			)
			( pin "U5D1.V9"
				( objectStatus "@baseboard_fab2_lib.baseboard_fab2(sch_1):page40_i21:vss(975)" )
			)
			( pin "U5D1.V5"
				( objectStatus "@baseboard_fab2_lib.baseboard_fab2(sch_1):page40_i21:vss(976)" )
			)
			( pin "U5D1.V1"
				( objectStatus "@baseboard_fab2_lib.baseboard_fab2(sch_1):page40_i21:vss(977)" )
			)
			( pin "U5D1.U86"
				( objectStatus "@baseboard_fab2_lib.baseboard_fab2(sch_1):page40_i21:vss(978)" )
			)
			( pin "U5D1.U80"
				( objectStatus "@baseboard_fab2_lib.baseboard_fab2(sch_1):page40_i21:vss(979)" )
			)
			( pin "U5D1.U78"
				( objectStatus "@baseboard_fab2_lib.baseboard_fab2(sch_1):page40_i21:vss(980)" )
			)
			( pin "U5D1.U76"
				( objectStatus "@baseboard_fab2_lib.baseboard_fab2(sch_1):page40_i21:vss(981)" )
			)
			( pin "U5D1.U74"
				( objectStatus "@baseboard_fab2_lib.baseboard_fab2(sch_1):page40_i21:vss(982)" )
			)
			( pin "U5D1.U70"
				( objectStatus "@baseboard_fab2_lib.baseboard_fab2(sch_1):page40_i21:vss(983)" )
			)
			( pin "U5D1.U68"
				( objectStatus "@baseboard_fab2_lib.baseboard_fab2(sch_1):page40_i21:vss(984)" )
			)
			( pin "U5D1.U42"
				( objectStatus "@baseboard_fab2_lib.baseboard_fab2(sch_1):page40_i21:vss(985)" )
			)
			( pin "U5D1.U36"
				( objectStatus "@baseboard_fab2_lib.baseboard_fab2(sch_1):page40_i21:vss(986)" )
			)
			( pin "U5D1.U30"
				( objectStatus "@baseboard_fab2_lib.baseboard_fab2(sch_1):page40_i21:vss(987)" )
			)
			( pin "U5D1.U24"
				( objectStatus "@baseboard_fab2_lib.baseboard_fab2(sch_1):page40_i21:vss(988)" )
			)
			( pin "U5D1.U22"
				( objectStatus "@baseboard_fab2_lib.baseboard_fab2(sch_1):page40_i21:vss(989)" )
			)
			( pin "U5D1.U20"
				( objectStatus "@baseboard_fab2_lib.baseboard_fab2(sch_1):page40_i21:vss(990)" )
			)
			( pin "U5D1.U6"
				( objectStatus "@baseboard_fab2_lib.baseboard_fab2(sch_1):page40_i21:vss(991)" )
			)
			( pin "U5D1.U4"
				( objectStatus "@baseboard_fab2_lib.baseboard_fab2(sch_1):page40_i21:vss(992)" )
			)
			( pin "U5D1.U2"
				( objectStatus "@baseboard_fab2_lib.baseboard_fab2(sch_1):page40_i21:vss(993)" )
			)
			( pin "U5D1.T85"
				( objectStatus "@baseboard_fab2_lib.baseboard_fab2(sch_1):page40_i21:vss(994)" )
			)
			( pin "U5D1.T83"
				( objectStatus "@baseboard_fab2_lib.baseboard_fab2(sch_1):page40_i21:vss(995)" )
			)
			( pin "U5D1.T77"
				( objectStatus "@baseboard_fab2_lib.baseboard_fab2(sch_1):page40_i21:vss(996)" )
			)
			( pin "U5D1.T73"
				( objectStatus "@baseboard_fab2_lib.baseboard_fab2(sch_1):page40_i21:vss(997)" )
			)
			( pin "U5D1.T65"
				( objectStatus "@baseboard_fab2_lib.baseboard_fab2(sch_1):page40_i21:vss(998)" )
			)
			( pin "U5D1.T41"
				( objectStatus "@baseboard_fab2_lib.baseboard_fab2(sch_1):page40_i21:vss(999)" )
			)
			( pin "U5D1.T37"
				( objectStatus "@baseboard_fab2_lib.baseboard_fab2(sch_1):page40_i21:vss(1000)" )
			)
			( pin "U5D1.T35"
				( objectStatus "@baseboard_fab2_lib.baseboard_fab2(sch_1):page40_i21:vss(1001)" )
			)
			( pin "U5D1.T31"
				( objectStatus "@baseboard_fab2_lib.baseboard_fab2(sch_1):page40_i21:vss(1002)" )
			)
			( pin "U5D1.T29"
				( objectStatus "@baseboard_fab2_lib.baseboard_fab2(sch_1):page40_i21:vss(1003)" )
			)
			( pin "U5D1.T25"
				( objectStatus "@baseboard_fab2_lib.baseboard_fab2(sch_1):page40_i21:vss(1004)" )
			)
			( pin "U5D1.T17"
				( objectStatus "@baseboard_fab2_lib.baseboard_fab2(sch_1):page40_i21:vss(1005)" )
			)
			( pin "U5D1.T13"
				( objectStatus "@baseboard_fab2_lib.baseboard_fab2(sch_1):page40_i21:vss(1006)" )
			)
			( pin "U5D1.R86"
				( objectStatus "@baseboard_fab2_lib.baseboard_fab2(sch_1):page40_i21:vss(1007)" )
			)
			( pin "U5D1.R78"
				( objectStatus "@baseboard_fab2_lib.baseboard_fab2(sch_1):page40_i21:vss(1008)" )
			)
			( pin "U5D1.R72"
				( objectStatus "@baseboard_fab2_lib.baseboard_fab2(sch_1):page40_i21:vss(1009)" )
			)
			( pin "U5D1.R68"
				( objectStatus "@baseboard_fab2_lib.baseboard_fab2(sch_1):page40_i21:vss(1010)" )
			)
			( pin "U5D1.R40"
				( objectStatus "@baseboard_fab2_lib.baseboard_fab2(sch_1):page40_i21:vss(1011)" )
			)
			( pin "U5D1.R38"
				( objectStatus "@baseboard_fab2_lib.baseboard_fab2(sch_1):page40_i21:vss(1012)" )
			)
			( pin "U5D1.R34"
				( objectStatus "@baseboard_fab2_lib.baseboard_fab2(sch_1):page40_i21:vss(1013)" )
			)
			( pin "U5D1.R32"
				( objectStatus "@baseboard_fab2_lib.baseboard_fab2(sch_1):page40_i21:vss(1014)" )
			)
			( pin "U5D1.R28"
				( objectStatus "@baseboard_fab2_lib.baseboard_fab2(sch_1):page40_i21:vss(1015)" )
			)
			( pin "U5D1.R26"
				( objectStatus "@baseboard_fab2_lib.baseboard_fab2(sch_1):page40_i21:vss(1016)" )
			)
			( pin "U5D1.R22"
				( objectStatus "@baseboard_fab2_lib.baseboard_fab2(sch_1):page40_i21:vss(1017)" )
			)
			( pin "U5D1.R4"
				( objectStatus "@baseboard_fab2_lib.baseboard_fab2(sch_1):page40_i21:vss(1018)" )
			)
			( pin "U5D1.R2"
				( objectStatus "@baseboard_fab2_lib.baseboard_fab2(sch_1):page40_i21:vss(1019)" )
			)
			( pin "U5D1.R18"
				( objectStatus "@baseboard_fab2_lib.baseboard_fab2(sch_1):page40_i21:vss(1020)" )
			)
			( pin "U5D1.R14"
				( objectStatus "@baseboard_fab2_lib.baseboard_fab2(sch_1):page40_i21:vss(1021)" )
			)
			( pin "U5D1.P83"
				( objectStatus "@baseboard_fab2_lib.baseboard_fab2(sch_1):page40_i21:vss(1022)" )
			)
			( pin "U5D1.P81"
				( objectStatus "@baseboard_fab2_lib.baseboard_fab2(sch_1):page40_i21:vss(1023)" )
			)
			( pin "U5D1.P71"
				( objectStatus "@baseboard_fab2_lib.baseboard_fab2(sch_1):page40_i21:vss(1024)" )
			)
			( pin "U5D1.P69"
				( objectStatus "@baseboard_fab2_lib.baseboard_fab2(sch_1):page40_i21:vss(1025)" )
			)
			( pin "U5D1.P67"
				( objectStatus "@baseboard_fab2_lib.baseboard_fab2(sch_1):page40_i21:vss(1026)" )
			)
			( pin "U5D1.P39"
				( objectStatus "@baseboard_fab2_lib.baseboard_fab2(sch_1):page40_i21:vss(1027)" )
			)
			( pin "U5D1.P33"
				( objectStatus "@baseboard_fab2_lib.baseboard_fab2(sch_1):page40_i21:vss(1028)" )
			)
			( pin "U5D1.P27"
				( objectStatus "@baseboard_fab2_lib.baseboard_fab2(sch_1):page40_i21:vss(1029)" )
			)
			( pin "U5D1.P15"
				( objectStatus "@baseboard_fab2_lib.baseboard_fab2(sch_1):page40_i21:vss(1030)" )
			)
			( pin "U5D1.P11"
				( objectStatus "@baseboard_fab2_lib.baseboard_fab2(sch_1):page40_i21:vss(1031)" )
			)
			( pin "U5D1.N8"
				( objectStatus "@baseboard_fab2_lib.baseboard_fab2(sch_1):page40_i21:vss(1032)" )
			)
			( pin "U5D1.N4"
				( objectStatus "@baseboard_fab2_lib.baseboard_fab2(sch_1):page40_i21:vss(1033)" )
			)
			( pin "U5D1.N78"
				( objectStatus "@baseboard_fab2_lib.baseboard_fab2(sch_1):page40_i21:vss(1034)" )
			)
			( pin "U5D1.N76"
				( objectStatus "@baseboard_fab2_lib.baseboard_fab2(sch_1):page40_i21:vss(1035)" )
			)
			( pin "U5D1.N74"
				( objectStatus "@baseboard_fab2_lib.baseboard_fab2(sch_1):page40_i21:vss(1036)" )
			)
			( pin "U5D1.N72"
				( objectStatus "@baseboard_fab2_lib.baseboard_fab2(sch_1):page40_i21:vss(1037)" )
			)
			( pin "U5D1.N70"
				( objectStatus "@baseboard_fab2_lib.baseboard_fab2(sch_1):page40_i21:vss(1038)" )
			)
			( pin "U5D1.N66"
				( objectStatus "@baseboard_fab2_lib.baseboard_fab2(sch_1):page40_i21:vss(1039)" )
			)
			( pin "U5D1.N6"
				( objectStatus "@baseboard_fab2_lib.baseboard_fab2(sch_1):page40_i21:vss(1040)" )
			)
			( pin "U5D1.N22"
				( objectStatus "@baseboard_fab2_lib.baseboard_fab2(sch_1):page40_i21:vss(1041)" )
			)
			( pin "U5D1.N20"
				( objectStatus "@baseboard_fab2_lib.baseboard_fab2(sch_1):page40_i21:vss(1042)" )
			)
			( pin "U5D1.DM19"
				( objectStatus "@baseboard_fab2_lib.baseboard_fab2(sch_1):page40_i21:vss(1043)" )
			)
			( pin "U5D1.M85"
				( objectStatus "@baseboard_fab2_lib.baseboard_fab2(sch_1):page40_i21:vss(1044)" )
			)
			( pin "U5D1.M83"
				( objectStatus "@baseboard_fab2_lib.baseboard_fab2(sch_1):page40_i21:vss(1045)" )
			)
			( pin "U5D1.M79"
				( objectStatus "@baseboard_fab2_lib.baseboard_fab2(sch_1):page40_i21:vss(1046)" )
			)
			( pin "U5D1.M71"
				( objectStatus "@baseboard_fab2_lib.baseboard_fab2(sch_1):page40_i21:vss(1047)" )
			)
			( pin "U5D1.M65"
				( objectStatus "@baseboard_fab2_lib.baseboard_fab2(sch_1):page40_i21:vss(1048)" )
			)
			( pin "U5D1.M43"
				( objectStatus "@baseboard_fab2_lib.baseboard_fab2(sch_1):page40_i21:vss(1049)" )
			)
			( pin "U5D1.M41"
				( objectStatus "@baseboard_fab2_lib.baseboard_fab2(sch_1):page40_i21:vss(1050)" )
			)
			( pin "U5D1.M39"
				( objectStatus "@baseboard_fab2_lib.baseboard_fab2(sch_1):page40_i21:vss(1051)" )
			)
			( pin "U5D1.M37"
				( objectStatus "@baseboard_fab2_lib.baseboard_fab2(sch_1):page40_i21:vss(1052)" )
			)
			( pin "U5D1.M35"
				( objectStatus "@baseboard_fab2_lib.baseboard_fab2(sch_1):page40_i21:vss(1053)" )
			)
			( pin "U5D1.M33"
				( objectStatus "@baseboard_fab2_lib.baseboard_fab2(sch_1):page40_i21:vss(1054)" )
			)
			( pin "U5D1.M31"
				( objectStatus "@baseboard_fab2_lib.baseboard_fab2(sch_1):page40_i21:vss(1055)" )
			)
			( pin "U5D1.M29"
				( objectStatus "@baseboard_fab2_lib.baseboard_fab2(sch_1):page40_i21:vss(1056)" )
			)
			( pin "U5D1.M27"
				( objectStatus "@baseboard_fab2_lib.baseboard_fab2(sch_1):page40_i21:vss(1057)" )
			)
			( pin "U5D1.M25"
				( objectStatus "@baseboard_fab2_lib.baseboard_fab2(sch_1):page40_i21:vss(1058)" )
			)
			( pin "U5D1.M23"
				( objectStatus "@baseboard_fab2_lib.baseboard_fab2(sch_1):page40_i21:vss(1059)" )
			)
			( pin "U5D1.M19"
				( objectStatus "@baseboard_fab2_lib.baseboard_fab2(sch_1):page40_i21:vss(1060)" )
			)
			( pin "U5D1.M17"
				( objectStatus "@baseboard_fab2_lib.baseboard_fab2(sch_1):page40_i21:vss(1061)" )
			)
			( pin "U5D1.M15"
				( objectStatus "@baseboard_fab2_lib.baseboard_fab2(sch_1):page40_i21:vss(1062)" )
			)
			( pin "U5D1.CT7"
				( objectStatus "@baseboard_fab2_lib.baseboard_fab2(sch_1):page40_i21:vss(1063)" )
			)
			( pin "U5D1.BT9"
				( objectStatus "@baseboard_fab2_lib.baseboard_fab2(sch_1):page40_i21:vss(1064)" )
			)
			( pin "U5D1.L82"
				( objectStatus "@baseboard_fab2_lib.baseboard_fab2(sch_1):page40_i21:vss(1065)" )
			)
			( pin "U5D1.L80"
				( objectStatus "@baseboard_fab2_lib.baseboard_fab2(sch_1):page40_i21:vss(1066)" )
			)
			( pin "U5D1.L78"
				( objectStatus "@baseboard_fab2_lib.baseboard_fab2(sch_1):page40_i21:vss(1067)" )
			)
			( pin "U5D1.L72"
				( objectStatus "@baseboard_fab2_lib.baseboard_fab2(sch_1):page40_i21:vss(1068)" )
			)
			( pin "U5D1.L22"
				( objectStatus "@baseboard_fab2_lib.baseboard_fab2(sch_1):page40_i21:vss(1069)" )
			)
			( pin "U5D1.L20"
				( objectStatus "@baseboard_fab2_lib.baseboard_fab2(sch_1):page40_i21:vss(1070)" )
			)
			( pin "U5D1.L6"
				( objectStatus "@baseboard_fab2_lib.baseboard_fab2(sch_1):page40_i21:vss(1071)" )
			)
			( pin "U5D1.L2"
				( objectStatus "@baseboard_fab2_lib.baseboard_fab2(sch_1):page40_i21:vss(1072)" )
			)
			( pin "U5D1.L10"
				( objectStatus "@baseboard_fab2_lib.baseboard_fab2(sch_1):page40_i21:vss(1073)" )
			)
			( pin "U5D1.K85"
				( objectStatus "@baseboard_fab2_lib.baseboard_fab2(sch_1):page40_i21:vss(1074)" )
			)
			( pin "U5D1.K83"
				( objectStatus "@baseboard_fab2_lib.baseboard_fab2(sch_1):page40_i21:vss(1075)" )
			)
			( pin "U5D1.K81"
				( objectStatus "@baseboard_fab2_lib.baseboard_fab2(sch_1):page40_i21:vss(1076)" )
			)
			( pin "U5D1.K77"
				( objectStatus "@baseboard_fab2_lib.baseboard_fab2(sch_1):page40_i21:vss(1077)" )
			)
			( pin "U5D1.K73"
				( objectStatus "@baseboard_fab2_lib.baseboard_fab2(sch_1):page40_i21:vss(1078)" )
			)
			( pin "U5D1.K71"
				( objectStatus "@baseboard_fab2_lib.baseboard_fab2(sch_1):page40_i21:vss(1079)" )
			)
			( pin "U5D1.K69"
				( objectStatus "@baseboard_fab2_lib.baseboard_fab2(sch_1):page40_i21:vss(1080)" )
			)
			( pin "U5D1.K67"
				( objectStatus "@baseboard_fab2_lib.baseboard_fab2(sch_1):page40_i21:vss(1081)" )
			)
			( pin "U5D1.K65"
				( objectStatus "@baseboard_fab2_lib.baseboard_fab2(sch_1):page40_i21:vss(1082)" )
			)
			( pin "U5D1.K39"
				( objectStatus "@baseboard_fab2_lib.baseboard_fab2(sch_1):page40_i21:vss(1083)" )
			)
			( pin "U5D1.K33"
				( objectStatus "@baseboard_fab2_lib.baseboard_fab2(sch_1):page40_i21:vss(1084)" )
			)
			( pin "U5D1.K27"
				( objectStatus "@baseboard_fab2_lib.baseboard_fab2(sch_1):page40_i21:vss(1085)" )
			)
			( pin "U5D1.DB7"
				( objectStatus "@baseboard_fab2_lib.baseboard_fab2(sch_1):page40_i21:vss(1086)" )
			)
			( pin "U5D1.K17"
				( objectStatus "@baseboard_fab2_lib.baseboard_fab2(sch_1):page40_i21:vss(1087)" )
			)
			( pin "U5D1.K13"
				( objectStatus "@baseboard_fab2_lib.baseboard_fab2(sch_1):page40_i21:vss(1088)" )
			)
			( pin "U5D1.K11"
				( objectStatus "@baseboard_fab2_lib.baseboard_fab2(sch_1):page40_i21:vss(1089)" )
			)
			( pin "U5D1.K1"
				( objectStatus "@baseboard_fab2_lib.baseboard_fab2(sch_1):page40_i21:vss(1090)" )
			)
			( pin "U5D1.J84"
				( objectStatus "@baseboard_fab2_lib.baseboard_fab2(sch_1):page40_i21:vss(1091)" )
			)
			( pin "U5D1.J82"
				( objectStatus "@baseboard_fab2_lib.baseboard_fab2(sch_1):page40_i21:vss(1092)" )
			)
			( pin "U5D1.J76"
				( objectStatus "@baseboard_fab2_lib.baseboard_fab2(sch_1):page40_i21:vss(1093)" )
			)
			( pin "U5D1.AL68"
				( objectStatus "@baseboard_fab2_lib.baseboard_fab2(sch_1):page40_i22:vss(774)" )
			)
			( pin "U5D1.AL64"
				( objectStatus "@baseboard_fab2_lib.baseboard_fab2(sch_1):page40_i22:vss(775)" )
			)
			( pin "U5D1.AL56"
				( objectStatus "@baseboard_fab2_lib.baseboard_fab2(sch_1):page40_i22:vss(776)" )
			)
			( pin "U5D1.AL32"
				( objectStatus "@baseboard_fab2_lib.baseboard_fab2(sch_1):page40_i22:vss(777)" )
			)
			( pin "U5D1.AL30"
				( objectStatus "@baseboard_fab2_lib.baseboard_fab2(sch_1):page40_i22:vss(778)" )
			)
			( pin "U5D1.AL24"
				( objectStatus "@baseboard_fab2_lib.baseboard_fab2(sch_1):page40_i22:vss(779)" )
			)
			( pin "U5D1.AL10"
				( objectStatus "@baseboard_fab2_lib.baseboard_fab2(sch_1):page40_i22:vss(780)" )
			)
			( pin "U5D1.AL4"
				( objectStatus "@baseboard_fab2_lib.baseboard_fab2(sch_1):page40_i22:vss(781)" )
			)
			( pin "U5D1.AK85"
				( objectStatus "@baseboard_fab2_lib.baseboard_fab2(sch_1):page40_i22:vss(782)" )
			)
			( pin "U5D1.AK83"
				( objectStatus "@baseboard_fab2_lib.baseboard_fab2(sch_1):page40_i22:vss(783)" )
			)
			( pin "U5D1.AK81"
				( objectStatus "@baseboard_fab2_lib.baseboard_fab2(sch_1):page40_i22:vss(784)" )
			)
			( pin "U5D1.AK79"
				( objectStatus "@baseboard_fab2_lib.baseboard_fab2(sch_1):page40_i22:vss(785)" )
			)
			( pin "U5D1.AK73"
				( objectStatus "@baseboard_fab2_lib.baseboard_fab2(sch_1):page40_i22:vss(786)" )
			)
			( pin "U5D1.AK67"
				( objectStatus "@baseboard_fab2_lib.baseboard_fab2(sch_1):page40_i22:vss(787)" )
			)
			( pin "U5D1.AK65"
				( objectStatus "@baseboard_fab2_lib.baseboard_fab2(sch_1):page40_i22:vss(788)" )
			)
			( pin "U5D1.AK55"
				( objectStatus "@baseboard_fab2_lib.baseboard_fab2(sch_1):page40_i22:vss(789)" )
			)
			( pin "U5D1.AK33"
				( objectStatus "@baseboard_fab2_lib.baseboard_fab2(sch_1):page40_i22:vss(790)" )
			)
			( pin "U5D1.AK31"
				( objectStatus "@baseboard_fab2_lib.baseboard_fab2(sch_1):page40_i22:vss(791)" )
			)
			( pin "U5D1.AK29"
				( objectStatus "@baseboard_fab2_lib.baseboard_fab2(sch_1):page40_i22:vss(792)" )
			)
			( pin "U5D1.AK25"
				( objectStatus "@baseboard_fab2_lib.baseboard_fab2(sch_1):page40_i22:vss(793)" )
			)
			( pin "U5D1.AK23"
				( objectStatus "@baseboard_fab2_lib.baseboard_fab2(sch_1):page40_i22:vss(794)" )
			)
			( pin "U5D1.AK19"
				( objectStatus "@baseboard_fab2_lib.baseboard_fab2(sch_1):page40_i22:vss(795)" )
			)
			( pin "U5D1.AK13"
				( objectStatus "@baseboard_fab2_lib.baseboard_fab2(sch_1):page40_i22:vss(796)" )
			)
			( pin "U5D1.AK9"
				( objectStatus "@baseboard_fab2_lib.baseboard_fab2(sch_1):page40_i22:vss(797)" )
			)
			( pin "U5D1.AJ86"
				( objectStatus "@baseboard_fab2_lib.baseboard_fab2(sch_1):page40_i22:vss(798)" )
			)
			( pin "U5D1.AJ82"
				( objectStatus "@baseboard_fab2_lib.baseboard_fab2(sch_1):page40_i22:vss(799)" )
			)
			( pin "U5D1.AJ78"
				( objectStatus "@baseboard_fab2_lib.baseboard_fab2(sch_1):page40_i22:vss(800)" )
			)
			( pin "U5D1.AJ74"
				( objectStatus "@baseboard_fab2_lib.baseboard_fab2(sch_1):page40_i22:vss(801)" )
			)
			( pin "U5D1.AJ68"
				( objectStatus "@baseboard_fab2_lib.baseboard_fab2(sch_1):page40_i22:vss(802)" )
			)
			( pin "U5D1.AJ66"
				( objectStatus "@baseboard_fab2_lib.baseboard_fab2(sch_1):page40_i22:vss(803)" )
			)
			( pin "U5D1.AJ54"
				( objectStatus "@baseboard_fab2_lib.baseboard_fab2(sch_1):page40_i22:vss(804)" )
			)
			( pin "U5D1.AJ52"
				( objectStatus "@baseboard_fab2_lib.baseboard_fab2(sch_1):page40_i22:vss(805)" )
			)
			( pin "U5D1.AJ50"
				( objectStatus "@baseboard_fab2_lib.baseboard_fab2(sch_1):page40_i22:vss(806)" )
			)
			( pin "U5D1.AJ48"
				( objectStatus "@baseboard_fab2_lib.baseboard_fab2(sch_1):page40_i22:vss(807)" )
			)
			( pin "U5D1.AJ46"
				( objectStatus "@baseboard_fab2_lib.baseboard_fab2(sch_1):page40_i22:vss(808)" )
			)
			( pin "U5D1.AJ34"
				( objectStatus "@baseboard_fab2_lib.baseboard_fab2(sch_1):page40_i22:vss(809)" )
			)
			( pin "U5D1.AJ32"
				( objectStatus "@baseboard_fab2_lib.baseboard_fab2(sch_1):page40_i22:vss(810)" )
			)
			( pin "U5D1.AJ28"
				( objectStatus "@baseboard_fab2_lib.baseboard_fab2(sch_1):page40_i22:vss(811)" )
			)
			( pin "U5D1.AJ26"
				( objectStatus "@baseboard_fab2_lib.baseboard_fab2(sch_1):page40_i22:vss(812)" )
			)
			( pin "U5D1.AJ22"
				( objectStatus "@baseboard_fab2_lib.baseboard_fab2(sch_1):page40_i22:vss(813)" )
			)
			( pin "U5D1.AJ8"
				( objectStatus "@baseboard_fab2_lib.baseboard_fab2(sch_1):page40_i22:vss(814)" )
			)
			( pin "U5D1.AH83"
				( objectStatus "@baseboard_fab2_lib.baseboard_fab2(sch_1):page40_i22:vss(815)" )
			)
			( pin "U5D1.AH77"
				( objectStatus "@baseboard_fab2_lib.baseboard_fab2(sch_1):page40_i22:vss(816)" )
			)
			( pin "U5D1.AH75"
				( objectStatus "@baseboard_fab2_lib.baseboard_fab2(sch_1):page40_i22:vss(817)" )
			)
			( pin "U5D1.AH69"
				( objectStatus "@baseboard_fab2_lib.baseboard_fab2(sch_1):page40_i22:vss(818)" )
			)
			( pin "U5D1.AH65"
				( objectStatus "@baseboard_fab2_lib.baseboard_fab2(sch_1):page40_i22:vss(819)" )
			)
			( pin "U5D1.AH61"
				( objectStatus "@baseboard_fab2_lib.baseboard_fab2(sch_1):page40_i22:vss(820)" )
			)
			( pin "U5D1.AH59"
				( objectStatus "@baseboard_fab2_lib.baseboard_fab2(sch_1):page40_i22:vss(821)" )
			)
			( pin "U5D1.AH53"
				( objectStatus "@baseboard_fab2_lib.baseboard_fab2(sch_1):page40_i22:vss(822)" )
			)
			( pin "U5D1.AH51"
				( objectStatus "@baseboard_fab2_lib.baseboard_fab2(sch_1):page40_i22:vss(823)" )
			)
			( pin "U5D1.AH49"
				( objectStatus "@baseboard_fab2_lib.baseboard_fab2(sch_1):page40_i22:vss(824)" )
			)
			( pin "U5D1.AH47"
				( objectStatus "@baseboard_fab2_lib.baseboard_fab2(sch_1):page40_i22:vss(825)" )
			)
			( pin "U5D1.AH45"
				( objectStatus "@baseboard_fab2_lib.baseboard_fab2(sch_1):page40_i22:vss(826)" )
			)
			( pin "U5D1.AH35"
				( objectStatus "@baseboard_fab2_lib.baseboard_fab2(sch_1):page40_i22:vss(827)" )
			)
			( pin "U5D1.AH33"
				( objectStatus "@baseboard_fab2_lib.baseboard_fab2(sch_1):page40_i22:vss(828)" )
			)
			( pin "U5D1.AH27"
				( objectStatus "@baseboard_fab2_lib.baseboard_fab2(sch_1):page40_i22:vss(829)" )
			)
			( pin "U5D1.AH21"
				( objectStatus "@baseboard_fab2_lib.baseboard_fab2(sch_1):page40_i22:vss(830)" )
			)
			( pin "U5D1.AH5"
				( objectStatus "@baseboard_fab2_lib.baseboard_fab2(sch_1):page40_i22:vss(831)" )
			)
			( pin "U5D1.AH1"
				( objectStatus "@baseboard_fab2_lib.baseboard_fab2(sch_1):page40_i22:vss(832)" )
			)
			( pin "U5D1.AG80"
				( objectStatus "@baseboard_fab2_lib.baseboard_fab2(sch_1):page40_i22:vss(833)" )
			)
			( pin "U5D1.AG78"
				( objectStatus "@baseboard_fab2_lib.baseboard_fab2(sch_1):page40_i22:vss(834)" )
			)
			( pin "U5D1.AG76"
				( objectStatus "@baseboard_fab2_lib.baseboard_fab2(sch_1):page40_i22:vss(835)" )
			)
			( pin "U5D1.AG74"
				( objectStatus "@baseboard_fab2_lib.baseboard_fab2(sch_1):page40_i22:vss(836)" )
			)
			( pin "U5D1.AG70"
				( objectStatus "@baseboard_fab2_lib.baseboard_fab2(sch_1):page40_i22:vss(837)" )
			)
			( pin "U5D1.AG64"
				( objectStatus "@baseboard_fab2_lib.baseboard_fab2(sch_1):page40_i22:vss(838)" )
			)
			( pin "U5D1.AG36"
				( objectStatus "@baseboard_fab2_lib.baseboard_fab2(sch_1):page40_i22:vss(839)" )
			)
			( pin "U5D1.AG18"
				( objectStatus "@baseboard_fab2_lib.baseboard_fab2(sch_1):page40_i22:vss(840)" )
			)
			( pin "U5D1.AG14"
				( objectStatus "@baseboard_fab2_lib.baseboard_fab2(sch_1):page40_i22:vss(841)" )
			)
			( pin "U5D1.AG12"
				( objectStatus "@baseboard_fab2_lib.baseboard_fab2(sch_1):page40_i22:vss(842)" )
			)
			( pin "U5D1.AF85"
				( objectStatus "@baseboard_fab2_lib.baseboard_fab2(sch_1):page40_i22:vss(843)" )
			)
			( pin "U5D1.AF83"
				( objectStatus "@baseboard_fab2_lib.baseboard_fab2(sch_1):page40_i22:vss(844)" )
			)
			( pin "U5D1.AF77"
				( objectStatus "@baseboard_fab2_lib.baseboard_fab2(sch_1):page40_i22:vss(845)" )
			)
			( pin "U5D1.AF73"
				( objectStatus "@baseboard_fab2_lib.baseboard_fab2(sch_1):page40_i22:vss(846)" )
			)
			( pin "U5D1.AF41"
				( objectStatus "@baseboard_fab2_lib.baseboard_fab2(sch_1):page40_i22:vss(847)" )
			)
			( pin "U5D1.AF39"
				( objectStatus "@baseboard_fab2_lib.baseboard_fab2(sch_1):page40_i22:vss(848)" )
			)
			( pin "U5D1.AF37"
				( objectStatus "@baseboard_fab2_lib.baseboard_fab2(sch_1):page40_i22:vss(849)" )
			)
			( pin "U5D1.AF33"
				( objectStatus "@baseboard_fab2_lib.baseboard_fab2(sch_1):page40_i22:vss(850)" )
			)
			( pin "U5D1.AF31"
				( objectStatus "@baseboard_fab2_lib.baseboard_fab2(sch_1):page40_i22:vss(851)" )
			)
			( pin "U5D1.AF29"
				( objectStatus "@baseboard_fab2_lib.baseboard_fab2(sch_1):page40_i22:vss(852)" )
			)
			( pin "U5D1.AF27"
				( objectStatus "@baseboard_fab2_lib.baseboard_fab2(sch_1):page40_i22:vss(853)" )
			)
			( pin "U5D1.AF25"
				( objectStatus "@baseboard_fab2_lib.baseboard_fab2(sch_1):page40_i22:vss(854)" )
			)
			( pin "U5D1.AF23"
				( objectStatus "@baseboard_fab2_lib.baseboard_fab2(sch_1):page40_i22:vss(855)" )
			)
			( pin "U5D1.AF21"
				( objectStatus "@baseboard_fab2_lib.baseboard_fab2(sch_1):page40_i22:vss(856)" )
			)
			( pin "U5D1.AF9"
				( objectStatus "@baseboard_fab2_lib.baseboard_fab2(sch_1):page40_i22:vss(857)" )
			)
			( pin "U5D1.AC52"
				( objectStatus "@baseboard_fab2_lib.baseboard_fab2(sch_1):page40_i22:vss(858)" )
			)
			( pin "U5D1.AF1"
				( objectStatus "@baseboard_fab2_lib.baseboard_fab2(sch_1):page40_i22:vss(859)" )
			)
			( pin "U5D1.AE78"
				( objectStatus "@baseboard_fab2_lib.baseboard_fab2(sch_1):page40_i22:vss(860)" )
			)
			( pin "U5D1.AE70"
				( objectStatus "@baseboard_fab2_lib.baseboard_fab2(sch_1):page40_i22:vss(861)" )
			)
			( pin "U5D1.AE68"
				( objectStatus "@baseboard_fab2_lib.baseboard_fab2(sch_1):page40_i22:vss(862)" )
			)
			( pin "U5D1.AE66"
				( objectStatus "@baseboard_fab2_lib.baseboard_fab2(sch_1):page40_i22:vss(863)" )
			)
			( pin "U5D1.AE64"
				( objectStatus "@baseboard_fab2_lib.baseboard_fab2(sch_1):page40_i22:vss(864)" )
			)
			( pin "U5D1.AE42"
				( objectStatus "@baseboard_fab2_lib.baseboard_fab2(sch_1):page40_i22:vss(865)" )
			)
			( pin "U5D1.AE40"
				( objectStatus "@baseboard_fab2_lib.baseboard_fab2(sch_1):page40_i22:vss(866)" )
			)
			( pin "U5D1.AE38"
				( objectStatus "@baseboard_fab2_lib.baseboard_fab2(sch_1):page40_i22:vss(867)" )
			)
			( pin "U5D1.AE16"
				( objectStatus "@baseboard_fab2_lib.baseboard_fab2(sch_1):page40_i22:vss(868)" )
			)
			( pin "U5D1.AC54"
				( objectStatus "@baseboard_fab2_lib.baseboard_fab2(sch_1):page40_i22:vss(869)" )
			)
			( pin "U5D1.AE8"
				( objectStatus "@baseboard_fab2_lib.baseboard_fab2(sch_1):page40_i22:vss(870)" )
			)
			( pin "U5D1.AE4"
				( objectStatus "@baseboard_fab2_lib.baseboard_fab2(sch_1):page40_i22:vss(871)" )
			)
			( pin "U5D1.AD85"
				( objectStatus "@baseboard_fab2_lib.baseboard_fab2(sch_1):page40_i22:vss(872)" )
			)
			( pin "U5D1.AD83"
				( objectStatus "@baseboard_fab2_lib.baseboard_fab2(sch_1):page40_i22:vss(873)" )
			)
			( pin "U5D1.AD81"
				( objectStatus "@baseboard_fab2_lib.baseboard_fab2(sch_1):page40_i22:vss(874)" )
			)
			( pin "U5D1.AD75"
				( objectStatus "@baseboard_fab2_lib.baseboard_fab2(sch_1):page40_i22:vss(875)" )
			)
			( pin "U5D1.AD73"
				( objectStatus "@baseboard_fab2_lib.baseboard_fab2(sch_1):page40_i22:vss(876)" )
			)
			( pin "U5D1.AD71"
				( objectStatus "@baseboard_fab2_lib.baseboard_fab2(sch_1):page40_i22:vss(877)" )
			)
			( pin "U5D1.AD43"
				( objectStatus "@baseboard_fab2_lib.baseboard_fab2(sch_1):page40_i22:vss(878)" )
			)
			( pin "U5D1.AD39"
				( objectStatus "@baseboard_fab2_lib.baseboard_fab2(sch_1):page40_i22:vss(879)" )
			)
			( pin "U5D1.AD33"
				( objectStatus "@baseboard_fab2_lib.baseboard_fab2(sch_1):page40_i22:vss(880)" )
			)
			( pin "U5D1.AD27"
				( objectStatus "@baseboard_fab2_lib.baseboard_fab2(sch_1):page40_i22:vss(881)" )
			)
			( pin "U5D1.AD21"
				( objectStatus "@baseboard_fab2_lib.baseboard_fab2(sch_1):page40_i22:vss(882)" )
			)
			( pin "U5D1.AD19"
				( objectStatus "@baseboard_fab2_lib.baseboard_fab2(sch_1):page40_i22:vss(883)" )
			)
			( pin "U5D1.AD15"
				( objectStatus "@baseboard_fab2_lib.baseboard_fab2(sch_1):page40_i22:vss(884)" )
			)
			( pin "U5D1.AD13"
				( objectStatus "@baseboard_fab2_lib.baseboard_fab2(sch_1):page40_i22:vss(885)" )
			)
			( pin "U5D1.AD11"
				( objectStatus "@baseboard_fab2_lib.baseboard_fab2(sch_1):page40_i22:vss(886)" )
			)
			( pin "U5D1.AD9"
				( objectStatus "@baseboard_fab2_lib.baseboard_fab2(sch_1):page40_i22:vss(887)" )
			)
			( pin "U5D1.AD7"
				( objectStatus "@baseboard_fab2_lib.baseboard_fab2(sch_1):page40_i22:vss(888)" )
			)
			( pin "U5D1.AD3"
				( objectStatus "@baseboard_fab2_lib.baseboard_fab2(sch_1):page40_i22:vss(889)" )
			)
			( pin "U5D1.AC86"
				( objectStatus "@baseboard_fab2_lib.baseboard_fab2(sch_1):page40_i22:vss(890)" )
			)
			( pin "U5D1.AC84"
				( objectStatus "@baseboard_fab2_lib.baseboard_fab2(sch_1):page40_i22:vss(891)" )
			)
			( pin "U5D1.AC78"
				( objectStatus "@baseboard_fab2_lib.baseboard_fab2(sch_1):page40_i22:vss(892)" )
			)
			( pin "U5D1.AC72"
				( objectStatus "@baseboard_fab2_lib.baseboard_fab2(sch_1):page40_i22:vss(893)" )
			)
			( pin "U5D1.AC70"
				( objectStatus "@baseboard_fab2_lib.baseboard_fab2(sch_1):page40_i22:vss(894)" )
			)
			( pin "U5D1.AC64"
				( objectStatus "@baseboard_fab2_lib.baseboard_fab2(sch_1):page40_i22:vss(895)" )
			)
			( pin "U5D1.AC40"
				( objectStatus "@baseboard_fab2_lib.baseboard_fab2(sch_1):page40_i22:vss(896)" )
			)
			( pin "U5D1.AC38"
				( objectStatus "@baseboard_fab2_lib.baseboard_fab2(sch_1):page40_i22:vss(897)" )
			)
			( pin "U5D1.AC34"
				( objectStatus "@baseboard_fab2_lib.baseboard_fab2(sch_1):page40_i22:vss(898)" )
			)
			( pin "U5D1.AC32"
				( objectStatus "@baseboard_fab2_lib.baseboard_fab2(sch_1):page40_i22:vss(899)" )
			)
			( pin "U5D1.AC28"
				( objectStatus "@baseboard_fab2_lib.baseboard_fab2(sch_1):page40_i22:vss(900)" )
			)
			( pin "U5D1.AC26"
				( objectStatus "@baseboard_fab2_lib.baseboard_fab2(sch_1):page40_i22:vss(901)" )
			)
			( pin "U5D1.AC22"
				( objectStatus "@baseboard_fab2_lib.baseboard_fab2(sch_1):page40_i22:vss(902)" )
			)
			( pin "U5D1.AC18"
				( objectStatus "@baseboard_fab2_lib.baseboard_fab2(sch_1):page40_i22:vss(903)" )
			)
			( pin "U5D1.AB85"
				( objectStatus "@baseboard_fab2_lib.baseboard_fab2(sch_1):page40_i22:vss(904)" )
			)
			( pin "U5D1.AB83"
				( objectStatus "@baseboard_fab2_lib.baseboard_fab2(sch_1):page40_i22:vss(905)" )
			)
			( pin "U5D1.AB79"
				( objectStatus "@baseboard_fab2_lib.baseboard_fab2(sch_1):page40_i22:vss(906)" )
			)
			( pin "U5D1.AB73"
				( objectStatus "@baseboard_fab2_lib.baseboard_fab2(sch_1):page40_i22:vss(907)" )
			)
			( pin "U5D1.AB69"
				( objectStatus "@baseboard_fab2_lib.baseboard_fab2(sch_1):page40_i22:vss(908)" )
			)
			( pin "U5D1.AB65"
				( objectStatus "@baseboard_fab2_lib.baseboard_fab2(sch_1):page40_i22:vss(909)" )
			)
			( pin "U5D1.AB41"
				( objectStatus "@baseboard_fab2_lib.baseboard_fab2(sch_1):page40_i22:vss(910)" )
			)
			( pin "U5D1.AB37"
				( objectStatus "@baseboard_fab2_lib.baseboard_fab2(sch_1):page40_i22:vss(911)" )
			)
			( pin "U5D1.AB35"
				( objectStatus "@baseboard_fab2_lib.baseboard_fab2(sch_1):page40_i22:vss(912)" )
			)
			( pin "U5D1.AB31"
				( objectStatus "@baseboard_fab2_lib.baseboard_fab2(sch_1):page40_i22:vss(913)" )
			)
			( pin "U5D1.AB29"
				( objectStatus "@baseboard_fab2_lib.baseboard_fab2(sch_1):page40_i22:vss(914)" )
			)
			( pin "U5D1.AB25"
				( objectStatus "@baseboard_fab2_lib.baseboard_fab2(sch_1):page40_i22:vss(915)" )
			)
			( pin "U5D1.AB23"
				( objectStatus "@baseboard_fab2_lib.baseboard_fab2(sch_1):page40_i22:vss(916)" )
			)
			( pin "U5D1.AB21"
				( objectStatus "@baseboard_fab2_lib.baseboard_fab2(sch_1):page40_i22:vss(917)" )
			)
			( pin "U5D1.AB11"
				( objectStatus "@baseboard_fab2_lib.baseboard_fab2(sch_1):page40_i22:vss(918)" )
			)
			( pin "U5D1.AB5"
				( objectStatus "@baseboard_fab2_lib.baseboard_fab2(sch_1):page40_i22:vss(919)" )
			)
			( pin "U5D1.AB1"
				( objectStatus "@baseboard_fab2_lib.baseboard_fab2(sch_1):page40_i22:vss(920)" )
			)
			( pin "U5D1.AA82"
				( objectStatus "@baseboard_fab2_lib.baseboard_fab2(sch_1):page40_i22:vss(921)" )
			)
			( pin "U5D1.AA80"
				( objectStatus "@baseboard_fab2_lib.baseboard_fab2(sch_1):page40_i22:vss(922)" )
			)
			( pin "U5D1.AA78"
				( objectStatus "@baseboard_fab2_lib.baseboard_fab2(sch_1):page40_i22:vss(923)" )
			)
			( pin "U5D1.AA76"
				( objectStatus "@baseboard_fab2_lib.baseboard_fab2(sch_1):page40_i22:vss(924)" )
			)
			( pin "U5D1.AA68"
				( objectStatus "@baseboard_fab2_lib.baseboard_fab2(sch_1):page40_i22:vss(925)" )
			)
			( pin "U5D1.AA66"
				( objectStatus "@baseboard_fab2_lib.baseboard_fab2(sch_1):page40_i22:vss(926)" )
			)
			( pin "U5D1.AA64"
				( objectStatus "@baseboard_fab2_lib.baseboard_fab2(sch_1):page40_i22:vss(927)" )
			)
			( pin "U5D1.AA42"
				( objectStatus "@baseboard_fab2_lib.baseboard_fab2(sch_1):page40_i22:vss(928)" )
			)
			( pin "U5D1.AA36"
				( objectStatus "@baseboard_fab2_lib.baseboard_fab2(sch_1):page40_i22:vss(929)" )
			)
			( pin "U5D1.AA30"
				( objectStatus "@baseboard_fab2_lib.baseboard_fab2(sch_1):page40_i22:vss(930)" )
			)
			( pin "U5D1.AA24"
				( objectStatus "@baseboard_fab2_lib.baseboard_fab2(sch_1):page40_i22:vss(931)" )
			)
			( pin "U5D1.AA22"
				( objectStatus "@baseboard_fab2_lib.baseboard_fab2(sch_1):page40_i22:vss(932)" )
			)
			( pin "U5D1.AA18"
				( objectStatus "@baseboard_fab2_lib.baseboard_fab2(sch_1):page40_i22:vss(933)" )
			)
			( pin "U5D1.BG72"
				( objectStatus "@baseboard_fab2_lib.baseboard_fab2(sch_1):page40_i23:vss(614)" )
			)
			( pin "U5D1.BG24"
				( objectStatus "@baseboard_fab2_lib.baseboard_fab2(sch_1):page40_i23:vss(615)" )
			)
			( pin "U5D1.BG22"
				( objectStatus "@baseboard_fab2_lib.baseboard_fab2(sch_1):page40_i23:vss(616)" )
			)
			( pin "U5D1.BG10"
				( objectStatus "@baseboard_fab2_lib.baseboard_fab2(sch_1):page40_i23:vss(617)" )
			)
			( pin "U5D1.BG8"
				( objectStatus "@baseboard_fab2_lib.baseboard_fab2(sch_1):page40_i23:vss(618)" )
			)
			( pin "U5D1.BG6"
				( objectStatus "@baseboard_fab2_lib.baseboard_fab2(sch_1):page40_i23:vss(619)" )
			)
			( pin "U5D1.BF71"
				( objectStatus "@baseboard_fab2_lib.baseboard_fab2(sch_1):page40_i23:vss(620)" )
			)
			( pin "U5D1.BF69"
				( objectStatus "@baseboard_fab2_lib.baseboard_fab2(sch_1):page40_i23:vss(621)" )
			)
			( pin "U5D1.BF67"
				( objectStatus "@baseboard_fab2_lib.baseboard_fab2(sch_1):page40_i23:vss(622)" )
			)
			( pin "U5D1.BF65"
				( objectStatus "@baseboard_fab2_lib.baseboard_fab2(sch_1):page40_i23:vss(623)" )
			)
			( pin "U5D1.BF63"
				( objectStatus "@baseboard_fab2_lib.baseboard_fab2(sch_1):page40_i23:vss(624)" )
			)
			( pin "U5D1.BF25"
				( objectStatus "@baseboard_fab2_lib.baseboard_fab2(sch_1):page40_i23:vss(625)" )
			)
			( pin "U5D1.BF19"
				( objectStatus "@baseboard_fab2_lib.baseboard_fab2(sch_1):page40_i23:vss(626)" )
			)
			( pin "U5D1.BF17"
				( objectStatus "@baseboard_fab2_lib.baseboard_fab2(sch_1):page40_i23:vss(627)" )
			)
			( pin "U5D1.BF15"
				( objectStatus "@baseboard_fab2_lib.baseboard_fab2(sch_1):page40_i23:vss(628)" )
			)
			( pin "U5D1.BF9"
				( objectStatus "@baseboard_fab2_lib.baseboard_fab2(sch_1):page40_i23:vss(629)" )
			)
			( pin "U5D1.BE70"
				( objectStatus "@baseboard_fab2_lib.baseboard_fab2(sch_1):page40_i23:vss(630)" )
			)
			( pin "U5D1.BE68"
				( objectStatus "@baseboard_fab2_lib.baseboard_fab2(sch_1):page40_i23:vss(631)" )
			)
			( pin "U5D1.BE66"
				( objectStatus "@baseboard_fab2_lib.baseboard_fab2(sch_1):page40_i23:vss(632)" )
			)
			( pin "U5D1.BE64"
				( objectStatus "@baseboard_fab2_lib.baseboard_fab2(sch_1):page40_i23:vss(633)" )
			)
			( pin "U5D1.BE26"
				( objectStatus "@baseboard_fab2_lib.baseboard_fab2(sch_1):page40_i23:vss(634)" )
			)
			( pin "U5D1.BE10"
				( objectStatus "@baseboard_fab2_lib.baseboard_fab2(sch_1):page40_i23:vss(635)" )
			)
			( pin "U5D1.BE8"
				( objectStatus "@baseboard_fab2_lib.baseboard_fab2(sch_1):page40_i23:vss(636)" )
			)
			( pin "U5D1.BE6"
				( objectStatus "@baseboard_fab2_lib.baseboard_fab2(sch_1):page40_i23:vss(637)" )
			)
			( pin "U5D1.BE4"
				( objectStatus "@baseboard_fab2_lib.baseboard_fab2(sch_1):page40_i23:vss(638)" )
			)
			( pin "U5D1.BD71"
				( objectStatus "@baseboard_fab2_lib.baseboard_fab2(sch_1):page40_i23:vss(639)" )
			)
			( pin "U5D1.BD63"
				( objectStatus "@baseboard_fab2_lib.baseboard_fab2(sch_1):page40_i23:vss(640)" )
			)
			( pin "U5D1.BD27"
				( objectStatus "@baseboard_fab2_lib.baseboard_fab2(sch_1):page40_i23:vss(641)" )
			)
			( pin "U5D1.BD21"
				( objectStatus "@baseboard_fab2_lib.baseboard_fab2(sch_1):page40_i23:vss(642)" )
			)
			( pin "U5D1.BD15"
				( objectStatus "@baseboard_fab2_lib.baseboard_fab2(sch_1):page40_i23:vss(643)" )
			)
			( pin "U5D1.BD11"
				( objectStatus "@baseboard_fab2_lib.baseboard_fab2(sch_1):page40_i23:vss(644)" )
			)
			( pin "U5D1.BD5"
				( objectStatus "@baseboard_fab2_lib.baseboard_fab2(sch_1):page40_i23:vss(645)" )
			)
			( pin "U5D1.BC82"
				( objectStatus "@baseboard_fab2_lib.baseboard_fab2(sch_1):page40_i23:vss(646)" )
			)
			( pin "U5D1.BC80"
				( objectStatus "@baseboard_fab2_lib.baseboard_fab2(sch_1):page40_i23:vss(647)" )
			)
			( pin "U5D1.BC78"
				( objectStatus "@baseboard_fab2_lib.baseboard_fab2(sch_1):page40_i23:vss(648)" )
			)
			( pin "U5D1.BC76"
				( objectStatus "@baseboard_fab2_lib.baseboard_fab2(sch_1):page40_i23:vss(649)" )
			)
			( pin "U5D1.BC74"
				( objectStatus "@baseboard_fab2_lib.baseboard_fab2(sch_1):page40_i23:vss(650)" )
			)
			( pin "U5D1.BC72"
				( objectStatus "@baseboard_fab2_lib.baseboard_fab2(sch_1):page40_i23:vss(651)" )
			)
			( pin "U5D1.BC70"
				( objectStatus "@baseboard_fab2_lib.baseboard_fab2(sch_1):page40_i23:vss(652)" )
			)
			( pin "U5D1.BC16"
				( objectStatus "@baseboard_fab2_lib.baseboard_fab2(sch_1):page40_i23:vss(653)" )
			)
			( pin "U5D1.BC12"
				( objectStatus "@baseboard_fab2_lib.baseboard_fab2(sch_1):page40_i23:vss(654)" )
			)
			( pin "U5D1.BC8"
				( objectStatus "@baseboard_fab2_lib.baseboard_fab2(sch_1):page40_i23:vss(655)" )
			)
			( pin "U5D1.BC4"
				( objectStatus "@baseboard_fab2_lib.baseboard_fab2(sch_1):page40_i23:vss(656)" )
			)
			( pin "U5D1.BB83"
				( objectStatus "@baseboard_fab2_lib.baseboard_fab2(sch_1):page40_i23:vss(657)" )
			)
			( pin "U5D1.BB81"
				( objectStatus "@baseboard_fab2_lib.baseboard_fab2(sch_1):page40_i23:vss(658)" )
			)
			( pin "U5D1.BB79"
				( objectStatus "@baseboard_fab2_lib.baseboard_fab2(sch_1):page40_i23:vss(659)" )
			)
			( pin "U5D1.BB77"
				( objectStatus "@baseboard_fab2_lib.baseboard_fab2(sch_1):page40_i23:vss(660)" )
			)
			( pin "U5D1.BB75"
				( objectStatus "@baseboard_fab2_lib.baseboard_fab2(sch_1):page40_i23:vss(661)" )
			)
			( pin "U5D1.BB73"
				( objectStatus "@baseboard_fab2_lib.baseboard_fab2(sch_1):page40_i23:vss(662)" )
			)
			( pin "U5D1.BB69"
				( objectStatus "@baseboard_fab2_lib.baseboard_fab2(sch_1):page40_i23:vss(663)" )
			)
			( pin "U5D1.BB63"
				( objectStatus "@baseboard_fab2_lib.baseboard_fab2(sch_1):page40_i23:vss(664)" )
			)
			( pin "U5D1.BB23"
				( objectStatus "@baseboard_fab2_lib.baseboard_fab2(sch_1):page40_i23:vss(665)" )
			)
			( pin "U5D1.BB19"
				( objectStatus "@baseboard_fab2_lib.baseboard_fab2(sch_1):page40_i23:vss(666)" )
			)
			( pin "U5D1.BA84"
				( objectStatus "@baseboard_fab2_lib.baseboard_fab2(sch_1):page40_i23:vss(667)" )
			)
			( pin "U5D1.BA80"
				( objectStatus "@baseboard_fab2_lib.baseboard_fab2(sch_1):page40_i23:vss(668)" )
			)
			( pin "U5D1.BA74"
				( objectStatus "@baseboard_fab2_lib.baseboard_fab2(sch_1):page40_i23:vss(669)" )
			)
			( pin "U5D1.BA68"
				( objectStatus "@baseboard_fab2_lib.baseboard_fab2(sch_1):page40_i23:vss(670)" )
			)
			( pin "U5D1.BA62"
				( objectStatus "@baseboard_fab2_lib.baseboard_fab2(sch_1):page40_i23:vss(671)" )
			)
			( pin "U5D1.BA12"
				( objectStatus "@baseboard_fab2_lib.baseboard_fab2(sch_1):page40_i23:vss(672)" )
			)
			( pin "U5D1.BA6"
				( objectStatus "@baseboard_fab2_lib.baseboard_fab2(sch_1):page40_i23:vss(673)" )
			)
			( pin "U5D1.BA2"
				( objectStatus "@baseboard_fab2_lib.baseboard_fab2(sch_1):page40_i23:vss(674)" )
			)
			( pin "U5D1.AY81"
				( objectStatus "@baseboard_fab2_lib.baseboard_fab2(sch_1):page40_i23:vss(675)" )
			)
			( pin "U5D1.AY79"
				( objectStatus "@baseboard_fab2_lib.baseboard_fab2(sch_1):page40_i23:vss(676)" )
			)
			( pin "U5D1.AY63"
				( objectStatus "@baseboard_fab2_lib.baseboard_fab2(sch_1):page40_i23:vss(677)" )
			)
			( pin "U5D1.AY25"
				( objectStatus "@baseboard_fab2_lib.baseboard_fab2(sch_1):page40_i23:vss(678)" )
			)
			( pin "U5D1.AY23"
				( objectStatus "@baseboard_fab2_lib.baseboard_fab2(sch_1):page40_i23:vss(679)" )
			)
			( pin "U5D1.AY21"
				( objectStatus "@baseboard_fab2_lib.baseboard_fab2(sch_1):page40_i23:vss(680)" )
			)
			( pin "U5D1.AY17"
				( objectStatus "@baseboard_fab2_lib.baseboard_fab2(sch_1):page40_i23:vss(681)" )
			)
			( pin "U5D1.AY15"
				( objectStatus "@baseboard_fab2_lib.baseboard_fab2(sch_1):page40_i23:vss(682)" )
			)
			( pin "U5D1.AY5"
				( objectStatus "@baseboard_fab2_lib.baseboard_fab2(sch_1):page40_i23:vss(683)" )
			)
			( pin "U5D1.AW84"
				( objectStatus "@baseboard_fab2_lib.baseboard_fab2(sch_1):page40_i23:vss(684)" )
			)
			( pin "U5D1.AW82"
				( objectStatus "@baseboard_fab2_lib.baseboard_fab2(sch_1):page40_i23:vss(685)" )
			)
			( pin "U5D1.AW78"
				( objectStatus "@baseboard_fab2_lib.baseboard_fab2(sch_1):page40_i23:vss(686)" )
			)
			( pin "U5D1.AW74"
				( objectStatus "@baseboard_fab2_lib.baseboard_fab2(sch_1):page40_i23:vss(687)" )
			)
			( pin "U5D1.AW72"
				( objectStatus "@baseboard_fab2_lib.baseboard_fab2(sch_1):page40_i23:vss(688)" )
			)
			( pin "U5D1.AW70"
				( objectStatus "@baseboard_fab2_lib.baseboard_fab2(sch_1):page40_i23:vss(689)" )
			)
			( pin "U5D1.AW68"
				( objectStatus "@baseboard_fab2_lib.baseboard_fab2(sch_1):page40_i23:vss(690)" )
			)
			( pin "U5D1.AW66"
				( objectStatus "@baseboard_fab2_lib.baseboard_fab2(sch_1):page40_i23:vss(691)" )
			)
			( pin "U5D1.AW62"
				( objectStatus "@baseboard_fab2_lib.baseboard_fab2(sch_1):page40_i23:vss(692)" )
			)
			( pin "U5D1.AW10"
				( objectStatus "@baseboard_fab2_lib.baseboard_fab2(sch_1):page40_i23:vss(693)" )
			)
			( pin "U5D1.AW2"
				( objectStatus "@baseboard_fab2_lib.baseboard_fab2(sch_1):page40_i23:vss(694)" )
			)
			( pin "U5D1.AV83"
				( objectStatus "@baseboard_fab2_lib.baseboard_fab2(sch_1):page40_i23:vss(695)" )
			)
			( pin "U5D1.AV75"
				( objectStatus "@baseboard_fab2_lib.baseboard_fab2(sch_1):page40_i23:vss(696)" )
			)
			( pin "U5D1.AV67"
				( objectStatus "@baseboard_fab2_lib.baseboard_fab2(sch_1):page40_i23:vss(697)" )
			)
			( pin "U5D1.AV65"
				( objectStatus "@baseboard_fab2_lib.baseboard_fab2(sch_1):page40_i23:vss(698)" )
			)
			( pin "U5D1.AV63"
				( objectStatus "@baseboard_fab2_lib.baseboard_fab2(sch_1):page40_i23:vss(699)" )
			)
			( pin "U5D1.AV25"
				( objectStatus "@baseboard_fab2_lib.baseboard_fab2(sch_1):page40_i23:vss(700)" )
			)
			( pin "U5D1.AV23"
				( objectStatus "@baseboard_fab2_lib.baseboard_fab2(sch_1):page40_i23:vss(701)" )
			)
			( pin "U5D1.AV19"
				( objectStatus "@baseboard_fab2_lib.baseboard_fab2(sch_1):page40_i23:vss(702)" )
			)
			( pin "U5D1.AV13"
				( objectStatus "@baseboard_fab2_lib.baseboard_fab2(sch_1):page40_i23:vss(703)" )
			)
			( pin "U5D1.AV11"
				( objectStatus "@baseboard_fab2_lib.baseboard_fab2(sch_1):page40_i23:vss(704)" )
			)
			( pin "U5D1.AV7"
				( objectStatus "@baseboard_fab2_lib.baseboard_fab2(sch_1):page40_i23:vss(705)" )
			)
			( pin "U5D1.AV3"
				( objectStatus "@baseboard_fab2_lib.baseboard_fab2(sch_1):page40_i23:vss(706)" )
			)
			( pin "U5D1.AV1"
				( objectStatus "@baseboard_fab2_lib.baseboard_fab2(sch_1):page40_i23:vss(707)" )
			)
			( pin "U5D1.AU86"
				( objectStatus "@baseboard_fab2_lib.baseboard_fab2(sch_1):page40_i23:vss(708)" )
			)
			( pin "U5D1.AU84"
				( objectStatus "@baseboard_fab2_lib.baseboard_fab2(sch_1):page40_i23:vss(709)" )
			)
			( pin "U5D1.AU80"
				( objectStatus "@baseboard_fab2_lib.baseboard_fab2(sch_1):page40_i23:vss(710)" )
			)
			( pin "U5D1.AU78"
				( objectStatus "@baseboard_fab2_lib.baseboard_fab2(sch_1):page40_i23:vss(711)" )
			)
			( pin "U5D1.AU76"
				( objectStatus "@baseboard_fab2_lib.baseboard_fab2(sch_1):page40_i23:vss(712)" )
			)
			( pin "U5D1.AU74"
				( objectStatus "@baseboard_fab2_lib.baseboard_fab2(sch_1):page40_i23:vss(713)" )
			)
			( pin "U5D1.AU68"
				( objectStatus "@baseboard_fab2_lib.baseboard_fab2(sch_1):page40_i23:vss(714)" )
			)
			( pin "U5D1.AU64"
				( objectStatus "@baseboard_fab2_lib.baseboard_fab2(sch_1):page40_i23:vss(715)" )
			)
			( pin "U5D1.AU62"
				( objectStatus "@baseboard_fab2_lib.baseboard_fab2(sch_1):page40_i23:vss(716)" )
			)
			( pin "U5D1.AU28"
				( objectStatus "@baseboard_fab2_lib.baseboard_fab2(sch_1):page40_i23:vss(717)" )
			)
			( pin "U5D1.AU26"
				( objectStatus "@baseboard_fab2_lib.baseboard_fab2(sch_1):page40_i23:vss(718)" )
			)
			( pin "U5D1.AU6"
				( objectStatus "@baseboard_fab2_lib.baseboard_fab2(sch_1):page40_i23:vss(719)" )
			)
			( pin "U5D1.AU2"
				( objectStatus "@baseboard_fab2_lib.baseboard_fab2(sch_1):page40_i23:vss(720)" )
			)
			( pin "U5D1.AT85"
				( objectStatus "@baseboard_fab2_lib.baseboard_fab2(sch_1):page40_i23:vss(721)" )
			)
			( pin "U5D1.AT83"
				( objectStatus "@baseboard_fab2_lib.baseboard_fab2(sch_1):page40_i23:vss(722)" )
			)
			( pin "U5D1.AT77"
				( objectStatus "@baseboard_fab2_lib.baseboard_fab2(sch_1):page40_i23:vss(723)" )
			)
			( pin "U5D1.AT73"
				( objectStatus "@baseboard_fab2_lib.baseboard_fab2(sch_1):page40_i23:vss(724)" )
			)
			( pin "U5D1.AT69"
				( objectStatus "@baseboard_fab2_lib.baseboard_fab2(sch_1):page40_i23:vss(725)" )
			)
			( pin "U5D1.AT63"
				( objectStatus "@baseboard_fab2_lib.baseboard_fab2(sch_1):page40_i23:vss(726)" )
			)
			( pin "U5D1.AT61"
				( objectStatus "@baseboard_fab2_lib.baseboard_fab2(sch_1):page40_i23:vss(727)" )
			)
			( pin "U5D1.AT27"
				( objectStatus "@baseboard_fab2_lib.baseboard_fab2(sch_1):page40_i23:vss(728)" )
			)
			( pin "U5D1.AT21"
				( objectStatus "@baseboard_fab2_lib.baseboard_fab2(sch_1):page40_i23:vss(729)" )
			)
			( pin "U5D1.AT17"
				( objectStatus "@baseboard_fab2_lib.baseboard_fab2(sch_1):page40_i23:vss(730)" )
			)
			( pin "U5D1.AT15"
				( objectStatus "@baseboard_fab2_lib.baseboard_fab2(sch_1):page40_i23:vss(731)" )
			)
			( pin "U5D1.P63"
				( objectStatus "@baseboard_fab2_lib.baseboard_fab2(sch_1):page40_i23:vss(732)" )
			)
			( pin "U5D1.AC48"
				( objectStatus "@baseboard_fab2_lib.baseboard_fab2(sch_1):page40_i23:vss(733)" )
			)
			( pin "U5D1.AR78"
				( objectStatus "@baseboard_fab2_lib.baseboard_fab2(sch_1):page40_i23:vss(734)" )
			)
			( pin "U5D1.AR72"
				( objectStatus "@baseboard_fab2_lib.baseboard_fab2(sch_1):page40_i23:vss(735)" )
			)
			( pin "U5D1.AR60"
				( objectStatus "@baseboard_fab2_lib.baseboard_fab2(sch_1):page40_i23:vss(736)" )
			)
			( pin "U5D1.AR30"
				( objectStatus "@baseboard_fab2_lib.baseboard_fab2(sch_1):page40_i23:vss(737)" )
			)
			( pin "U5D1.AR24"
				( objectStatus "@baseboard_fab2_lib.baseboard_fab2(sch_1):page40_i23:vss(738)" )
			)
			( pin "U5D1.AR10"
				( objectStatus "@baseboard_fab2_lib.baseboard_fab2(sch_1):page40_i23:vss(739)" )
			)
			( pin "U5D1.AP85"
				( objectStatus "@baseboard_fab2_lib.baseboard_fab2(sch_1):page40_i23:vss(740)" )
			)
			( pin "U5D1.AP83"
				( objectStatus "@baseboard_fab2_lib.baseboard_fab2(sch_1):page40_i23:vss(741)" )
			)
			( pin "U5D1.AP81"
				( objectStatus "@baseboard_fab2_lib.baseboard_fab2(sch_1):page40_i23:vss(742)" )
			)
			( pin "U5D1.AP75"
				( objectStatus "@baseboard_fab2_lib.baseboard_fab2(sch_1):page40_i23:vss(743)" )
			)
			( pin "U5D1.AP73"
				( objectStatus "@baseboard_fab2_lib.baseboard_fab2(sch_1):page40_i23:vss(744)" )
			)
			( pin "U5D1.AP69"
				( objectStatus "@baseboard_fab2_lib.baseboard_fab2(sch_1):page40_i23:vss(745)" )
			)
			( pin "U5D1.AP67"
				( objectStatus "@baseboard_fab2_lib.baseboard_fab2(sch_1):page40_i23:vss(746)" )
			)
			( pin "U5D1.AP65"
				( objectStatus "@baseboard_fab2_lib.baseboard_fab2(sch_1):page40_i23:vss(747)" )
			)
			( pin "U5D1.AP63"
				( objectStatus "@baseboard_fab2_lib.baseboard_fab2(sch_1):page40_i23:vss(748)" )
			)
			( pin "U5D1.AP59"
				( objectStatus "@baseboard_fab2_lib.baseboard_fab2(sch_1):page40_i23:vss(749)" )
			)
			( pin "U5D1.AP31"
				( objectStatus "@baseboard_fab2_lib.baseboard_fab2(sch_1):page40_i23:vss(750)" )
			)
			( pin "U5D1.AP19"
				( objectStatus "@baseboard_fab2_lib.baseboard_fab2(sch_1):page40_i23:vss(751)" )
			)
			( pin "U5D1.AP13"
				( objectStatus "@baseboard_fab2_lib.baseboard_fab2(sch_1):page40_i23:vss(752)" )
			)
			( pin "U5D1.AP9"
				( objectStatus "@baseboard_fab2_lib.baseboard_fab2(sch_1):page40_i23:vss(753)" )
			)
			( pin "U5D1.AP5"
				( objectStatus "@baseboard_fab2_lib.baseboard_fab2(sch_1):page40_i23:vss(754)" )
			)
			( pin "U5D1.AN78"
				( objectStatus "@baseboard_fab2_lib.baseboard_fab2(sch_1):page40_i23:vss(755)" )
			)
			( pin "U5D1.AN58"
				( objectStatus "@baseboard_fab2_lib.baseboard_fab2(sch_1):page40_i23:vss(756)" )
			)
			( pin "U5D1.AN28"
				( objectStatus "@baseboard_fab2_lib.baseboard_fab2(sch_1):page40_i23:vss(757)" )
			)
			( pin "U5D1.AN6"
				( objectStatus "@baseboard_fab2_lib.baseboard_fab2(sch_1):page40_i23:vss(758)" )
			)
			( pin "U5D1.AN2"
				( objectStatus "@baseboard_fab2_lib.baseboard_fab2(sch_1):page40_i23:vss(759)" )
			)
			( pin "U5D1.AM83"
				( objectStatus "@baseboard_fab2_lib.baseboard_fab2(sch_1):page40_i23:vss(760)" )
			)
			( pin "U5D1.AM79"
				( objectStatus "@baseboard_fab2_lib.baseboard_fab2(sch_1):page40_i23:vss(761)" )
			)
			( pin "U5D1.AM73"
				( objectStatus "@baseboard_fab2_lib.baseboard_fab2(sch_1):page40_i23:vss(762)" )
			)
			( pin "U5D1.AM69"
				( objectStatus "@baseboard_fab2_lib.baseboard_fab2(sch_1):page40_i23:vss(763)" )
			)
			( pin "U5D1.AM63"
				( objectStatus "@baseboard_fab2_lib.baseboard_fab2(sch_1):page40_i23:vss(764)" )
			)
			( pin "U5D1.AM57"
				( objectStatus "@baseboard_fab2_lib.baseboard_fab2(sch_1):page40_i23:vss(765)" )
			)
			( pin "U5D1.AM31"
				( objectStatus "@baseboard_fab2_lib.baseboard_fab2(sch_1):page40_i23:vss(766)" )
			)
			( pin "U5D1.AC50"
				( objectStatus "@baseboard_fab2_lib.baseboard_fab2(sch_1):page40_i23:vss(767)" )
			)
			( pin "U5D1.AM1"
				( objectStatus "@baseboard_fab2_lib.baseboard_fab2(sch_1):page40_i23:vss(768)" )
			)
			( pin "U5D1.AL86"
				( objectStatus "@baseboard_fab2_lib.baseboard_fab2(sch_1):page40_i23:vss(769)" )
			)
			( pin "U5D1.AL82"
				( objectStatus "@baseboard_fab2_lib.baseboard_fab2(sch_1):page40_i23:vss(770)" )
			)
			( pin "U5D1.AL80"
				( objectStatus "@baseboard_fab2_lib.baseboard_fab2(sch_1):page40_i23:vss(771)" )
			)
			( pin "U5D1.AL78"
				( objectStatus "@baseboard_fab2_lib.baseboard_fab2(sch_1):page40_i23:vss(772)" )
			)
			( pin "U5D1.AL76"
				( objectStatus "@baseboard_fab2_lib.baseboard_fab2(sch_1):page40_i23:vss(773)" )
			)
			( pin "U5D1.P49"
				( objectStatus "@baseboard_fab2_lib.baseboard_fab2(sch_1):page41_i283:vss(454)" )
			)
			( pin "U5D1.CJ12"
				( objectStatus "@baseboard_fab2_lib.baseboard_fab2(sch_1):page41_i283:vss(455)" )
			)
			( pin "U5D1.CJ10"
				( objectStatus "@baseboard_fab2_lib.baseboard_fab2(sch_1):page41_i283:vss(456)" )
			)
			( pin "U5D1.CJ8"
				( objectStatus "@baseboard_fab2_lib.baseboard_fab2(sch_1):page41_i283:vss(457)" )
			)
			( pin "U5D1.CJ6"
				( objectStatus "@baseboard_fab2_lib.baseboard_fab2(sch_1):page41_i283:vss(458)" )
			)
			( pin "U5D1.CJ2"
				( objectStatus "@baseboard_fab2_lib.baseboard_fab2(sch_1):page41_i283:vss(459)" )
			)
			( pin "U5D1.CH83"
				( objectStatus "@baseboard_fab2_lib.baseboard_fab2(sch_1):page41_i283:vss(460)" )
			)
			( pin "U5D1.CH81"
				( objectStatus "@baseboard_fab2_lib.baseboard_fab2(sch_1):page41_i283:vss(461)" )
			)
			( pin "U5D1.CH79"
				( objectStatus "@baseboard_fab2_lib.baseboard_fab2(sch_1):page41_i283:vss(462)" )
			)
			( pin "U5D1.CH73"
				( objectStatus "@baseboard_fab2_lib.baseboard_fab2(sch_1):page41_i283:vss(463)" )
			)
			( pin "U5D1.CH67"
				( objectStatus "@baseboard_fab2_lib.baseboard_fab2(sch_1):page41_i283:vss(464)" )
			)
			( pin "U5D1.CH63"
				( objectStatus "@baseboard_fab2_lib.baseboard_fab2(sch_1):page41_i283:vss(465)" )
			)
			( pin "U5D1.CH19"
				( objectStatus "@baseboard_fab2_lib.baseboard_fab2(sch_1):page41_i283:vss(466)" )
			)
			( pin "U5D1.CH15"
				( objectStatus "@baseboard_fab2_lib.baseboard_fab2(sch_1):page41_i283:vss(467)" )
			)
			( pin "U5D1.CH3"
				( objectStatus "@baseboard_fab2_lib.baseboard_fab2(sch_1):page41_i283:vss(468)" )
			)
			( pin "U5D1.CH1"
				( objectStatus "@baseboard_fab2_lib.baseboard_fab2(sch_1):page41_i283:vss(469)" )
			)
			( pin "U5D1.CG80"
				( objectStatus "@baseboard_fab2_lib.baseboard_fab2(sch_1):page41_i283:vss(470)" )
			)
			( pin "U5D1.CG72"
				( objectStatus "@baseboard_fab2_lib.baseboard_fab2(sch_1):page41_i283:vss(471)" )
			)
			( pin "U5D1.CG68"
				( objectStatus "@baseboard_fab2_lib.baseboard_fab2(sch_1):page41_i283:vss(472)" )
			)
			( pin "U5D1.CG62"
				( objectStatus "@baseboard_fab2_lib.baseboard_fab2(sch_1):page41_i283:vss(473)" )
			)
			( pin "U5D1.CG22"
				( objectStatus "@baseboard_fab2_lib.baseboard_fab2(sch_1):page41_i283:vss(474)" )
			)
			( pin "U5D1.CG18"
				( objectStatus "@baseboard_fab2_lib.baseboard_fab2(sch_1):page41_i283:vss(475)" )
			)
			( pin "U5D1.P51"
				( objectStatus "@baseboard_fab2_lib.baseboard_fab2(sch_1):page41_i283:vss(476)" )
			)
			( pin "U5D1.CF83"
				( objectStatus "@baseboard_fab2_lib.baseboard_fab2(sch_1):page41_i283:vss(477)" )
			)
			( pin "U5D1.CF77"
				( objectStatus "@baseboard_fab2_lib.baseboard_fab2(sch_1):page41_i283:vss(478)" )
			)
			( pin "U5D1.CF71"
				( objectStatus "@baseboard_fab2_lib.baseboard_fab2(sch_1):page41_i283:vss(479)" )
			)
			( pin "U5D1.CF69"
				( objectStatus "@baseboard_fab2_lib.baseboard_fab2(sch_1):page41_i283:vss(480)" )
			)
			( pin "U5D1.CF63"
				( objectStatus "@baseboard_fab2_lib.baseboard_fab2(sch_1):page41_i283:vss(481)" )
			)
			( pin "U5D1.CF9"
				( objectStatus "@baseboard_fab2_lib.baseboard_fab2(sch_1):page41_i283:vss(482)" )
			)
			( pin "U5D1.P53"
				( objectStatus "@baseboard_fab2_lib.baseboard_fab2(sch_1):page41_i283:vss(483)" )
			)
			( pin "U5D1.CE82"
				( objectStatus "@baseboard_fab2_lib.baseboard_fab2(sch_1):page41_i283:vss(484)" )
			)
			( pin "U5D1.CE70"
				( objectStatus "@baseboard_fab2_lib.baseboard_fab2(sch_1):page41_i283:vss(485)" )
			)
			( pin "U5D1.CE62"
				( objectStatus "@baseboard_fab2_lib.baseboard_fab2(sch_1):page41_i283:vss(486)" )
			)
			( pin "U5D1.CE26"
				( objectStatus "@baseboard_fab2_lib.baseboard_fab2(sch_1):page41_i283:vss(487)" )
			)
			( pin "U5D1.CE20"
				( objectStatus "@baseboard_fab2_lib.baseboard_fab2(sch_1):page41_i283:vss(488)" )
			)
			( pin "U5D1.CE14"
				( objectStatus "@baseboard_fab2_lib.baseboard_fab2(sch_1):page41_i283:vss(489)" )
			)
			( pin "U5D1.CE10"
				( objectStatus "@baseboard_fab2_lib.baseboard_fab2(sch_1):page41_i283:vss(490)" )
			)
			( pin "U5D1.CD81"
				( objectStatus "@baseboard_fab2_lib.baseboard_fab2(sch_1):page41_i283:vss(491)" )
			)
			( pin "U5D1.CD79"
				( objectStatus "@baseboard_fab2_lib.baseboard_fab2(sch_1):page41_i283:vss(492)" )
			)
			( pin "U5D1.CD77"
				( objectStatus "@baseboard_fab2_lib.baseboard_fab2(sch_1):page41_i283:vss(493)" )
			)
			( pin "U5D1.CD75"
				( objectStatus "@baseboard_fab2_lib.baseboard_fab2(sch_1):page41_i283:vss(494)" )
			)
			( pin "U5D1.CD73"
				( objectStatus "@baseboard_fab2_lib.baseboard_fab2(sch_1):page41_i283:vss(495)" )
			)
			( pin "U5D1.CD63"
				( objectStatus "@baseboard_fab2_lib.baseboard_fab2(sch_1):page41_i283:vss(496)" )
			)
			( pin "U5D1.CD13"
				( objectStatus "@baseboard_fab2_lib.baseboard_fab2(sch_1):page41_i283:vss(497)" )
			)
			( pin "U5D1.CD5"
				( objectStatus "@baseboard_fab2_lib.baseboard_fab2(sch_1):page41_i283:vss(498)" )
			)
			( pin "U5D1.CC82"
				( objectStatus "@baseboard_fab2_lib.baseboard_fab2(sch_1):page41_i283:vss(499)" )
			)
			( pin "U5D1.CC80"
				( objectStatus "@baseboard_fab2_lib.baseboard_fab2(sch_1):page41_i283:vss(500)" )
			)
			( pin "U5D1.CC78"
				( objectStatus "@baseboard_fab2_lib.baseboard_fab2(sch_1):page41_i283:vss(501)" )
			)
			( pin "U5D1.CC76"
				( objectStatus "@baseboard_fab2_lib.baseboard_fab2(sch_1):page41_i283:vss(502)" )
			)
			( pin "U5D1.CC74"
				( objectStatus "@baseboard_fab2_lib.baseboard_fab2(sch_1):page41_i283:vss(503)" )
			)
			( pin "U5D1.CC72"
				( objectStatus "@baseboard_fab2_lib.baseboard_fab2(sch_1):page41_i283:vss(504)" )
			)
			( pin "U5D1.CC64"
				( objectStatus "@baseboard_fab2_lib.baseboard_fab2(sch_1):page41_i283:vss(505)" )
			)
			( pin "U5D1.CC24"
				( objectStatus "@baseboard_fab2_lib.baseboard_fab2(sch_1):page41_i283:vss(506)" )
			)
			( pin "U5D1.CC18"
				( objectStatus "@baseboard_fab2_lib.baseboard_fab2(sch_1):page41_i283:vss(507)" )
			)
			( pin "U5D1.CC16"
				( objectStatus "@baseboard_fab2_lib.baseboard_fab2(sch_1):page41_i283:vss(508)" )
			)
			( pin "U5D1.CC4"
				( objectStatus "@baseboard_fab2_lib.baseboard_fab2(sch_1):page41_i283:vss(509)" )
			)
			( pin "U5D1.CB71"
				( objectStatus "@baseboard_fab2_lib.baseboard_fab2(sch_1):page41_i283:vss(510)" )
			)
			( pin "U5D1.CB63"
				( objectStatus "@baseboard_fab2_lib.baseboard_fab2(sch_1):page41_i283:vss(511)" )
			)
			( pin "U5D1.CB27"
				( objectStatus "@baseboard_fab2_lib.baseboard_fab2(sch_1):page41_i283:vss(512)" )
			)
			( pin "U5D1.CB9"
				( objectStatus "@baseboard_fab2_lib.baseboard_fab2(sch_1):page41_i283:vss(513)" )
			)
			( pin "U5D1.CB7"
				( objectStatus "@baseboard_fab2_lib.baseboard_fab2(sch_1):page41_i283:vss(514)" )
			)
			( pin "U5D1.CA70"
				( objectStatus "@baseboard_fab2_lib.baseboard_fab2(sch_1):page41_i283:vss(515)" )
			)
			( pin "U5D1.CA68"
				( objectStatus "@baseboard_fab2_lib.baseboard_fab2(sch_1):page41_i283:vss(516)" )
			)
			( pin "U5D1.CA66"
				( objectStatus "@baseboard_fab2_lib.baseboard_fab2(sch_1):page41_i283:vss(517)" )
			)
			( pin "U5D1.CA64"
				( objectStatus "@baseboard_fab2_lib.baseboard_fab2(sch_1):page41_i283:vss(518)" )
			)
			( pin "U5D1.CA26"
				( objectStatus "@baseboard_fab2_lib.baseboard_fab2(sch_1):page41_i283:vss(519)" )
			)
			( pin "U5D1.CA18"
				( objectStatus "@baseboard_fab2_lib.baseboard_fab2(sch_1):page41_i283:vss(520)" )
			)
			( pin "U5D1.CA14"
				( objectStatus "@baseboard_fab2_lib.baseboard_fab2(sch_1):page41_i283:vss(521)" )
			)
			( pin "U5D1.CA10"
				( objectStatus "@baseboard_fab2_lib.baseboard_fab2(sch_1):page41_i283:vss(522)" )
			)
			( pin "U5D1.CA8"
				( objectStatus "@baseboard_fab2_lib.baseboard_fab2(sch_1):page41_i283:vss(523)" )
			)
			( pin "U5D1.CA6"
				( objectStatus "@baseboard_fab2_lib.baseboard_fab2(sch_1):page41_i283:vss(524)" )
			)
			( pin "U5D1.CA2"
				( objectStatus "@baseboard_fab2_lib.baseboard_fab2(sch_1):page41_i283:vss(525)" )
			)
			( pin "U5D1.BY71"
				( objectStatus "@baseboard_fab2_lib.baseboard_fab2(sch_1):page41_i283:vss(526)" )
			)
			( pin "U5D1.BY69"
				( objectStatus "@baseboard_fab2_lib.baseboard_fab2(sch_1):page41_i283:vss(527)" )
			)
			( pin "U5D1.BY67"
				( objectStatus "@baseboard_fab2_lib.baseboard_fab2(sch_1):page41_i283:vss(528)" )
			)
			( pin "U5D1.BY65"
				( objectStatus "@baseboard_fab2_lib.baseboard_fab2(sch_1):page41_i283:vss(529)" )
			)
			( pin "U5D1.BY63"
				( objectStatus "@baseboard_fab2_lib.baseboard_fab2(sch_1):page41_i283:vss(530)" )
			)
			( pin "U5D1.BY23"
				( objectStatus "@baseboard_fab2_lib.baseboard_fab2(sch_1):page41_i283:vss(531)" )
			)
			( pin "U5D1.BY13"
				( objectStatus "@baseboard_fab2_lib.baseboard_fab2(sch_1):page41_i283:vss(532)" )
			)
			( pin "U5D1.BY11"
				( objectStatus "@baseboard_fab2_lib.baseboard_fab2(sch_1):page41_i283:vss(533)" )
			)
			( pin "U5D1.BW82"
				( objectStatus "@baseboard_fab2_lib.baseboard_fab2(sch_1):page41_i283:vss(534)" )
			)
			( pin "U5D1.BW80"
				( objectStatus "@baseboard_fab2_lib.baseboard_fab2(sch_1):page41_i283:vss(535)" )
			)
			( pin "U5D1.BW78"
				( objectStatus "@baseboard_fab2_lib.baseboard_fab2(sch_1):page41_i283:vss(536)" )
			)
			( pin "U5D1.BW76"
				( objectStatus "@baseboard_fab2_lib.baseboard_fab2(sch_1):page41_i283:vss(537)" )
			)
			( pin "U5D1.BW74"
				( objectStatus "@baseboard_fab2_lib.baseboard_fab2(sch_1):page41_i283:vss(538)" )
			)
			( pin "U5D1.BW72"
				( objectStatus "@baseboard_fab2_lib.baseboard_fab2(sch_1):page41_i283:vss(539)" )
			)
			( pin "U5D1.BW26"
				( objectStatus "@baseboard_fab2_lib.baseboard_fab2(sch_1):page41_i283:vss(540)" )
			)
			( pin "U5D1.BW18"
				( objectStatus "@baseboard_fab2_lib.baseboard_fab2(sch_1):page41_i283:vss(541)" )
			)
			( pin "U5D1.BW16"
				( objectStatus "@baseboard_fab2_lib.baseboard_fab2(sch_1):page41_i283:vss(542)" )
			)
			( pin "U5D1.BW14"
				( objectStatus "@baseboard_fab2_lib.baseboard_fab2(sch_1):page41_i283:vss(543)" )
			)
			( pin "U5D1.BW12"
				( objectStatus "@baseboard_fab2_lib.baseboard_fab2(sch_1):page41_i283:vss(544)" )
			)
			( pin "U5D1.P55"
				( objectStatus "@baseboard_fab2_lib.baseboard_fab2(sch_1):page41_i283:vss(545)" )
			)
			( pin "U5D1.BW6"
				( objectStatus "@baseboard_fab2_lib.baseboard_fab2(sch_1):page41_i283:vss(546)" )
			)
			( pin "U5D1.BV25"
				( objectStatus "@baseboard_fab2_lib.baseboard_fab2(sch_1):page41_i283:vss(547)" )
			)
			( pin "U5D1.BV17"
				( objectStatus "@baseboard_fab2_lib.baseboard_fab2(sch_1):page41_i283:vss(548)" )
			)
			( pin "U5D1.BU10"
				( objectStatus "@baseboard_fab2_lib.baseboard_fab2(sch_1):page41_i283:vss(549)" )
			)
			( pin "U5D1.BV5"
				( objectStatus "@baseboard_fab2_lib.baseboard_fab2(sch_1):page41_i283:vss(550)" )
			)
			( pin "U5D1.BU8"
				( objectStatus "@baseboard_fab2_lib.baseboard_fab2(sch_1):page41_i283:vss(551)" )
			)
			( pin "U5D1.BT25"
				( objectStatus "@baseboard_fab2_lib.baseboard_fab2(sch_1):page41_i283:vss(552)" )
			)
			( pin "U5D1.BT23"
				( objectStatus "@baseboard_fab2_lib.baseboard_fab2(sch_1):page41_i283:vss(553)" )
			)
			( pin "U5D1.BT21"
				( objectStatus "@baseboard_fab2_lib.baseboard_fab2(sch_1):page41_i283:vss(554)" )
			)
			( pin "U5D1.BT5"
				( objectStatus "@baseboard_fab2_lib.baseboard_fab2(sch_1):page41_i283:vss(555)" )
			)
			( pin "U5D1.BT3"
				( objectStatus "@baseboard_fab2_lib.baseboard_fab2(sch_1):page41_i283:vss(556)" )
			)
			( pin "U5D1.BR82"
				( objectStatus "@baseboard_fab2_lib.baseboard_fab2(sch_1):page41_i283:vss(557)" )
			)
			( pin "U5D1.BR80"
				( objectStatus "@baseboard_fab2_lib.baseboard_fab2(sch_1):page41_i283:vss(558)" )
			)
			( pin "U5D1.BR78"
				( objectStatus "@baseboard_fab2_lib.baseboard_fab2(sch_1):page41_i283:vss(559)" )
			)
			( pin "U5D1.BR76"
				( objectStatus "@baseboard_fab2_lib.baseboard_fab2(sch_1):page41_i283:vss(560)" )
			)
			( pin "U5D1.BR74"
				( objectStatus "@baseboard_fab2_lib.baseboard_fab2(sch_1):page41_i283:vss(561)" )
			)
			( pin "U5D1.BR72"
				( objectStatus "@baseboard_fab2_lib.baseboard_fab2(sch_1):page41_i283:vss(562)" )
			)
			( pin "U5D1.BR70"
				( objectStatus "@baseboard_fab2_lib.baseboard_fab2(sch_1):page41_i283:vss(563)" )
			)
			( pin "U5D1.BR68"
				( objectStatus "@baseboard_fab2_lib.baseboard_fab2(sch_1):page41_i283:vss(564)" )
			)
			( pin "U5D1.BR66"
				( objectStatus "@baseboard_fab2_lib.baseboard_fab2(sch_1):page41_i283:vss(565)" )
			)
			( pin "U5D1.BR64"
				( objectStatus "@baseboard_fab2_lib.baseboard_fab2(sch_1):page41_i283:vss(566)" )
			)
			( pin "U5D1.P57"
				( objectStatus "@baseboard_fab2_lib.baseboard_fab2(sch_1):page41_i283:vss(567)" )
			)
			( pin "U5D1.BR16"
				( objectStatus "@baseboard_fab2_lib.baseboard_fab2(sch_1):page41_i283:vss(568)" )
			)
			( pin "U5D1.BR10"
				( objectStatus "@baseboard_fab2_lib.baseboard_fab2(sch_1):page41_i283:vss(569)" )
			)
			( pin "U5D1.BR6"
				( objectStatus "@baseboard_fab2_lib.baseboard_fab2(sch_1):page41_i283:vss(570)" )
			)
			( pin "U5D1.BP27"
				( objectStatus "@baseboard_fab2_lib.baseboard_fab2(sch_1):page41_i283:vss(571)" )
			)
			( pin "U5D1.BP3"
				( objectStatus "@baseboard_fab2_lib.baseboard_fab2(sch_1):page41_i283:vss(572)" )
			)
			( pin "U5D1.BN26"
				( objectStatus "@baseboard_fab2_lib.baseboard_fab2(sch_1):page41_i283:vss(573)" )
			)
			( pin "U5D1.BN20"
				( objectStatus "@baseboard_fab2_lib.baseboard_fab2(sch_1):page41_i283:vss(574)" )
			)
			( pin "U5D1.BN10"
				( objectStatus "@baseboard_fab2_lib.baseboard_fab2(sch_1):page41_i283:vss(575)" )
			)
			( pin "U5D1.BN6"
				( objectStatus "@baseboard_fab2_lib.baseboard_fab2(sch_1):page41_i283:vss(576)" )
			)
			( pin "U5D1.BM25"
				( objectStatus "@baseboard_fab2_lib.baseboard_fab2(sch_1):page41_i283:vss(577)" )
			)
			( pin "U5D1.P59"
				( objectStatus "@baseboard_fab2_lib.baseboard_fab2(sch_1):page41_i283:vss(578)" )
			)
			( pin "U5D1.BM15"
				( objectStatus "@baseboard_fab2_lib.baseboard_fab2(sch_1):page41_i283:vss(579)" )
			)
			( pin "U5D1.BM13"
				( objectStatus "@baseboard_fab2_lib.baseboard_fab2(sch_1):page41_i283:vss(580)" )
			)
			( pin "U5D1.BM9"
				( objectStatus "@baseboard_fab2_lib.baseboard_fab2(sch_1):page41_i283:vss(581)" )
			)
			( pin "U5D1.BL82"
				( objectStatus "@baseboard_fab2_lib.baseboard_fab2(sch_1):page41_i283:vss(582)" )
			)
			( pin "U5D1.BL80"
				( objectStatus "@baseboard_fab2_lib.baseboard_fab2(sch_1):page41_i283:vss(583)" )
			)
			( pin "U5D1.BL78"
				( objectStatus "@baseboard_fab2_lib.baseboard_fab2(sch_1):page41_i283:vss(584)" )
			)
			( pin "U5D1.BL76"
				( objectStatus "@baseboard_fab2_lib.baseboard_fab2(sch_1):page41_i283:vss(585)" )
			)
			( pin "U5D1.BL74"
				( objectStatus "@baseboard_fab2_lib.baseboard_fab2(sch_1):page41_i283:vss(586)" )
			)
			( pin "U5D1.BL72"
				( objectStatus "@baseboard_fab2_lib.baseboard_fab2(sch_1):page41_i283:vss(587)" )
			)
			( pin "U5D1.BL70"
				( objectStatus "@baseboard_fab2_lib.baseboard_fab2(sch_1):page41_i283:vss(588)" )
			)
			( pin "U5D1.BL68"
				( objectStatus "@baseboard_fab2_lib.baseboard_fab2(sch_1):page41_i283:vss(589)" )
			)
			( pin "U5D1.BL66"
				( objectStatus "@baseboard_fab2_lib.baseboard_fab2(sch_1):page41_i283:vss(590)" )
			)
			( pin "U5D1.BL64"
				( objectStatus "@baseboard_fab2_lib.baseboard_fab2(sch_1):page41_i283:vss(591)" )
			)
			( pin "U5D1.BL24"
				( objectStatus "@baseboard_fab2_lib.baseboard_fab2(sch_1):page41_i283:vss(592)" )
			)
			( pin "U5D1.BL22"
				( objectStatus "@baseboard_fab2_lib.baseboard_fab2(sch_1):page41_i283:vss(593)" )
			)
			( pin "U5D1.P61"
				( objectStatus "@baseboard_fab2_lib.baseboard_fab2(sch_1):page41_i283:vss(594)" )
			)
			( pin "U5D1.BL12"
				( objectStatus "@baseboard_fab2_lib.baseboard_fab2(sch_1):page41_i283:vss(595)" )
			)
			( pin "U5D1.BL10"
				( objectStatus "@baseboard_fab2_lib.baseboard_fab2(sch_1):page41_i283:vss(596)" )
			)
			( pin "U5D1.BL6"
				( objectStatus "@baseboard_fab2_lib.baseboard_fab2(sch_1):page41_i283:vss(597)" )
			)
			( pin "U5D1.BK19"
				( objectStatus "@baseboard_fab2_lib.baseboard_fab2(sch_1):page41_i283:vss(598)" )
			)
			( pin "U5D1.BK11"
				( objectStatus "@baseboard_fab2_lib.baseboard_fab2(sch_1):page41_i283:vss(599)" )
			)
			( pin "U5D1.BK7"
				( objectStatus "@baseboard_fab2_lib.baseboard_fab2(sch_1):page41_i283:vss(600)" )
			)
			( pin "U5D1.BK3"
				( objectStatus "@baseboard_fab2_lib.baseboard_fab2(sch_1):page41_i283:vss(601)" )
			)
			( pin "U5D1.BJ6"
				( objectStatus "@baseboard_fab2_lib.baseboard_fab2(sch_1):page41_i283:vss(602)" )
			)
			( pin "U5D1.BJ4"
				( objectStatus "@baseboard_fab2_lib.baseboard_fab2(sch_1):page41_i283:vss(603)" )
			)
			( pin "U5D1.BH21"
				( objectStatus "@baseboard_fab2_lib.baseboard_fab2(sch_1):page41_i283:vss(604)" )
			)
			( pin "U5D1.BH15"
				( objectStatus "@baseboard_fab2_lib.baseboard_fab2(sch_1):page41_i283:vss(605)" )
			)
			( pin "U5D1.BH11"
				( objectStatus "@baseboard_fab2_lib.baseboard_fab2(sch_1):page41_i283:vss(606)" )
			)
			( pin "U5D1.BH9"
				( objectStatus "@baseboard_fab2_lib.baseboard_fab2(sch_1):page41_i283:vss(607)" )
			)
			( pin "U5D1.BH7"
				( objectStatus "@baseboard_fab2_lib.baseboard_fab2(sch_1):page41_i283:vss(608)" )
			)
			( pin "U5D1.BG82"
				( objectStatus "@baseboard_fab2_lib.baseboard_fab2(sch_1):page41_i283:vss(609)" )
			)
			( pin "U5D1.BG80"
				( objectStatus "@baseboard_fab2_lib.baseboard_fab2(sch_1):page41_i283:vss(610)" )
			)
			( pin "U5D1.BG78"
				( objectStatus "@baseboard_fab2_lib.baseboard_fab2(sch_1):page41_i283:vss(611)" )
			)
			( pin "U5D1.BG76"
				( objectStatus "@baseboard_fab2_lib.baseboard_fab2(sch_1):page41_i283:vss(612)" )
			)
			( pin "U5D1.BG74"
				( objectStatus "@baseboard_fab2_lib.baseboard_fab2(sch_1):page41_i283:vss(613)" )
			)
			( pin "U5D1.DA46"
				( objectStatus "@baseboard_fab2_lib.baseboard_fab2(sch_1):page41_i284:vss(294)" )
			)
			( pin "U5D1.DA44"
				( objectStatus "@baseboard_fab2_lib.baseboard_fab2(sch_1):page41_i284:vss(295)" )
			)
			( pin "U5D1.DA38"
				( objectStatus "@baseboard_fab2_lib.baseboard_fab2(sch_1):page41_i284:vss(296)" )
			)
			( pin "U5D1.DA36"
				( objectStatus "@baseboard_fab2_lib.baseboard_fab2(sch_1):page41_i284:vss(297)" )
			)
			( pin "U5D1.DA34"
				( objectStatus "@baseboard_fab2_lib.baseboard_fab2(sch_1):page41_i284:vss(298)" )
			)
			( pin "U5D1.DA32"
				( objectStatus "@baseboard_fab2_lib.baseboard_fab2(sch_1):page41_i284:vss(299)" )
			)
			( pin "U5D1.DA30"
				( objectStatus "@baseboard_fab2_lib.baseboard_fab2(sch_1):page41_i284:vss(300)" )
			)
			( pin "U5D1.DA28"
				( objectStatus "@baseboard_fab2_lib.baseboard_fab2(sch_1):page41_i284:vss(301)" )
			)
			( pin "U5D1.DA26"
				( objectStatus "@baseboard_fab2_lib.baseboard_fab2(sch_1):page41_i284:vss(302)" )
			)
			( pin "U5D1.DA18"
				( objectStatus "@baseboard_fab2_lib.baseboard_fab2(sch_1):page41_i284:vss(303)" )
			)
			( pin "U5D1.H53"
				( objectStatus "@baseboard_fab2_lib.baseboard_fab2(sch_1):page41_i284:vss(304)" )
			)
			( pin "U5D1.DA6"
				( objectStatus "@baseboard_fab2_lib.baseboard_fab2(sch_1):page41_i284:vss(305)" )
			)
			( pin "U5D1.CY85"
				( objectStatus "@baseboard_fab2_lib.baseboard_fab2(sch_1):page41_i284:vss(306)" )
			)
			( pin "U5D1.CY83"
				( objectStatus "@baseboard_fab2_lib.baseboard_fab2(sch_1):page41_i284:vss(307)" )
			)
			( pin "U5D1.CY77"
				( objectStatus "@baseboard_fab2_lib.baseboard_fab2(sch_1):page41_i284:vss(308)" )
			)
			( pin "U5D1.CY75"
				( objectStatus "@baseboard_fab2_lib.baseboard_fab2(sch_1):page41_i284:vss(309)" )
			)
			( pin "U5D1.CY69"
				( objectStatus "@baseboard_fab2_lib.baseboard_fab2(sch_1):page41_i284:vss(310)" )
			)
			( pin "U5D1.CY65"
				( objectStatus "@baseboard_fab2_lib.baseboard_fab2(sch_1):page41_i284:vss(311)" )
			)
			( pin "U5D1.CY61"
				( objectStatus "@baseboard_fab2_lib.baseboard_fab2(sch_1):page41_i284:vss(312)" )
			)
			( pin "U5D1.CY59"
				( objectStatus "@baseboard_fab2_lib.baseboard_fab2(sch_1):page41_i284:vss(313)" )
			)
			( pin "U5D1.CY51"
				( objectStatus "@baseboard_fab2_lib.baseboard_fab2(sch_1):page41_i284:vss(314)" )
			)
			( pin "U5D1.CY45"
				( objectStatus "@baseboard_fab2_lib.baseboard_fab2(sch_1):page41_i284:vss(315)" )
			)
			( pin "U5D1.CY41"
				( objectStatus "@baseboard_fab2_lib.baseboard_fab2(sch_1):page41_i284:vss(316)" )
			)
			( pin "U5D1.CY21"
				( objectStatus "@baseboard_fab2_lib.baseboard_fab2(sch_1):page41_i284:vss(317)" )
			)
			( pin "U5D1.CY15"
				( objectStatus "@baseboard_fab2_lib.baseboard_fab2(sch_1):page41_i284:vss(318)" )
			)
			( pin "U5D1.CY13"
				( objectStatus "@baseboard_fab2_lib.baseboard_fab2(sch_1):page41_i284:vss(319)" )
			)
			( pin "U5D1.CY9"
				( objectStatus "@baseboard_fab2_lib.baseboard_fab2(sch_1):page41_i284:vss(320)" )
			)
			( pin "U5D1.CY1"
				( objectStatus "@baseboard_fab2_lib.baseboard_fab2(sch_1):page41_i284:vss(321)" )
			)
			( pin "U5D1.CW82"
				( objectStatus "@baseboard_fab2_lib.baseboard_fab2(sch_1):page41_i284:vss(322)" )
			)
			( pin "U5D1.CW78"
				( objectStatus "@baseboard_fab2_lib.baseboard_fab2(sch_1):page41_i284:vss(323)" )
			)
			( pin "U5D1.CW74"
				( objectStatus "@baseboard_fab2_lib.baseboard_fab2(sch_1):page41_i284:vss(324)" )
			)
			( pin "U5D1.CW68"
				( objectStatus "@baseboard_fab2_lib.baseboard_fab2(sch_1):page41_i284:vss(325)" )
			)
			( pin "U5D1.CW66"
				( objectStatus "@baseboard_fab2_lib.baseboard_fab2(sch_1):page41_i284:vss(326)" )
			)
			( pin "U5D1.CW64"
				( objectStatus "@baseboard_fab2_lib.baseboard_fab2(sch_1):page41_i284:vss(327)" )
			)
			( pin "U5D1.CW54"
				( objectStatus "@baseboard_fab2_lib.baseboard_fab2(sch_1):page41_i284:vss(328)" )
			)
			( pin "U5D1.CW52"
				( objectStatus "@baseboard_fab2_lib.baseboard_fab2(sch_1):page41_i284:vss(329)" )
			)
			( pin "U5D1.CW42"
				( objectStatus "@baseboard_fab2_lib.baseboard_fab2(sch_1):page41_i284:vss(330)" )
			)
			( pin "U5D1.CW40"
				( objectStatus "@baseboard_fab2_lib.baseboard_fab2(sch_1):page41_i284:vss(331)" )
			)
			( pin "U5D1.CW38"
				( objectStatus "@baseboard_fab2_lib.baseboard_fab2(sch_1):page41_i284:vss(332)" )
			)
			( pin "U5D1.CW32"
				( objectStatus "@baseboard_fab2_lib.baseboard_fab2(sch_1):page41_i284:vss(333)" )
			)
			( pin "U5D1.CW26"
				( objectStatus "@baseboard_fab2_lib.baseboard_fab2(sch_1):page41_i284:vss(334)" )
			)
			( pin "U5D1.CW12"
				( objectStatus "@baseboard_fab2_lib.baseboard_fab2(sch_1):page41_i284:vss(335)" )
			)
			( pin "U5D1.CV83"
				( objectStatus "@baseboard_fab2_lib.baseboard_fab2(sch_1):page41_i284:vss(336)" )
			)
			( pin "U5D1.CV81"
				( objectStatus "@baseboard_fab2_lib.baseboard_fab2(sch_1):page41_i284:vss(337)" )
			)
			( pin "U5D1.CV79"
				( objectStatus "@baseboard_fab2_lib.baseboard_fab2(sch_1):page41_i284:vss(338)" )
			)
			( pin "U5D1.CV73"
				( objectStatus "@baseboard_fab2_lib.baseboard_fab2(sch_1):page41_i284:vss(339)" )
			)
			( pin "U5D1.CV67"
				( objectStatus "@baseboard_fab2_lib.baseboard_fab2(sch_1):page41_i284:vss(340)" )
			)
			( pin "U5D1.CV63"
				( objectStatus "@baseboard_fab2_lib.baseboard_fab2(sch_1):page41_i284:vss(341)" )
			)
			( pin "U5D1.CV55"
				( objectStatus "@baseboard_fab2_lib.baseboard_fab2(sch_1):page41_i284:vss(342)" )
			)
			( pin "U5D1.CV53"
				( objectStatus "@baseboard_fab2_lib.baseboard_fab2(sch_1):page41_i284:vss(343)" )
			)
			( pin "U5D1.CV41"
				( objectStatus "@baseboard_fab2_lib.baseboard_fab2(sch_1):page41_i284:vss(344)" )
			)
			( pin "U5D1.CV39"
				( objectStatus "@baseboard_fab2_lib.baseboard_fab2(sch_1):page41_i284:vss(345)" )
			)
			( pin "U5D1.CV37"
				( objectStatus "@baseboard_fab2_lib.baseboard_fab2(sch_1):page41_i284:vss(346)" )
			)
			( pin "U5D1.CV33"
				( objectStatus "@baseboard_fab2_lib.baseboard_fab2(sch_1):page41_i284:vss(347)" )
			)
			( pin "U5D1.CV31"
				( objectStatus "@baseboard_fab2_lib.baseboard_fab2(sch_1):page41_i284:vss(348)" )
			)
			( pin "U5D1.CV27"
				( objectStatus "@baseboard_fab2_lib.baseboard_fab2(sch_1):page41_i284:vss(349)" )
			)
			( pin "U5D1.CV25"
				( objectStatus "@baseboard_fab2_lib.baseboard_fab2(sch_1):page41_i284:vss(350)" )
			)
			( pin "U5D1.CV17"
				( objectStatus "@baseboard_fab2_lib.baseboard_fab2(sch_1):page41_i284:vss(351)" )
			)
			( pin "U5D1.H55"
				( objectStatus "@baseboard_fab2_lib.baseboard_fab2(sch_1):page41_i284:vss(352)" )
			)
			( pin "U5D1.CV1"
				( objectStatus "@baseboard_fab2_lib.baseboard_fab2(sch_1):page41_i284:vss(353)" )
			)
			( pin "U5D1.CU86"
				( objectStatus "@baseboard_fab2_lib.baseboard_fab2(sch_1):page41_i284:vss(354)" )
			)
			( pin "U5D1.CU82"
				( objectStatus "@baseboard_fab2_lib.baseboard_fab2(sch_1):page41_i284:vss(355)" )
			)
			( pin "U5D1.CU80"
				( objectStatus "@baseboard_fab2_lib.baseboard_fab2(sch_1):page41_i284:vss(356)" )
			)
			( pin "U5D1.CU78"
				( objectStatus "@baseboard_fab2_lib.baseboard_fab2(sch_1):page41_i284:vss(357)" )
			)
			( pin "U5D1.CU76"
				( objectStatus "@baseboard_fab2_lib.baseboard_fab2(sch_1):page41_i284:vss(358)" )
			)
			( pin "U5D1.CU68"
				( objectStatus "@baseboard_fab2_lib.baseboard_fab2(sch_1):page41_i284:vss(359)" )
			)
			( pin "U5D1.CU62"
				( objectStatus "@baseboard_fab2_lib.baseboard_fab2(sch_1):page41_i284:vss(360)" )
			)
			( pin "U5D1.CU56"
				( objectStatus "@baseboard_fab2_lib.baseboard_fab2(sch_1):page41_i284:vss(361)" )
			)
			( pin "U5D1.CU36"
				( objectStatus "@baseboard_fab2_lib.baseboard_fab2(sch_1):page41_i284:vss(362)" )
			)
			( pin "U5D1.CU34"
				( objectStatus "@baseboard_fab2_lib.baseboard_fab2(sch_1):page41_i284:vss(363)" )
			)
			( pin "U5D1.CU30"
				( objectStatus "@baseboard_fab2_lib.baseboard_fab2(sch_1):page41_i284:vss(364)" )
			)
			( pin "U5D1.CU28"
				( objectStatus "@baseboard_fab2_lib.baseboard_fab2(sch_1):page41_i284:vss(365)" )
			)
			( pin "U5D1.CU22"
				( objectStatus "@baseboard_fab2_lib.baseboard_fab2(sch_1):page41_i284:vss(366)" )
			)
			( pin "U5D1.CU4"
				( objectStatus "@baseboard_fab2_lib.baseboard_fab2(sch_1):page41_i284:vss(367)" )
			)
			( pin "U5D1.CT85"
				( objectStatus "@baseboard_fab2_lib.baseboard_fab2(sch_1):page41_i284:vss(368)" )
			)
			( pin "U5D1.CT83"
				( objectStatus "@baseboard_fab2_lib.baseboard_fab2(sch_1):page41_i284:vss(369)" )
			)
			( pin "U5D1.CT79"
				( objectStatus "@baseboard_fab2_lib.baseboard_fab2(sch_1):page41_i284:vss(370)" )
			)
			( pin "U5D1.CT73"
				( objectStatus "@baseboard_fab2_lib.baseboard_fab2(sch_1):page41_i284:vss(371)" )
			)
			( pin "U5D1.CT57"
				( objectStatus "@baseboard_fab2_lib.baseboard_fab2(sch_1):page41_i284:vss(372)" )
			)
			( pin "U5D1.CT35"
				( objectStatus "@baseboard_fab2_lib.baseboard_fab2(sch_1):page41_i284:vss(373)" )
			)
			( pin "U5D1.CT33"
				( objectStatus "@baseboard_fab2_lib.baseboard_fab2(sch_1):page41_i284:vss(374)" )
			)
			( pin "U5D1.CT29"
				( objectStatus "@baseboard_fab2_lib.baseboard_fab2(sch_1):page41_i284:vss(375)" )
			)
			( pin "U5D1.CT27"
				( objectStatus "@baseboard_fab2_lib.baseboard_fab2(sch_1):page41_i284:vss(376)" )
			)
			( pin "U5D1.CT19"
				( objectStatus "@baseboard_fab2_lib.baseboard_fab2(sch_1):page41_i284:vss(377)" )
			)
			( pin "U5D1.CT13"
				( objectStatus "@baseboard_fab2_lib.baseboard_fab2(sch_1):page41_i284:vss(378)" )
			)
			( pin "U5D1.H57"
				( objectStatus "@baseboard_fab2_lib.baseboard_fab2(sch_1):page41_i284:vss(379)" )
			)
			( pin "U5D1.CR86"
				( objectStatus "@baseboard_fab2_lib.baseboard_fab2(sch_1):page41_i284:vss(380)" )
			)
			( pin "U5D1.CR78"
				( objectStatus "@baseboard_fab2_lib.baseboard_fab2(sch_1):page41_i284:vss(381)" )
			)
			( pin "U5D1.CR68"
				( objectStatus "@baseboard_fab2_lib.baseboard_fab2(sch_1):page41_i284:vss(382)" )
			)
			( pin "U5D1.CR66"
				( objectStatus "@baseboard_fab2_lib.baseboard_fab2(sch_1):page41_i284:vss(383)" )
			)
			( pin "U5D1.CR64"
				( objectStatus "@baseboard_fab2_lib.baseboard_fab2(sch_1):page41_i284:vss(384)" )
			)
			( pin "U5D1.CR62"
				( objectStatus "@baseboard_fab2_lib.baseboard_fab2(sch_1):page41_i284:vss(385)" )
			)
			( pin "U5D1.CR58"
				( objectStatus "@baseboard_fab2_lib.baseboard_fab2(sch_1):page41_i284:vss(386)" )
			)
			( pin "U5D1.CR32"
				( objectStatus "@baseboard_fab2_lib.baseboard_fab2(sch_1):page41_i284:vss(387)" )
			)
			( pin "U5D1.CR24"
				( objectStatus "@baseboard_fab2_lib.baseboard_fab2(sch_1):page41_i284:vss(388)" )
			)
			( pin "U5D1.CR22"
				( objectStatus "@baseboard_fab2_lib.baseboard_fab2(sch_1):page41_i284:vss(389)" )
			)
			( pin "U5D1.CR10"
				( objectStatus "@baseboard_fab2_lib.baseboard_fab2(sch_1):page41_i284:vss(390)" )
			)
			( pin "U5D1.CR6"
				( objectStatus "@baseboard_fab2_lib.baseboard_fab2(sch_1):page41_i284:vss(391)" )
			)
			( pin "U5D1.CP83"
				( objectStatus "@baseboard_fab2_lib.baseboard_fab2(sch_1):page41_i284:vss(392)" )
			)
			( pin "U5D1.CP81"
				( objectStatus "@baseboard_fab2_lib.baseboard_fab2(sch_1):page41_i284:vss(393)" )
			)
			( pin "U5D1.CP75"
				( objectStatus "@baseboard_fab2_lib.baseboard_fab2(sch_1):page41_i284:vss(394)" )
			)
			( pin "U5D1.CP73"
				( objectStatus "@baseboard_fab2_lib.baseboard_fab2(sch_1):page41_i284:vss(395)" )
			)
			( pin "U5D1.CP69"
				( objectStatus "@baseboard_fab2_lib.baseboard_fab2(sch_1):page41_i284:vss(396)" )
			)
			( pin "U5D1.CP59"
				( objectStatus "@baseboard_fab2_lib.baseboard_fab2(sch_1):page41_i284:vss(397)" )
			)
			( pin "U5D1.CP25"
				( objectStatus "@baseboard_fab2_lib.baseboard_fab2(sch_1):page41_i284:vss(398)" )
			)
			( pin "U5D1.H59"
				( objectStatus "@baseboard_fab2_lib.baseboard_fab2(sch_1):page41_i284:vss(399)" )
			)
			( pin "U5D1.CP1"
				( objectStatus "@baseboard_fab2_lib.baseboard_fab2(sch_1):page41_i284:vss(400)" )
			)
			( pin "U5D1.CN78"
				( objectStatus "@baseboard_fab2_lib.baseboard_fab2(sch_1):page41_i284:vss(401)" )
			)
			( pin "U5D1.CN68"
				( objectStatus "@baseboard_fab2_lib.baseboard_fab2(sch_1):page41_i284:vss(402)" )
			)
			( pin "U5D1.CN62"
				( objectStatus "@baseboard_fab2_lib.baseboard_fab2(sch_1):page41_i284:vss(403)" )
			)
			( pin "U5D1.CN60"
				( objectStatus "@baseboard_fab2_lib.baseboard_fab2(sch_1):page41_i284:vss(404)" )
			)
			( pin "U5D1.CN32"
				( objectStatus "@baseboard_fab2_lib.baseboard_fab2(sch_1):page41_i284:vss(405)" )
			)
			( pin "U5D1.CN26"
				( objectStatus "@baseboard_fab2_lib.baseboard_fab2(sch_1):page41_i284:vss(406)" )
			)
			( pin "U5D1.H61"
				( objectStatus "@baseboard_fab2_lib.baseboard_fab2(sch_1):page41_i284:vss(407)" )
			)
			( pin "U5D1.CN12"
				( objectStatus "@baseboard_fab2_lib.baseboard_fab2(sch_1):page41_i284:vss(408)" )
			)
			( pin "U5D1.CN2"
				( objectStatus "@baseboard_fab2_lib.baseboard_fab2(sch_1):page41_i284:vss(409)" )
			)
			( pin "U5D1.CM85"
				( objectStatus "@baseboard_fab2_lib.baseboard_fab2(sch_1):page41_i284:vss(410)" )
			)
			( pin "U5D1.CM83"
				( objectStatus "@baseboard_fab2_lib.baseboard_fab2(sch_1):page41_i284:vss(411)" )
			)
			( pin "U5D1.CM77"
				( objectStatus "@baseboard_fab2_lib.baseboard_fab2(sch_1):page41_i284:vss(412)" )
			)
			( pin "U5D1.CM73"
				( objectStatus "@baseboard_fab2_lib.baseboard_fab2(sch_1):page41_i284:vss(413)" )
			)
			( pin "U5D1.CM67"
				( objectStatus "@baseboard_fab2_lib.baseboard_fab2(sch_1):page41_i284:vss(414)" )
			)
			( pin "U5D1.CM63"
				( objectStatus "@baseboard_fab2_lib.baseboard_fab2(sch_1):page41_i284:vss(415)" )
			)
			( pin "U5D1.CM61"
				( objectStatus "@baseboard_fab2_lib.baseboard_fab2(sch_1):page41_i284:vss(416)" )
			)
			( pin "U5D1.CM31"
				( objectStatus "@baseboard_fab2_lib.baseboard_fab2(sch_1):page41_i284:vss(417)" )
			)
			( pin "U5D1.CM5"
				( objectStatus "@baseboard_fab2_lib.baseboard_fab2(sch_1):page41_i284:vss(418)" )
			)
			( pin "U5D1.CM29"
				( objectStatus "@baseboard_fab2_lib.baseboard_fab2(sch_1):page41_i284:vss(419)" )
			)
			( pin "U5D1.CM19"
				( objectStatus "@baseboard_fab2_lib.baseboard_fab2(sch_1):page41_i284:vss(420)" )
			)
			( pin "U5D1.CL80"
				( objectStatus "@baseboard_fab2_lib.baseboard_fab2(sch_1):page41_i284:vss(421)" )
			)
			( pin "U5D1.CL78"
				( objectStatus "@baseboard_fab2_lib.baseboard_fab2(sch_1):page41_i284:vss(422)" )
			)
			( pin "U5D1.CL76"
				( objectStatus "@baseboard_fab2_lib.baseboard_fab2(sch_1):page41_i284:vss(423)" )
			)
			( pin "U5D1.CL74"
				( objectStatus "@baseboard_fab2_lib.baseboard_fab2(sch_1):page41_i284:vss(424)" )
			)
			( pin "U5D1.CL66"
				( objectStatus "@baseboard_fab2_lib.baseboard_fab2(sch_1):page41_i284:vss(425)" )
			)
			( pin "U5D1.CL64"
				( objectStatus "@baseboard_fab2_lib.baseboard_fab2(sch_1):page41_i284:vss(426)" )
			)
			( pin "U5D1.CL62"
				( objectStatus "@baseboard_fab2_lib.baseboard_fab2(sch_1):page41_i284:vss(427)" )
			)
			( pin "U5D1.H63"
				( objectStatus "@baseboard_fab2_lib.baseboard_fab2(sch_1):page41_i284:vss(428)" )
			)
			( pin "U5D1.P45"
				( objectStatus "@baseboard_fab2_lib.baseboard_fab2(sch_1):page41_i284:vss(429)" )
			)
			( pin "U5D1.CL18"
				( objectStatus "@baseboard_fab2_lib.baseboard_fab2(sch_1):page41_i284:vss(430)" )
			)
			( pin "U5D1.CL14"
				( objectStatus "@baseboard_fab2_lib.baseboard_fab2(sch_1):page41_i284:vss(431)" )
			)
			( pin "U5D1.CL8"
				( objectStatus "@baseboard_fab2_lib.baseboard_fab2(sch_1):page41_i284:vss(432)" )
			)
			( pin "U5D1.CK85"
				( objectStatus "@baseboard_fab2_lib.baseboard_fab2(sch_1):page41_i284:vss(433)" )
			)
			( pin "U5D1.CK83"
				( objectStatus "@baseboard_fab2_lib.baseboard_fab2(sch_1):page41_i284:vss(434)" )
			)
			( pin "U5D1.CK75"
				( objectStatus "@baseboard_fab2_lib.baseboard_fab2(sch_1):page41_i284:vss(435)" )
			)
			( pin "U5D1.CK73"
				( objectStatus "@baseboard_fab2_lib.baseboard_fab2(sch_1):page41_i284:vss(436)" )
			)
			( pin "U5D1.CK71"
				( objectStatus "@baseboard_fab2_lib.baseboard_fab2(sch_1):page41_i284:vss(437)" )
			)
			( pin "U5D1.CK69"
				( objectStatus "@baseboard_fab2_lib.baseboard_fab2(sch_1):page41_i284:vss(438)" )
			)
			( pin "U5D1.CK67"
				( objectStatus "@baseboard_fab2_lib.baseboard_fab2(sch_1):page41_i284:vss(439)" )
			)
			( pin "U5D1.CK65"
				( objectStatus "@baseboard_fab2_lib.baseboard_fab2(sch_1):page41_i284:vss(440)" )
			)
			( pin "U5D1.CK63"
				( objectStatus "@baseboard_fab2_lib.baseboard_fab2(sch_1):page41_i284:vss(441)" )
			)
			( pin "U5D1.CK27"
				( objectStatus "@baseboard_fab2_lib.baseboard_fab2(sch_1):page41_i284:vss(442)" )
			)
			( pin "U5D1.CK21"
				( objectStatus "@baseboard_fab2_lib.baseboard_fab2(sch_1):page41_i284:vss(443)" )
			)
			( pin "U5D1.CK15"
				( objectStatus "@baseboard_fab2_lib.baseboard_fab2(sch_1):page41_i284:vss(444)" )
			)
			( pin "U5D1.CK11"
				( objectStatus "@baseboard_fab2_lib.baseboard_fab2(sch_1):page41_i284:vss(445)" )
			)
			( pin "U5D1.CJ86"
				( objectStatus "@baseboard_fab2_lib.baseboard_fab2(sch_1):page41_i284:vss(446)" )
			)
			( pin "U5D1.CJ84"
				( objectStatus "@baseboard_fab2_lib.baseboard_fab2(sch_1):page41_i284:vss(447)" )
			)
			( pin "U5D1.CJ82"
				( objectStatus "@baseboard_fab2_lib.baseboard_fab2(sch_1):page41_i284:vss(448)" )
			)
			( pin "U5D1.CJ78"
				( objectStatus "@baseboard_fab2_lib.baseboard_fab2(sch_1):page41_i284:vss(449)" )
			)
			( pin "U5D1.CJ76"
				( objectStatus "@baseboard_fab2_lib.baseboard_fab2(sch_1):page41_i284:vss(450)" )
			)
			( pin "U5D1.CJ74"
				( objectStatus "@baseboard_fab2_lib.baseboard_fab2(sch_1):page41_i284:vss(451)" )
			)
			( pin "U5D1.CJ62"
				( objectStatus "@baseboard_fab2_lib.baseboard_fab2(sch_1):page41_i284:vss(452)" )
			)
			( pin "U5D1.P47"
				( objectStatus "@baseboard_fab2_lib.baseboard_fab2(sch_1):page41_i284:vss(453)" )
			)
			( pin "U5D1.DN72"
				( objectStatus "@baseboard_fab2_lib.baseboard_fab2(sch_1):page41_i285:vss(134)" )
			)
			( pin "U5D1.DN68"
				( objectStatus "@baseboard_fab2_lib.baseboard_fab2(sch_1):page41_i285:vss(135)" )
			)
			( pin "U5D1.DN38"
				( objectStatus "@baseboard_fab2_lib.baseboard_fab2(sch_1):page41_i285:vss(136)" )
			)
			( pin "U5D1.DN32"
				( objectStatus "@baseboard_fab2_lib.baseboard_fab2(sch_1):page41_i285:vss(137)" )
			)
			( pin "U5D1.DN26"
				( objectStatus "@baseboard_fab2_lib.baseboard_fab2(sch_1):page41_i285:vss(138)" )
			)
			( pin "U5D1.DN22"
				( objectStatus "@baseboard_fab2_lib.baseboard_fab2(sch_1):page41_i285:vss(139)" )
			)
			( pin "U5D1.DN12"
				( objectStatus "@baseboard_fab2_lib.baseboard_fab2(sch_1):page41_i285:vss(140)" )
			)
			( pin "U5D1.BH17"
				( objectStatus "@baseboard_fab2_lib.baseboard_fab2(sch_1):page41_i285:vss(141)" )
			)
			( pin "U5D1.DN2"
				( objectStatus "@baseboard_fab2_lib.baseboard_fab2(sch_1):page41_i285:vss(142)" )
			)
			( pin "U5D1.DM83"
				( objectStatus "@baseboard_fab2_lib.baseboard_fab2(sch_1):page41_i285:vss(143)" )
			)
			( pin "U5D1.DM77"
				( objectStatus "@baseboard_fab2_lib.baseboard_fab2(sch_1):page41_i285:vss(144)" )
			)
			( pin "U5D1.DM73"
				( objectStatus "@baseboard_fab2_lib.baseboard_fab2(sch_1):page41_i285:vss(145)" )
			)
			( pin "U5D1.DM65"
				( objectStatus "@baseboard_fab2_lib.baseboard_fab2(sch_1):page41_i285:vss(146)" )
			)
			( pin "U5D1.DM39"
				( objectStatus "@baseboard_fab2_lib.baseboard_fab2(sch_1):page41_i285:vss(147)" )
			)
			( pin "U5D1.DM37"
				( objectStatus "@baseboard_fab2_lib.baseboard_fab2(sch_1):page41_i285:vss(148)" )
			)
			( pin "U5D1.DM33"
				( objectStatus "@baseboard_fab2_lib.baseboard_fab2(sch_1):page41_i285:vss(149)" )
			)
			( pin "U5D1.DM31"
				( objectStatus "@baseboard_fab2_lib.baseboard_fab2(sch_1):page41_i285:vss(150)" )
			)
			( pin "U5D1.DM27"
				( objectStatus "@baseboard_fab2_lib.baseboard_fab2(sch_1):page41_i285:vss(151)" )
			)
			( pin "U5D1.DM25"
				( objectStatus "@baseboard_fab2_lib.baseboard_fab2(sch_1):page41_i285:vss(152)" )
			)
			( pin "U5D1.H45"
				( objectStatus "@baseboard_fab2_lib.baseboard_fab2(sch_1):page41_i285:vss(153)" )
			)
			( pin "U5D1.DM15"
				( objectStatus "@baseboard_fab2_lib.baseboard_fab2(sch_1):page41_i285:vss(154)" )
			)
			( pin "U5D1.DL80"
				( objectStatus "@baseboard_fab2_lib.baseboard_fab2(sch_1):page41_i285:vss(155)" )
			)
			( pin "U5D1.DL78"
				( objectStatus "@baseboard_fab2_lib.baseboard_fab2(sch_1):page41_i285:vss(156)" )
			)
			( pin "U5D1.DL76"
				( objectStatus "@baseboard_fab2_lib.baseboard_fab2(sch_1):page41_i285:vss(157)" )
			)
			( pin "U5D1.DL74"
				( objectStatus "@baseboard_fab2_lib.baseboard_fab2(sch_1):page41_i285:vss(158)" )
			)
			( pin "U5D1.DL70"
				( objectStatus "@baseboard_fab2_lib.baseboard_fab2(sch_1):page41_i285:vss(159)" )
			)
			( pin "U5D1.DL68"
				( objectStatus "@baseboard_fab2_lib.baseboard_fab2(sch_1):page41_i285:vss(160)" )
			)
			( pin "U5D1.DL40"
				( objectStatus "@baseboard_fab2_lib.baseboard_fab2(sch_1):page41_i285:vss(161)" )
			)
			( pin "U5D1.DL36"
				( objectStatus "@baseboard_fab2_lib.baseboard_fab2(sch_1):page41_i285:vss(162)" )
			)
			( pin "U5D1.DL34"
				( objectStatus "@baseboard_fab2_lib.baseboard_fab2(sch_1):page41_i285:vss(163)" )
			)
			( pin "U5D1.DL30"
				( objectStatus "@baseboard_fab2_lib.baseboard_fab2(sch_1):page41_i285:vss(164)" )
			)
			( pin "U5D1.DL28"
				( objectStatus "@baseboard_fab2_lib.baseboard_fab2(sch_1):page41_i285:vss(165)" )
			)
			( pin "U5D1.DL24"
				( objectStatus "@baseboard_fab2_lib.baseboard_fab2(sch_1):page41_i285:vss(166)" )
			)
			( pin "U5D1.DL22"
				( objectStatus "@baseboard_fab2_lib.baseboard_fab2(sch_1):page41_i285:vss(167)" )
			)
			( pin "U5D1.DL4"
				( objectStatus "@baseboard_fab2_lib.baseboard_fab2(sch_1):page41_i285:vss(168)" )
			)
			( pin "U5D1.DL18"
				( objectStatus "@baseboard_fab2_lib.baseboard_fab2(sch_1):page41_i285:vss(169)" )
			)
			( pin "U5D1.DL16"
				( objectStatus "@baseboard_fab2_lib.baseboard_fab2(sch_1):page41_i285:vss(170)" )
			)
			( pin "U5D1.DK85"
				( objectStatus "@baseboard_fab2_lib.baseboard_fab2(sch_1):page41_i285:vss(171)" )
			)
			( pin "U5D1.DK83"
				( objectStatus "@baseboard_fab2_lib.baseboard_fab2(sch_1):page41_i285:vss(172)" )
			)
			( pin "U5D1.DK77"
				( objectStatus "@baseboard_fab2_lib.baseboard_fab2(sch_1):page41_i285:vss(173)" )
			)
			( pin "U5D1.DK75"
				( objectStatus "@baseboard_fab2_lib.baseboard_fab2(sch_1):page41_i285:vss(174)" )
			)
			( pin "U5D1.DK73"
				( objectStatus "@baseboard_fab2_lib.baseboard_fab2(sch_1):page41_i285:vss(175)" )
			)
			( pin "U5D1.DK41"
				( objectStatus "@baseboard_fab2_lib.baseboard_fab2(sch_1):page41_i285:vss(176)" )
			)
			( pin "U5D1.DK39"
				( objectStatus "@baseboard_fab2_lib.baseboard_fab2(sch_1):page41_i285:vss(177)" )
			)
			( pin "U5D1.DK35"
				( objectStatus "@baseboard_fab2_lib.baseboard_fab2(sch_1):page41_i285:vss(178)" )
			)
			( pin "U5D1.DK29"
				( objectStatus "@baseboard_fab2_lib.baseboard_fab2(sch_1):page41_i285:vss(179)" )
			)
			( pin "U5D1.DK23"
				( objectStatus "@baseboard_fab2_lib.baseboard_fab2(sch_1):page41_i285:vss(180)" )
			)
			( pin "U5D1.DK7"
				( objectStatus "@baseboard_fab2_lib.baseboard_fab2(sch_1):page41_i285:vss(181)" )
			)
			( pin "U5D1.DJ84"
				( objectStatus "@baseboard_fab2_lib.baseboard_fab2(sch_1):page41_i285:vss(182)" )
			)
			( pin "U5D1.DJ82"
				( objectStatus "@baseboard_fab2_lib.baseboard_fab2(sch_1):page41_i285:vss(183)" )
			)
			( pin "U5D1.DJ78"
				( objectStatus "@baseboard_fab2_lib.baseboard_fab2(sch_1):page41_i285:vss(184)" )
			)
			( pin "U5D1.DJ74"
				( objectStatus "@baseboard_fab2_lib.baseboard_fab2(sch_1):page41_i285:vss(185)" )
			)
			( pin "U5D1.DJ68"
				( objectStatus "@baseboard_fab2_lib.baseboard_fab2(sch_1):page41_i285:vss(186)" )
			)
			( pin "U5D1.DJ42"
				( objectStatus "@baseboard_fab2_lib.baseboard_fab2(sch_1):page41_i285:vss(187)" )
			)
			( pin "U5D1.DJ38"
				( objectStatus "@baseboard_fab2_lib.baseboard_fab2(sch_1):page41_i285:vss(188)" )
			)
			( pin "U5D1.DJ22"
				( objectStatus "@baseboard_fab2_lib.baseboard_fab2(sch_1):page41_i285:vss(189)" )
			)
			( pin "U5D1.H47"
				( objectStatus "@baseboard_fab2_lib.baseboard_fab2(sch_1):page41_i285:vss(190)" )
			)
			( pin "U5D1.DJ10"
				( objectStatus "@baseboard_fab2_lib.baseboard_fab2(sch_1):page41_i285:vss(191)" )
			)
			( pin "U5D1.DJ2"
				( objectStatus "@baseboard_fab2_lib.baseboard_fab2(sch_1):page41_i285:vss(192)" )
			)
			( pin "U5D1.DH83"
				( objectStatus "@baseboard_fab2_lib.baseboard_fab2(sch_1):page41_i285:vss(193)" )
			)
			( pin "U5D1.DH81"
				( objectStatus "@baseboard_fab2_lib.baseboard_fab2(sch_1):page41_i285:vss(194)" )
			)
			( pin "U5D1.DH79"
				( objectStatus "@baseboard_fab2_lib.baseboard_fab2(sch_1):page41_i285:vss(195)" )
			)
			( pin "U5D1.DH73"
				( objectStatus "@baseboard_fab2_lib.baseboard_fab2(sch_1):page41_i285:vss(196)" )
			)
			( pin "U5D1.DH71"
				( objectStatus "@baseboard_fab2_lib.baseboard_fab2(sch_1):page41_i285:vss(197)" )
			)
			( pin "U5D1.DH67"
				( objectStatus "@baseboard_fab2_lib.baseboard_fab2(sch_1):page41_i285:vss(198)" )
			)
			( pin "U5D1.DH41"
				( objectStatus "@baseboard_fab2_lib.baseboard_fab2(sch_1):page41_i285:vss(199)" )
			)
			( pin "U5D1.DH37"
				( objectStatus "@baseboard_fab2_lib.baseboard_fab2(sch_1):page41_i285:vss(200)" )
			)
			( pin "U5D1.DH35"
				( objectStatus "@baseboard_fab2_lib.baseboard_fab2(sch_1):page41_i285:vss(201)" )
			)
			( pin "U5D1.DH33"
				( objectStatus "@baseboard_fab2_lib.baseboard_fab2(sch_1):page41_i285:vss(202)" )
			)
			( pin "U5D1.DH31"
				( objectStatus "@baseboard_fab2_lib.baseboard_fab2(sch_1):page41_i285:vss(203)" )
			)
			( pin "U5D1.DH29"
				( objectStatus "@baseboard_fab2_lib.baseboard_fab2(sch_1):page41_i285:vss(204)" )
			)
			( pin "U5D1.DH27"
				( objectStatus "@baseboard_fab2_lib.baseboard_fab2(sch_1):page41_i285:vss(205)" )
			)
			( pin "U5D1.DH25"
				( objectStatus "@baseboard_fab2_lib.baseboard_fab2(sch_1):page41_i285:vss(206)" )
			)
			( pin "U5D1.DH23"
				( objectStatus "@baseboard_fab2_lib.baseboard_fab2(sch_1):page41_i285:vss(207)" )
			)
			( pin "U5D1.DH15"
				( objectStatus "@baseboard_fab2_lib.baseboard_fab2(sch_1):page41_i285:vss(208)" )
			)
			( pin "U5D1.DH13"
				( objectStatus "@baseboard_fab2_lib.baseboard_fab2(sch_1):page41_i285:vss(209)" )
			)
			( pin "U5D1.DG82"
				( objectStatus "@baseboard_fab2_lib.baseboard_fab2(sch_1):page41_i285:vss(210)" )
			)
			( pin "U5D1.DG80"
				( objectStatus "@baseboard_fab2_lib.baseboard_fab2(sch_1):page41_i285:vss(211)" )
			)
			( pin "U5D1.DG78"
				( objectStatus "@baseboard_fab2_lib.baseboard_fab2(sch_1):page41_i285:vss(212)" )
			)
			( pin "U5D1.DG76"
				( objectStatus "@baseboard_fab2_lib.baseboard_fab2(sch_1):page41_i285:vss(213)" )
			)
			( pin "U5D1.DG68"
				( objectStatus "@baseboard_fab2_lib.baseboard_fab2(sch_1):page41_i285:vss(214)" )
			)
			( pin "U5D1.DG66"
				( objectStatus "@baseboard_fab2_lib.baseboard_fab2(sch_1):page41_i285:vss(215)" )
			)
			( pin "U5D1.DG24"
				( objectStatus "@baseboard_fab2_lib.baseboard_fab2(sch_1):page41_i285:vss(216)" )
			)
			( pin "U5D1.DG16"
				( objectStatus "@baseboard_fab2_lib.baseboard_fab2(sch_1):page41_i285:vss(217)" )
			)
			( pin "U5D1.DG14"
				( objectStatus "@baseboard_fab2_lib.baseboard_fab2(sch_1):page41_i285:vss(218)" )
			)
			( pin "U5D1.H49"
				( objectStatus "@baseboard_fab2_lib.baseboard_fab2(sch_1):page41_i285:vss(219)" )
			)
			( pin "U5D1.DG2"
				( objectStatus "@baseboard_fab2_lib.baseboard_fab2(sch_1):page41_i285:vss(220)" )
			)
			( pin "U5D1.DF85"
				( objectStatus "@baseboard_fab2_lib.baseboard_fab2(sch_1):page41_i285:vss(221)" )
			)
			( pin "U5D1.DF83"
				( objectStatus "@baseboard_fab2_lib.baseboard_fab2(sch_1):page41_i285:vss(222)" )
			)
			( pin "U5D1.DF79"
				( objectStatus "@baseboard_fab2_lib.baseboard_fab2(sch_1):page41_i285:vss(223)" )
			)
			( pin "U5D1.DF73"
				( objectStatus "@baseboard_fab2_lib.baseboard_fab2(sch_1):page41_i285:vss(224)" )
			)
			( pin "U5D1.DF69"
				( objectStatus "@baseboard_fab2_lib.baseboard_fab2(sch_1):page41_i285:vss(225)" )
			)
			( pin "U5D1.DF65"
				( objectStatus "@baseboard_fab2_lib.baseboard_fab2(sch_1):page41_i285:vss(226)" )
			)
			( pin "U5D1.DF41"
				( objectStatus "@baseboard_fab2_lib.baseboard_fab2(sch_1):page41_i285:vss(227)" )
			)
			( pin "U5D1.DF39"
				( objectStatus "@baseboard_fab2_lib.baseboard_fab2(sch_1):page41_i285:vss(228)" )
			)
			( pin "U5D1.DF37"
				( objectStatus "@baseboard_fab2_lib.baseboard_fab2(sch_1):page41_i285:vss(229)" )
			)
			( pin "U5D1.DF35"
				( objectStatus "@baseboard_fab2_lib.baseboard_fab2(sch_1):page41_i285:vss(230)" )
			)
			( pin "U5D1.DF29"
				( objectStatus "@baseboard_fab2_lib.baseboard_fab2(sch_1):page41_i285:vss(231)" )
			)
			( pin "U5D1.DF19"
				( objectStatus "@baseboard_fab2_lib.baseboard_fab2(sch_1):page41_i285:vss(232)" )
			)
			( pin "U5D1.H51"
				( objectStatus "@baseboard_fab2_lib.baseboard_fab2(sch_1):page41_i285:vss(233)" )
			)
			( pin "U5D1.DF7"
				( objectStatus "@baseboard_fab2_lib.baseboard_fab2(sch_1):page41_i285:vss(234)" )
			)
			( pin "U5D1.DF5"
				( objectStatus "@baseboard_fab2_lib.baseboard_fab2(sch_1):page41_i285:vss(235)" )
			)
			( pin "U5D1.DE78"
				( objectStatus "@baseboard_fab2_lib.baseboard_fab2(sch_1):page41_i285:vss(236)" )
			)
			( pin "U5D1.DE72"
				( objectStatus "@baseboard_fab2_lib.baseboard_fab2(sch_1):page41_i285:vss(237)" )
			)
			( pin "U5D1.DE70"
				( objectStatus "@baseboard_fab2_lib.baseboard_fab2(sch_1):page41_i285:vss(238)" )
			)
			( pin "U5D1.DE64"
				( objectStatus "@baseboard_fab2_lib.baseboard_fab2(sch_1):page41_i285:vss(239)" )
			)
			( pin "U5D1.DE36"
				( objectStatus "@baseboard_fab2_lib.baseboard_fab2(sch_1):page41_i285:vss(240)" )
			)
			( pin "U5D1.DE34"
				( objectStatus "@baseboard_fab2_lib.baseboard_fab2(sch_1):page41_i285:vss(241)" )
			)
			( pin "U5D1.DE30"
				( objectStatus "@baseboard_fab2_lib.baseboard_fab2(sch_1):page41_i285:vss(242)" )
			)
			( pin "U5D1.DE28"
				( objectStatus "@baseboard_fab2_lib.baseboard_fab2(sch_1):page41_i285:vss(243)" )
			)
			( pin "U5D1.DE24"
				( objectStatus "@baseboard_fab2_lib.baseboard_fab2(sch_1):page41_i285:vss(244)" )
			)
			( pin "U5D1.DE20"
				( objectStatus "@baseboard_fab2_lib.baseboard_fab2(sch_1):page41_i285:vss(245)" )
			)
			( pin "U5D1.DE18"
				( objectStatus "@baseboard_fab2_lib.baseboard_fab2(sch_1):page41_i285:vss(246)" )
			)
			( pin "U5D1.DE8"
				( objectStatus "@baseboard_fab2_lib.baseboard_fab2(sch_1):page41_i285:vss(247)" )
			)
			( pin "U5D1.DE6"
				( objectStatus "@baseboard_fab2_lib.baseboard_fab2(sch_1):page41_i285:vss(248)" )
			)
			( pin "U5D1.DD83"
				( objectStatus "@baseboard_fab2_lib.baseboard_fab2(sch_1):page41_i285:vss(249)" )
			)
			( pin "U5D1.DD81"
				( objectStatus "@baseboard_fab2_lib.baseboard_fab2(sch_1):page41_i285:vss(250)" )
			)
			( pin "U5D1.DD75"
				( objectStatus "@baseboard_fab2_lib.baseboard_fab2(sch_1):page41_i285:vss(251)" )
			)
			( pin "U5D1.DD73"
				( objectStatus "@baseboard_fab2_lib.baseboard_fab2(sch_1):page41_i285:vss(252)" )
			)
			( pin "U5D1.DD71"
				( objectStatus "@baseboard_fab2_lib.baseboard_fab2(sch_1):page41_i285:vss(253)" )
			)
			( pin "U5D1.DD37"
				( objectStatus "@baseboard_fab2_lib.baseboard_fab2(sch_1):page41_i285:vss(254)" )
			)
			( pin "U5D1.DD33"
				( objectStatus "@baseboard_fab2_lib.baseboard_fab2(sch_1):page41_i285:vss(255)" )
			)
			( pin "U5D1.DD31"
				( objectStatus "@baseboard_fab2_lib.baseboard_fab2(sch_1):page41_i285:vss(256)" )
			)
			( pin "U5D1.DD27"
				( objectStatus "@baseboard_fab2_lib.baseboard_fab2(sch_1):page41_i285:vss(257)" )
			)
			( pin "U5D1.DD23"
				( objectStatus "@baseboard_fab2_lib.baseboard_fab2(sch_1):page41_i285:vss(258)" )
			)
			( pin "U5D1.DD11"
				( objectStatus "@baseboard_fab2_lib.baseboard_fab2(sch_1):page41_i285:vss(259)" )
			)
			( pin "U5D1.DC86"
				( objectStatus "@baseboard_fab2_lib.baseboard_fab2(sch_1):page41_i285:vss(260)" )
			)
			( pin "U5D1.DC84"
				( objectStatus "@baseboard_fab2_lib.baseboard_fab2(sch_1):page41_i285:vss(261)" )
			)
			( pin "U5D1.DC78"
				( objectStatus "@baseboard_fab2_lib.baseboard_fab2(sch_1):page41_i285:vss(262)" )
			)
			( pin "U5D1.DC70"
				( objectStatus "@baseboard_fab2_lib.baseboard_fab2(sch_1):page41_i285:vss(263)" )
			)
			( pin "U5D1.DC68"
				( objectStatus "@baseboard_fab2_lib.baseboard_fab2(sch_1):page41_i285:vss(264)" )
			)
			( pin "U5D1.DC66"
				( objectStatus "@baseboard_fab2_lib.baseboard_fab2(sch_1):page41_i285:vss(265)" )
			)
			( pin "U5D1.DC64"
				( objectStatus "@baseboard_fab2_lib.baseboard_fab2(sch_1):page41_i285:vss(266)" )
			)
			( pin "U5D1.DC42"
				( objectStatus "@baseboard_fab2_lib.baseboard_fab2(sch_1):page41_i285:vss(267)" )
			)
			( pin "U5D1.DC38"
				( objectStatus "@baseboard_fab2_lib.baseboard_fab2(sch_1):page41_i285:vss(268)" )
			)
			( pin "U5D1.DC32"
				( objectStatus "@baseboard_fab2_lib.baseboard_fab2(sch_1):page41_i285:vss(269)" )
			)
			( pin "U5D1.DC26"
				( objectStatus "@baseboard_fab2_lib.baseboard_fab2(sch_1):page41_i285:vss(270)" )
			)
			( pin "U5D1.DC24"
				( objectStatus "@baseboard_fab2_lib.baseboard_fab2(sch_1):page41_i285:vss(271)" )
			)
			( pin "U5D1.DC14"
				( objectStatus "@baseboard_fab2_lib.baseboard_fab2(sch_1):page41_i285:vss(272)" )
			)
			( pin "U5D1.DB85"
				( objectStatus "@baseboard_fab2_lib.baseboard_fab2(sch_1):page41_i285:vss(273)" )
			)
			( pin "U5D1.DB83"
				( objectStatus "@baseboard_fab2_lib.baseboard_fab2(sch_1):page41_i285:vss(274)" )
			)
			( pin "U5D1.DB77"
				( objectStatus "@baseboard_fab2_lib.baseboard_fab2(sch_1):page41_i285:vss(275)" )
			)
			( pin "U5D1.DB73"
				( objectStatus "@baseboard_fab2_lib.baseboard_fab2(sch_1):page41_i285:vss(276)" )
			)
			( pin "U5D1.DB49"
				( objectStatus "@baseboard_fab2_lib.baseboard_fab2(sch_1):page41_i285:vss(277)" )
			)
			( pin "U5D1.DB47"
				( objectStatus "@baseboard_fab2_lib.baseboard_fab2(sch_1):page41_i285:vss(278)" )
			)
			( pin "U5D1.DB41"
				( objectStatus "@baseboard_fab2_lib.baseboard_fab2(sch_1):page41_i285:vss(279)" )
			)
			( pin "U5D1.DB39"
				( objectStatus "@baseboard_fab2_lib.baseboard_fab2(sch_1):page41_i285:vss(280)" )
			)
			( pin "U5D1.DB25"
				( objectStatus "@baseboard_fab2_lib.baseboard_fab2(sch_1):page41_i285:vss(281)" )
			)
			( pin "U5D1.DB23"
				( objectStatus "@baseboard_fab2_lib.baseboard_fab2(sch_1):page41_i285:vss(282)" )
			)
			( pin "U5D1.DB17"
				( objectStatus "@baseboard_fab2_lib.baseboard_fab2(sch_1):page41_i285:vss(283)" )
			)
			( pin "U5D1.DB13"
				( objectStatus "@baseboard_fab2_lib.baseboard_fab2(sch_1):page41_i285:vss(284)" )
			)
			( pin "U5D1.DB3"
				( objectStatus "@baseboard_fab2_lib.baseboard_fab2(sch_1):page41_i285:vss(285)" )
			)
			( pin "U5D1.DA80"
				( objectStatus "@baseboard_fab2_lib.baseboard_fab2(sch_1):page41_i285:vss(286)" )
			)
			( pin "U5D1.DA78"
				( objectStatus "@baseboard_fab2_lib.baseboard_fab2(sch_1):page41_i285:vss(287)" )
			)
			( pin "U5D1.DA76"
				( objectStatus "@baseboard_fab2_lib.baseboard_fab2(sch_1):page41_i285:vss(288)" )
			)
			( pin "U5D1.DA74"
				( objectStatus "@baseboard_fab2_lib.baseboard_fab2(sch_1):page41_i285:vss(289)" )
			)
			( pin "U5D1.DA70"
				( objectStatus "@baseboard_fab2_lib.baseboard_fab2(sch_1):page41_i285:vss(290)" )
			)
			( pin "U5D1.DA64"
				( objectStatus "@baseboard_fab2_lib.baseboard_fab2(sch_1):page41_i285:vss(291)" )
			)
			( pin "U5D1.DA50"
				( objectStatus "@baseboard_fab2_lib.baseboard_fab2(sch_1):page41_i285:vss(292)" )
			)
			( pin "U5D1.DA48"
				( objectStatus "@baseboard_fab2_lib.baseboard_fab2(sch_1):page41_i285:vss(293)" )
			)
			( pin "U5D1.EF79"
				( objectStatus "@baseboard_fab2_lib.baseboard_fab2(sch_1):page41_i286:vss(0)" )
			)
			( pin "U5D1.EF75"
				( objectStatus "@baseboard_fab2_lib.baseboard_fab2(sch_1):page41_i286:vss(1)" )
			)
			( pin "U5D1.EF71"
				( objectStatus "@baseboard_fab2_lib.baseboard_fab2(sch_1):page41_i286:vss(2)" )
			)
			( pin "U5D1.EE78"
				( objectStatus "@baseboard_fab2_lib.baseboard_fab2(sch_1):page41_i286:vss(3)" )
			)
			( pin "U5D1.EE76"
				( objectStatus "@baseboard_fab2_lib.baseboard_fab2(sch_1):page41_i286:vss(4)" )
			)
			( pin "U5D1.EE70"
				( objectStatus "@baseboard_fab2_lib.baseboard_fab2(sch_1):page41_i286:vss(5)" )
			)
			( pin "U5D1.EE36"
				( objectStatus "@baseboard_fab2_lib.baseboard_fab2(sch_1):page41_i286:vss(6)" )
			)
			( pin "U5D1.EE34"
				( objectStatus "@baseboard_fab2_lib.baseboard_fab2(sch_1):page41_i286:vss(7)" )
			)
			( pin "U5D1.EE30"
				( objectStatus "@baseboard_fab2_lib.baseboard_fab2(sch_1):page41_i286:vss(8)" )
			)
			( pin "U5D1.EE28"
				( objectStatus "@baseboard_fab2_lib.baseboard_fab2(sch_1):page41_i286:vss(9)" )
			)
			( pin "U5D1.EE24"
				( objectStatus "@baseboard_fab2_lib.baseboard_fab2(sch_1):page41_i286:vss(10)" )
			)
			( pin "U5D1.ED77"
				( objectStatus "@baseboard_fab2_lib.baseboard_fab2(sch_1):page41_i286:vss(11)" )
			)
			( pin "U5D1.ED35"
				( objectStatus "@baseboard_fab2_lib.baseboard_fab2(sch_1):page41_i286:vss(12)" )
			)
			( pin "U5D1.ED29"
				( objectStatus "@baseboard_fab2_lib.baseboard_fab2(sch_1):page41_i286:vss(13)" )
			)
			( pin "U5D1.ED23"
				( objectStatus "@baseboard_fab2_lib.baseboard_fab2(sch_1):page41_i286:vss(14)" )
			)
			( pin "U5D1.ED15"
				( objectStatus "@baseboard_fab2_lib.baseboard_fab2(sch_1):page41_i286:vss(15)" )
			)
			( pin "U5D1.ED11"
				( objectStatus "@baseboard_fab2_lib.baseboard_fab2(sch_1):page41_i286:vss(16)" )
			)
			( pin "U5D1.EC76"
				( objectStatus "@baseboard_fab2_lib.baseboard_fab2(sch_1):page41_i286:vss(17)" )
			)
			( pin "U5D1.EC74"
				( objectStatus "@baseboard_fab2_lib.baseboard_fab2(sch_1):page41_i286:vss(18)" )
			)
			( pin "U5D1.EC72"
				( objectStatus "@baseboard_fab2_lib.baseboard_fab2(sch_1):page41_i286:vss(19)" )
			)
			( pin "U5D1.EC70"
				( objectStatus "@baseboard_fab2_lib.baseboard_fab2(sch_1):page41_i286:vss(20)" )
			)
			( pin "U5D1.EC10"
				( objectStatus "@baseboard_fab2_lib.baseboard_fab2(sch_1):page41_i286:vss(21)" )
			)
			( pin "U5D1.EB69"
				( objectStatus "@baseboard_fab2_lib.baseboard_fab2(sch_1):page41_i286:vss(22)" )
			)
			( pin "U5D1.EB65"
				( objectStatus "@baseboard_fab2_lib.baseboard_fab2(sch_1):page41_i286:vss(23)" )
			)
			( pin "U5D1.EB41"
				( objectStatus "@baseboard_fab2_lib.baseboard_fab2(sch_1):page41_i286:vss(24)" )
			)
			( pin "U5D1.EB39"
				( objectStatus "@baseboard_fab2_lib.baseboard_fab2(sch_1):page41_i286:vss(25)" )
			)
			( pin "U5D1.EB37"
				( objectStatus "@baseboard_fab2_lib.baseboard_fab2(sch_1):page41_i286:vss(26)" )
			)
			( pin "U5D1.EB35"
				( objectStatus "@baseboard_fab2_lib.baseboard_fab2(sch_1):page41_i286:vss(27)" )
			)
			( pin "U5D1.EB33"
				( objectStatus "@baseboard_fab2_lib.baseboard_fab2(sch_1):page41_i286:vss(28)" )
			)
			( pin "U5D1.EB31"
				( objectStatus "@baseboard_fab2_lib.baseboard_fab2(sch_1):page41_i286:vss(29)" )
			)
			( pin "U5D1.EB29"
				( objectStatus "@baseboard_fab2_lib.baseboard_fab2(sch_1):page41_i286:vss(30)" )
			)
			( pin "U5D1.EB27"
				( objectStatus "@baseboard_fab2_lib.baseboard_fab2(sch_1):page41_i286:vss(31)" )
			)
			( pin "U5D1.EB25"
				( objectStatus "@baseboard_fab2_lib.baseboard_fab2(sch_1):page41_i286:vss(32)" )
			)
			( pin "U5D1.EB23"
				( objectStatus "@baseboard_fab2_lib.baseboard_fab2(sch_1):page41_i286:vss(33)" )
			)
			( pin "U5D1.BR18"
				( objectStatus "@baseboard_fab2_lib.baseboard_fab2(sch_1):page41_i286:vss(34)" )
			)
			( pin "U5D1.EB13"
				( objectStatus "@baseboard_fab2_lib.baseboard_fab2(sch_1):page41_i286:vss(35)" )
			)
			( pin "U5D1.EA82"
				( objectStatus "@baseboard_fab2_lib.baseboard_fab2(sch_1):page41_i286:vss(36)" )
			)
			( pin "U5D1.EA80"
				( objectStatus "@baseboard_fab2_lib.baseboard_fab2(sch_1):page41_i286:vss(37)" )
			)
			( pin "U5D1.EA78"
				( objectStatus "@baseboard_fab2_lib.baseboard_fab2(sch_1):page41_i286:vss(38)" )
			)
			( pin "U5D1.EA76"
				( objectStatus "@baseboard_fab2_lib.baseboard_fab2(sch_1):page41_i286:vss(39)" )
			)
			( pin "U5D1.EA70"
				( objectStatus "@baseboard_fab2_lib.baseboard_fab2(sch_1):page41_i286:vss(40)" )
			)
			( pin "U5D1.EA64"
				( objectStatus "@baseboard_fab2_lib.baseboard_fab2(sch_1):page41_i286:vss(41)" )
			)
			( pin "U5D1.EA42"
				( objectStatus "@baseboard_fab2_lib.baseboard_fab2(sch_1):page41_i286:vss(42)" )
			)
			( pin "U5D1.EA22"
				( objectStatus "@baseboard_fab2_lib.baseboard_fab2(sch_1):page41_i286:vss(43)" )
			)
			( pin "U5D1.EA20"
				( objectStatus "@baseboard_fab2_lib.baseboard_fab2(sch_1):page41_i286:vss(44)" )
			)
			( pin "U5D1.EA16"
				( objectStatus "@baseboard_fab2_lib.baseboard_fab2(sch_1):page41_i286:vss(45)" )
			)
			( pin "U5D1.J16"
				( objectStatus "@baseboard_fab2_lib.baseboard_fab2(sch_1):page41_i286:vss(46)" )
			)
			( pin "U5D1.EA6"
				( objectStatus "@baseboard_fab2_lib.baseboard_fab2(sch_1):page41_i286:vss(47)" )
			)
			( pin "U5D1.DY75"
				( objectStatus "@baseboard_fab2_lib.baseboard_fab2(sch_1):page41_i286:vss(48)" )
			)
			( pin "U5D1.DY71"
				( objectStatus "@baseboard_fab2_lib.baseboard_fab2(sch_1):page41_i286:vss(49)" )
			)
			( pin "U5D1.DY41"
				( objectStatus "@baseboard_fab2_lib.baseboard_fab2(sch_1):page41_i286:vss(50)" )
			)
			( pin "U5D1.DY35"
				( objectStatus "@baseboard_fab2_lib.baseboard_fab2(sch_1):page41_i286:vss(51)" )
			)
			( pin "U5D1.DY29"
				( objectStatus "@baseboard_fab2_lib.baseboard_fab2(sch_1):page41_i286:vss(52)" )
			)
			( pin "U5D1.DY23"
				( objectStatus "@baseboard_fab2_lib.baseboard_fab2(sch_1):page41_i286:vss(53)" )
			)
			( pin "U5D1.DY19"
				( objectStatus "@baseboard_fab2_lib.baseboard_fab2(sch_1):page41_i286:vss(54)" )
			)
			( pin "U5D1.DY5"
				( objectStatus "@baseboard_fab2_lib.baseboard_fab2(sch_1):page41_i286:vss(55)" )
			)
			( pin "U5D1.DW84"
				( objectStatus "@baseboard_fab2_lib.baseboard_fab2(sch_1):page41_i286:vss(56)" )
			)
			( pin "U5D1.DW82"
				( objectStatus "@baseboard_fab2_lib.baseboard_fab2(sch_1):page41_i286:vss(57)" )
			)
			( pin "U5D1.DW8"
				( objectStatus "@baseboard_fab2_lib.baseboard_fab2(sch_1):page41_i286:vss(58)" )
			)
			( pin "U5D1.DW76"
				( objectStatus "@baseboard_fab2_lib.baseboard_fab2(sch_1):page41_i286:vss(59)" )
			)
			( pin "U5D1.DW74"
				( objectStatus "@baseboard_fab2_lib.baseboard_fab2(sch_1):page41_i286:vss(60)" )
			)
			( pin "U5D1.DW72"
				( objectStatus "@baseboard_fab2_lib.baseboard_fab2(sch_1):page41_i286:vss(61)" )
			)
			( pin "U5D1.DW70"
				( objectStatus "@baseboard_fab2_lib.baseboard_fab2(sch_1):page41_i286:vss(62)" )
			)
			( pin "U5D1.DW68"
				( objectStatus "@baseboard_fab2_lib.baseboard_fab2(sch_1):page41_i286:vss(63)" )
			)
			( pin "U5D1.DW66"
				( objectStatus "@baseboard_fab2_lib.baseboard_fab2(sch_1):page41_i286:vss(64)" )
			)
			( pin "U5D1.DW64"
				( objectStatus "@baseboard_fab2_lib.baseboard_fab2(sch_1):page41_i286:vss(65)" )
			)
			( pin "U5D1.DW40"
				( objectStatus "@baseboard_fab2_lib.baseboard_fab2(sch_1):page41_i286:vss(66)" )
			)
			( pin "U5D1.DW36"
				( objectStatus "@baseboard_fab2_lib.baseboard_fab2(sch_1):page41_i286:vss(67)" )
			)
			( pin "U5D1.DW34"
				( objectStatus "@baseboard_fab2_lib.baseboard_fab2(sch_1):page41_i286:vss(68)" )
			)
			( pin "U5D1.DW30"
				( objectStatus "@baseboard_fab2_lib.baseboard_fab2(sch_1):page41_i286:vss(69)" )
			)
			( pin "U5D1.DW28"
				( objectStatus "@baseboard_fab2_lib.baseboard_fab2(sch_1):page41_i286:vss(70)" )
			)
			( pin "U5D1.DW24"
				( objectStatus "@baseboard_fab2_lib.baseboard_fab2(sch_1):page41_i286:vss(71)" )
			)
			( pin "U5D1.DW20"
				( objectStatus "@baseboard_fab2_lib.baseboard_fab2(sch_1):page41_i286:vss(72)" )
			)
			( pin "U5D1.DW12"
				( objectStatus "@baseboard_fab2_lib.baseboard_fab2(sch_1):page41_i286:vss(73)" )
			)
			( pin "U5D1.DV81"
				( objectStatus "@baseboard_fab2_lib.baseboard_fab2(sch_1):page41_i286:vss(74)" )
			)
			( pin "U5D1.DV77"
				( objectStatus "@baseboard_fab2_lib.baseboard_fab2(sch_1):page41_i286:vss(75)" )
			)
			( pin "U5D1.DV73"
				( objectStatus "@baseboard_fab2_lib.baseboard_fab2(sch_1):page41_i286:vss(76)" )
			)
			( pin "U5D1.DV39"
				( objectStatus "@baseboard_fab2_lib.baseboard_fab2(sch_1):page41_i286:vss(77)" )
			)
			( pin "U5D1.DV37"
				( objectStatus "@baseboard_fab2_lib.baseboard_fab2(sch_1):page41_i286:vss(78)" )
			)
			( pin "U5D1.DV33"
				( objectStatus "@baseboard_fab2_lib.baseboard_fab2(sch_1):page41_i286:vss(79)" )
			)
			( pin "U5D1.DV31"
				( objectStatus "@baseboard_fab2_lib.baseboard_fab2(sch_1):page41_i286:vss(80)" )
			)
			( pin "U5D1.DV27"
				( objectStatus "@baseboard_fab2_lib.baseboard_fab2(sch_1):page41_i286:vss(81)" )
			)
			( pin "U5D1.DV25"
				( objectStatus "@baseboard_fab2_lib.baseboard_fab2(sch_1):page41_i286:vss(82)" )
			)
			( pin "U5D1.DV21"
				( objectStatus "@baseboard_fab2_lib.baseboard_fab2(sch_1):page41_i286:vss(83)" )
			)
			( pin "U5D1.DU84"
				( objectStatus "@baseboard_fab2_lib.baseboard_fab2(sch_1):page41_i286:vss(84)" )
			)
			( pin "U5D1.DU82"
				( objectStatus "@baseboard_fab2_lib.baseboard_fab2(sch_1):page41_i286:vss(85)" )
			)
			( pin "U5D1.DU80"
				( objectStatus "@baseboard_fab2_lib.baseboard_fab2(sch_1):page41_i286:vss(86)" )
			)
			( pin "U5D1.DU78"
				( objectStatus "@baseboard_fab2_lib.baseboard_fab2(sch_1):page41_i286:vss(87)" )
			)
			( pin "U5D1.DU72"
				( objectStatus "@baseboard_fab2_lib.baseboard_fab2(sch_1):page41_i286:vss(88)" )
			)
			( pin "U5D1.DU70"
				( objectStatus "@baseboard_fab2_lib.baseboard_fab2(sch_1):page41_i286:vss(89)" )
			)
			( pin "U5D1.DU38"
				( objectStatus "@baseboard_fab2_lib.baseboard_fab2(sch_1):page41_i286:vss(90)" )
			)
			( pin "U5D1.DU32"
				( objectStatus "@baseboard_fab2_lib.baseboard_fab2(sch_1):page41_i286:vss(91)" )
			)
			( pin "U5D1.DU26"
				( objectStatus "@baseboard_fab2_lib.baseboard_fab2(sch_1):page41_i286:vss(92)" )
			)
			( pin "U5D1.DU22"
				( objectStatus "@baseboard_fab2_lib.baseboard_fab2(sch_1):page41_i286:vss(93)" )
			)
			( pin "U5D1.CN14"
				( objectStatus "@baseboard_fab2_lib.baseboard_fab2(sch_1):page41_i286:vss(94)" )
			)
			( pin "U5D1.DU14"
				( objectStatus "@baseboard_fab2_lib.baseboard_fab2(sch_1):page41_i286:vss(95)" )
			)
			( pin "U5D1.DU10"
				( objectStatus "@baseboard_fab2_lib.baseboard_fab2(sch_1):page41_i286:vss(96)" )
			)
			( pin "U5D1.DT85"
				( objectStatus "@baseboard_fab2_lib.baseboard_fab2(sch_1):page41_i286:vss(97)" )
			)
			( pin "U5D1.DT83"
				( objectStatus "@baseboard_fab2_lib.baseboard_fab2(sch_1):page41_i286:vss(98)" )
			)
			( pin "U5D1.DT79"
				( objectStatus "@baseboard_fab2_lib.baseboard_fab2(sch_1):page41_i286:vss(99)" )
			)
			( pin "U5D1.DT69"
				( objectStatus "@baseboard_fab2_lib.baseboard_fab2(sch_1):page41_i286:vss(100)" )
			)
			( pin "U5D1.DT65"
				( objectStatus "@baseboard_fab2_lib.baseboard_fab2(sch_1):page41_i286:vss(101)" )
			)
			( pin "U5D1.DH21"
				( objectStatus "@baseboard_fab2_lib.baseboard_fab2(sch_1):page41_i286:vss(102)" )
			)
			( pin "U5D1.DT17"
				( objectStatus "@baseboard_fab2_lib.baseboard_fab2(sch_1):page41_i286:vss(103)" )
			)
			( pin "U5D1.DT3"
				( objectStatus "@baseboard_fab2_lib.baseboard_fab2(sch_1):page41_i286:vss(104)" )
			)
			( pin "U5D1.DR78"
				( objectStatus "@baseboard_fab2_lib.baseboard_fab2(sch_1):page41_i286:vss(105)" )
			)
			( pin "U5D1.DR76"
				( objectStatus "@baseboard_fab2_lib.baseboard_fab2(sch_1):page41_i286:vss(106)" )
			)
			( pin "U5D1.DR74"
				( objectStatus "@baseboard_fab2_lib.baseboard_fab2(sch_1):page41_i286:vss(107)" )
			)
			( pin "U5D1.DR72"
				( objectStatus "@baseboard_fab2_lib.baseboard_fab2(sch_1):page41_i286:vss(108)" )
			)
			( pin "U5D1.DR70"
				( objectStatus "@baseboard_fab2_lib.baseboard_fab2(sch_1):page41_i286:vss(109)" )
			)
			( pin "U5D1.DR68"
				( objectStatus "@baseboard_fab2_lib.baseboard_fab2(sch_1):page41_i286:vss(110)" )
			)
			( pin "U5D1.DR66"
				( objectStatus "@baseboard_fab2_lib.baseboard_fab2(sch_1):page41_i286:vss(111)" )
			)
			( pin "U5D1.DR42"
				( objectStatus "@baseboard_fab2_lib.baseboard_fab2(sch_1):page41_i286:vss(112)" )
			)
			( pin "U5D1.DR40"
				( objectStatus "@baseboard_fab2_lib.baseboard_fab2(sch_1):page41_i286:vss(113)" )
			)
			( pin "U5D1.DR38"
				( objectStatus "@baseboard_fab2_lib.baseboard_fab2(sch_1):page41_i286:vss(114)" )
			)
			( pin "U5D1.DR36"
				( objectStatus "@baseboard_fab2_lib.baseboard_fab2(sch_1):page41_i286:vss(115)" )
			)
			( pin "U5D1.DR34"
				( objectStatus "@baseboard_fab2_lib.baseboard_fab2(sch_1):page41_i286:vss(116)" )
			)
			( pin "U5D1.DR32"
				( objectStatus "@baseboard_fab2_lib.baseboard_fab2(sch_1):page41_i286:vss(117)" )
			)
			( pin "U5D1.DR30"
				( objectStatus "@baseboard_fab2_lib.baseboard_fab2(sch_1):page41_i286:vss(118)" )
			)
			( pin "U5D1.DR28"
				( objectStatus "@baseboard_fab2_lib.baseboard_fab2(sch_1):page41_i286:vss(119)" )
			)
			( pin "U5D1.DR26"
				( objectStatus "@baseboard_fab2_lib.baseboard_fab2(sch_1):page41_i286:vss(120)" )
			)
			( pin "U5D1.DR24"
				( objectStatus "@baseboard_fab2_lib.baseboard_fab2(sch_1):page41_i286:vss(121)" )
			)
			( pin "U5D1.DR22"
				( objectStatus "@baseboard_fab2_lib.baseboard_fab2(sch_1):page41_i286:vss(122)" )
			)
			( pin "U5D1.DR20"
				( objectStatus "@baseboard_fab2_lib.baseboard_fab2(sch_1):page41_i286:vss(123)" )
			)
			( pin "U5D1.CL22"
				( objectStatus "@baseboard_fab2_lib.baseboard_fab2(sch_1):page41_i286:vss(124)" )
			)
			( pin "U5D1.CA20"
				( objectStatus "@baseboard_fab2_lib.baseboard_fab2(sch_1):page41_i286:vss(125)" )
			)
			( pin "U5D1.DR6"
				( objectStatus "@baseboard_fab2_lib.baseboard_fab2(sch_1):page41_i286:vss(126)" )
			)
			( pin "U5D1.BR26"
				( objectStatus "@baseboard_fab2_lib.baseboard_fab2(sch_1):page41_i286:vss(127)" )
			)
			( pin "U5D1.DP83"
				( objectStatus "@baseboard_fab2_lib.baseboard_fab2(sch_1):page41_i286:vss(128)" )
			)
			( pin "U5D1.DP81"
				( objectStatus "@baseboard_fab2_lib.baseboard_fab2(sch_1):page41_i286:vss(129)" )
			)
			( pin "U5D1.DP71"
				( objectStatus "@baseboard_fab2_lib.baseboard_fab2(sch_1):page41_i286:vss(130)" )
			)
			( pin "U5D1.DP69"
				( objectStatus "@baseboard_fab2_lib.baseboard_fab2(sch_1):page41_i286:vss(131)" )
			)
			( pin "U5D1.DP67"
				( objectStatus "@baseboard_fab2_lib.baseboard_fab2(sch_1):page41_i286:vss(132)" )
			)
			( pin "U5D1.DN78"
				( objectStatus "@baseboard_fab2_lib.baseboard_fab2(sch_1):page41_i286:vss(133)" )
			)
			( pin "C4P1.1"
				( objectStatus "@baseboard_fab2_lib.baseboard_fab2(sch_1):page42_i10:a" )
			)
			( pin "C4P1.2"
				( objectStatus "@baseboard_fab2_lib.baseboard_fab2(sch_1):page42_i10:b" )
			)
			( pin "C4P9.1"
				( objectStatus "@baseboard_fab2_lib.baseboard_fab2(sch_1):page42_i12:a" )
			)
			( pin "C4P9.2"
				( objectStatus "@baseboard_fab2_lib.baseboard_fab2(sch_1):page42_i12:b" )
			)
			( pin "C4P10.1"
				( objectStatus "@baseboard_fab2_lib.baseboard_fab2(sch_1):page42_i17:a" )
			)
			( pin "C4P10.2"
				( objectStatus "@baseboard_fab2_lib.baseboard_fab2(sch_1):page42_i17:b" )
			)
			( pin "C8P5.1"
				( objectStatus "@baseboard_fab2_lib.baseboard_fab2(sch_1):page76_i246:a" )
			)
			( pin "C8P5.2"
				( objectStatus "@baseboard_fab2_lib.baseboard_fab2(sch_1):page76_i246:b" )
			)
			( pin "C5P9.1"
				( objectStatus "@baseboard_fab2_lib.baseboard_fab2(sch_1):page42_i215:a" )
			)
			( pin "C5P9.2"
				( objectStatus "@baseboard_fab2_lib.baseboard_fab2(sch_1):page42_i215:b" )
			)
			( pin "C5P7.1"
				( objectStatus "@baseboard_fab2_lib.baseboard_fab2(sch_1):page42_i25:a" )
			)
			( pin "C5P7.2"
				( objectStatus "@baseboard_fab2_lib.baseboard_fab2(sch_1):page42_i25:b" )
			)
			( pin "C5P23.1"
				( objectStatus "@baseboard_fab2_lib.baseboard_fab2(sch_1):page42_i28:a" )
			)
			( pin "C5P23.2"
				( objectStatus "@baseboard_fab2_lib.baseboard_fab2(sch_1):page42_i28:b" )
			)
			( pin "C5P24.1"
				( objectStatus "@baseboard_fab2_lib.baseboard_fab2(sch_1):page42_i33:a" )
			)
			( pin "C5P24.2"
				( objectStatus "@baseboard_fab2_lib.baseboard_fab2(sch_1):page42_i33:b" )
			)
			( pin "C5P25.1"
				( objectStatus "@baseboard_fab2_lib.baseboard_fab2(sch_1):page42_i37:a" )
			)
			( pin "C5P25.2"
				( objectStatus "@baseboard_fab2_lib.baseboard_fab2(sch_1):page42_i37:b" )
			)
			( pin "C5P14.1"
				( objectStatus "@baseboard_fab2_lib.baseboard_fab2(sch_1):page42_i41:a" )
			)
			( pin "C5P14.2"
				( objectStatus "@baseboard_fab2_lib.baseboard_fab2(sch_1):page42_i41:b" )
			)
			( pin "C5P27.1"
				( objectStatus "@baseboard_fab2_lib.baseboard_fab2(sch_1):page42_i44:a" )
			)
			( pin "C5P27.2"
				( objectStatus "@baseboard_fab2_lib.baseboard_fab2(sch_1):page42_i44:b" )
			)
			( pin "C5P33.1"
				( objectStatus "@baseboard_fab2_lib.baseboard_fab2(sch_1):page42_i50:a" )
			)
			( pin "C5P33.2"
				( objectStatus "@baseboard_fab2_lib.baseboard_fab2(sch_1):page42_i50:b" )
			)
			( pin "C5P35.1"
				( objectStatus "@baseboard_fab2_lib.baseboard_fab2(sch_1):page42_i51:a" )
			)
			( pin "C5P35.2"
				( objectStatus "@baseboard_fab2_lib.baseboard_fab2(sch_1):page42_i51:b" )
			)
			( pin "C5P32.1"
				( objectStatus "@baseboard_fab2_lib.baseboard_fab2(sch_1):page42_i53:a" )
			)
			( pin "C5P32.2"
				( objectStatus "@baseboard_fab2_lib.baseboard_fab2(sch_1):page42_i53:b" )
			)
			( pin "C5P34.1"
				( objectStatus "@baseboard_fab2_lib.baseboard_fab2(sch_1):page42_i54:a" )
			)
			( pin "C5P34.2"
				( objectStatus "@baseboard_fab2_lib.baseboard_fab2(sch_1):page42_i54:b" )
			)
			( pin "C5P22.1"
				( objectStatus "@baseboard_fab2_lib.baseboard_fab2(sch_1):page42_i55:a" )
			)
			( pin "C5P22.2"
				( objectStatus "@baseboard_fab2_lib.baseboard_fab2(sch_1):page42_i55:b" )
			)
			( pin "C5P26.1"
				( objectStatus "@baseboard_fab2_lib.baseboard_fab2(sch_1):page42_i56:a" )
			)
			( pin "C5P26.2"
				( objectStatus "@baseboard_fab2_lib.baseboard_fab2(sch_1):page42_i56:b" )
			)
			( pin "C5P40.1"
				( objectStatus "@baseboard_fab2_lib.baseboard_fab2(sch_1):page42_i57:a" )
			)
			( pin "C5P40.2"
				( objectStatus "@baseboard_fab2_lib.baseboard_fab2(sch_1):page42_i57:b" )
			)
			( pin "C8P32.1"
				( objectStatus "@baseboard_fab2_lib.baseboard_fab2(sch_1):page225_i317:a" )
			)
			( pin "C8P32.2"
				( objectStatus "@baseboard_fab2_lib.baseboard_fab2(sch_1):page225_i317:b" )
			)
			( pin "C7P20.1"
				( objectStatus "@baseboard_fab2_lib.baseboard_fab2(sch_1):page225_i318:a" )
			)
			( pin "C7P20.2"
				( objectStatus "@baseboard_fab2_lib.baseboard_fab2(sch_1):page225_i318:b" )
			)
			( pin "C8P33.1"
				( objectStatus "@baseboard_fab2_lib.baseboard_fab2(sch_1):page225_i316:a" )
			)
			( pin "C8P33.2"
				( objectStatus "@baseboard_fab2_lib.baseboard_fab2(sch_1):page225_i316:b" )
			)
			( pin "C5P37.1"
				( objectStatus "@baseboard_fab2_lib.baseboard_fab2(sch_1):page42_i63:a" )
			)
			( pin "C5P37.2"
				( objectStatus "@baseboard_fab2_lib.baseboard_fab2(sch_1):page42_i63:b" )
			)
			( pin "C5P36.1"
				( objectStatus "@baseboard_fab2_lib.baseboard_fab2(sch_1):page42_i65:a" )
			)
			( pin "C5P36.2"
				( objectStatus "@baseboard_fab2_lib.baseboard_fab2(sch_1):page42_i65:b" )
			)
			( pin "C6D8.1"
				( objectStatus "@baseboard_fab2_lib.baseboard_fab2(sch_1):page42_i68:a" )
			)
			( pin "C6D8.2"
				( objectStatus "@baseboard_fab2_lib.baseboard_fab2(sch_1):page42_i68:b" )
			)
			( pin "C5D38.1"
				( objectStatus "@baseboard_fab2_lib.baseboard_fab2(sch_1):page42_i69:a" )
			)
			( pin "C5D38.2"
				( objectStatus "@baseboard_fab2_lib.baseboard_fab2(sch_1):page42_i69:b" )
			)
			( pin "C5D37.1"
				( objectStatus "@baseboard_fab2_lib.baseboard_fab2(sch_1):page42_i70:a" )
			)
			( pin "C5D37.2"
				( objectStatus "@baseboard_fab2_lib.baseboard_fab2(sch_1):page42_i70:b" )
			)
			( pin "C6D7.1"
				( objectStatus "@baseboard_fab2_lib.baseboard_fab2(sch_1):page42_i72:a" )
			)
			( pin "C6D7.2"
				( objectStatus "@baseboard_fab2_lib.baseboard_fab2(sch_1):page42_i72:b" )
			)
			( pin "C6D4.1"
				( objectStatus "@baseboard_fab2_lib.baseboard_fab2(sch_1):page42_i74:a" )
			)
			( pin "C6D4.2"
				( objectStatus "@baseboard_fab2_lib.baseboard_fab2(sch_1):page42_i74:b" )
			)
			( pin "C6D5.1"
				( objectStatus "@baseboard_fab2_lib.baseboard_fab2(sch_1):page42_i75:a" )
			)
			( pin "C6D5.2"
				( objectStatus "@baseboard_fab2_lib.baseboard_fab2(sch_1):page42_i75:b" )
			)
			( pin "C6D2.1"
				( objectStatus "@baseboard_fab2_lib.baseboard_fab2(sch_1):page42_i77:a" )
			)
			( pin "C6D2.2"
				( objectStatus "@baseboard_fab2_lib.baseboard_fab2(sch_1):page42_i77:b" )
			)
			( pin "C6D3.1"
				( objectStatus "@baseboard_fab2_lib.baseboard_fab2(sch_1):page42_i80:a" )
			)
			( pin "C6D3.2"
				( objectStatus "@baseboard_fab2_lib.baseboard_fab2(sch_1):page42_i80:b" )
			)
			( pin "C6D6.1"
				( objectStatus "@baseboard_fab2_lib.baseboard_fab2(sch_1):page42_i81:a" )
			)
			( pin "C6D6.2"
				( objectStatus "@baseboard_fab2_lib.baseboard_fab2(sch_1):page42_i81:b" )
			)
			( pin "C5D51.1"
				( objectStatus "@baseboard_fab2_lib.baseboard_fab2(sch_1):page42_i83:a" )
			)
			( pin "C5D51.2"
				( objectStatus "@baseboard_fab2_lib.baseboard_fab2(sch_1):page42_i83:b" )
			)
			( pin "C5D21.1"
				( objectStatus "@baseboard_fab2_lib.baseboard_fab2(sch_1):page42_i88:a" )
			)
			( pin "C5D21.2"
				( objectStatus "@baseboard_fab2_lib.baseboard_fab2(sch_1):page42_i88:b" )
			)
			( pin "C5D50.1"
				( objectStatus "@baseboard_fab2_lib.baseboard_fab2(sch_1):page42_i89:a" )
			)
			( pin "C5D50.2"
				( objectStatus "@baseboard_fab2_lib.baseboard_fab2(sch_1):page42_i89:b" )
			)
			( pin "C5D48.1"
				( objectStatus "@baseboard_fab2_lib.baseboard_fab2(sch_1):page42_i90:a" )
			)
			( pin "C5D48.2"
				( objectStatus "@baseboard_fab2_lib.baseboard_fab2(sch_1):page42_i90:b" )
			)
			( pin "C5D13.1"
				( objectStatus "@baseboard_fab2_lib.baseboard_fab2(sch_1):page42_i91:a" )
			)
			( pin "C5D13.2"
				( objectStatus "@baseboard_fab2_lib.baseboard_fab2(sch_1):page42_i91:b" )
			)
			( pin "C5D11.1"
				( objectStatus "@baseboard_fab2_lib.baseboard_fab2(sch_1):page42_i93:a" )
			)
			( pin "C5D11.2"
				( objectStatus "@baseboard_fab2_lib.baseboard_fab2(sch_1):page42_i93:b" )
			)
			( pin "C5D12.1"
				( objectStatus "@baseboard_fab2_lib.baseboard_fab2(sch_1):page42_i94:a" )
			)
			( pin "C5D12.2"
				( objectStatus "@baseboard_fab2_lib.baseboard_fab2(sch_1):page42_i94:b" )
			)
			( pin "C5D23.1"
				( objectStatus "@baseboard_fab2_lib.baseboard_fab2(sch_1):page42_i98:a" )
			)
			( pin "C5D23.2"
				( objectStatus "@baseboard_fab2_lib.baseboard_fab2(sch_1):page42_i98:b" )
			)
			( pin "C5D28.1"
				( objectStatus "@baseboard_fab2_lib.baseboard_fab2(sch_1):page42_i100:a" )
			)
			( pin "C5D28.2"
				( objectStatus "@baseboard_fab2_lib.baseboard_fab2(sch_1):page42_i100:b" )
			)
			( pin "C5D29.1"
				( objectStatus "@baseboard_fab2_lib.baseboard_fab2(sch_1):page42_i102:a" )
			)
			( pin "C5D29.2"
				( objectStatus "@baseboard_fab2_lib.baseboard_fab2(sch_1):page42_i102:b" )
			)
			( pin "C5D32.1"
				( objectStatus "@baseboard_fab2_lib.baseboard_fab2(sch_1):page42_i103:a" )
			)
			( pin "C5D32.2"
				( objectStatus "@baseboard_fab2_lib.baseboard_fab2(sch_1):page42_i103:b" )
			)
			( pin "C5D47.1"
				( objectStatus "@baseboard_fab2_lib.baseboard_fab2(sch_1):page42_i104:a" )
			)
			( pin "C5D47.2"
				( objectStatus "@baseboard_fab2_lib.baseboard_fab2(sch_1):page42_i104:b" )
			)
			( pin "C5D31.1"
				( objectStatus "@baseboard_fab2_lib.baseboard_fab2(sch_1):page42_i106:a" )
			)
			( pin "C5D31.2"
				( objectStatus "@baseboard_fab2_lib.baseboard_fab2(sch_1):page42_i106:b" )
			)
			( pin "C5D46.1"
				( objectStatus "@baseboard_fab2_lib.baseboard_fab2(sch_1):page42_i107:a" )
			)
			( pin "C5D46.2"
				( objectStatus "@baseboard_fab2_lib.baseboard_fab2(sch_1):page42_i107:b" )
			)
			( pin "C5D10.1"
				( objectStatus "@baseboard_fab2_lib.baseboard_fab2(sch_1):page42_i108:a" )
			)
			( pin "C5D10.2"
				( objectStatus "@baseboard_fab2_lib.baseboard_fab2(sch_1):page42_i108:b" )
			)
			( pin "C5D27.1"
				( objectStatus "@baseboard_fab2_lib.baseboard_fab2(sch_1):page42_i109:a" )
			)
			( pin "C5D27.2"
				( objectStatus "@baseboard_fab2_lib.baseboard_fab2(sch_1):page42_i109:b" )
			)
			( pin "C5D30.1"
				( objectStatus "@baseboard_fab2_lib.baseboard_fab2(sch_1):page42_i111:a" )
			)
			( pin "C5D30.2"
				( objectStatus "@baseboard_fab2_lib.baseboard_fab2(sch_1):page42_i111:b" )
			)
			( pin "C5D60.1"
				( objectStatus "@baseboard_fab2_lib.baseboard_fab2(sch_1):page217_i272:a" )
			)
			( pin "C5D60.2"
				( objectStatus "@baseboard_fab2_lib.baseboard_fab2(sch_1):page217_i272:b" )
			)
			( pin "C5D59.1"
				( objectStatus "@baseboard_fab2_lib.baseboard_fab2(sch_1):page217_i271:a" )
			)
			( pin "C5D59.2"
				( objectStatus "@baseboard_fab2_lib.baseboard_fab2(sch_1):page217_i271:b" )
			)
			( pin "C5D41.1"
				( objectStatus "@baseboard_fab2_lib.baseboard_fab2(sch_1):page42_i114:a" )
			)
			( pin "C5D41.2"
				( objectStatus "@baseboard_fab2_lib.baseboard_fab2(sch_1):page42_i114:b" )
			)
			( pin "C5D40.1"
				( objectStatus "@baseboard_fab2_lib.baseboard_fab2(sch_1):page42_i115:a" )
			)
			( pin "C5D40.2"
				( objectStatus "@baseboard_fab2_lib.baseboard_fab2(sch_1):page42_i115:b" )
			)
			( pin "C5D14.1"
				( objectStatus "@baseboard_fab2_lib.baseboard_fab2(sch_1):page42_i117:a" )
			)
			( pin "C5D14.2"
				( objectStatus "@baseboard_fab2_lib.baseboard_fab2(sch_1):page42_i117:b" )
			)
			( pin "C5D17.1"
				( objectStatus "@baseboard_fab2_lib.baseboard_fab2(sch_1):page42_i118:a" )
			)
			( pin "C5D17.2"
				( objectStatus "@baseboard_fab2_lib.baseboard_fab2(sch_1):page42_i118:b" )
			)
			( pin "C5D61.1"
				( objectStatus "@baseboard_fab2_lib.baseboard_fab2(sch_1):page217_i270:a" )
			)
			( pin "C5D61.2"
				( objectStatus "@baseboard_fab2_lib.baseboard_fab2(sch_1):page217_i270:b" )
			)
			( pin "C5D16.1"
				( objectStatus "@baseboard_fab2_lib.baseboard_fab2(sch_1):page42_i123:a" )
			)
			( pin "C5D16.2"
				( objectStatus "@baseboard_fab2_lib.baseboard_fab2(sch_1):page42_i123:b" )
			)
			( pin "C5D5.1"
				( objectStatus "@baseboard_fab2_lib.baseboard_fab2(sch_1):page42_i125:a" )
			)
			( pin "C5D5.2"
				( objectStatus "@baseboard_fab2_lib.baseboard_fab2(sch_1):page42_i125:b" )
			)
			( pin "C5D1.1"
				( objectStatus "@baseboard_fab2_lib.baseboard_fab2(sch_1):page220_i252:a" )
			)
			( pin "C5D1.2"
				( objectStatus "@baseboard_fab2_lib.baseboard_fab2(sch_1):page220_i252:b" )
			)
			( pin "C5D2.1"
				( objectStatus "@baseboard_fab2_lib.baseboard_fab2(sch_1):page220_i251:a" )
			)
			( pin "C5D2.2"
				( objectStatus "@baseboard_fab2_lib.baseboard_fab2(sch_1):page220_i251:b" )
			)
			( pin "C5D19.1"
				( objectStatus "@baseboard_fab2_lib.baseboard_fab2(sch_1):page42_i128:a" )
			)
			( pin "C5D19.2"
				( objectStatus "@baseboard_fab2_lib.baseboard_fab2(sch_1):page42_i128:b" )
			)
			( pin "C5D58.1"
				( objectStatus "@baseboard_fab2_lib.baseboard_fab2(sch_1):page217_i269:a" )
			)
			( pin "C5D58.2"
				( objectStatus "@baseboard_fab2_lib.baseboard_fab2(sch_1):page217_i269:b" )
			)
			( pin "C5D3.1"
				( objectStatus "@baseboard_fab2_lib.baseboard_fab2(sch_1):page220_i250:a" )
			)
			( pin "C5D3.2"
				( objectStatus "@baseboard_fab2_lib.baseboard_fab2(sch_1):page220_i250:b" )
			)
			( pin "C5D43.1"
				( objectStatus "@baseboard_fab2_lib.baseboard_fab2(sch_1):page42_i131:a" )
			)
			( pin "C5D43.2"
				( objectStatus "@baseboard_fab2_lib.baseboard_fab2(sch_1):page42_i131:b" )
			)
			( pin "C5D15.1"
				( objectStatus "@baseboard_fab2_lib.baseboard_fab2(sch_1):page42_i132:a" )
			)
			( pin "C5D15.2"
				( objectStatus "@baseboard_fab2_lib.baseboard_fab2(sch_1):page42_i132:b" )
			)
			( pin "C5D18.1"
				( objectStatus "@baseboard_fab2_lib.baseboard_fab2(sch_1):page42_i134:a" )
			)
			( pin "C5D18.2"
				( objectStatus "@baseboard_fab2_lib.baseboard_fab2(sch_1):page42_i134:b" )
			)
			( pin "C5D42.1"
				( objectStatus "@baseboard_fab2_lib.baseboard_fab2(sch_1):page42_i135:a" )
			)
			( pin "C5D42.2"
				( objectStatus "@baseboard_fab2_lib.baseboard_fab2(sch_1):page42_i135:b" )
			)
			( pin "C5D4.1"
				( objectStatus "@baseboard_fab2_lib.baseboard_fab2(sch_1):page220_i249:a" )
			)
			( pin "C5D4.2"
				( objectStatus "@baseboard_fab2_lib.baseboard_fab2(sch_1):page220_i249:b" )
			)
			( pin "C5D24.1"
				( objectStatus "@baseboard_fab2_lib.baseboard_fab2(sch_1):page42_i138:a" )
			)
			( pin "C5D24.2"
				( objectStatus "@baseboard_fab2_lib.baseboard_fab2(sch_1):page42_i138:b" )
			)
			( pin "C5D39.1"
				( objectStatus "@baseboard_fab2_lib.baseboard_fab2(sch_1):page42_i140:a" )
			)
			( pin "C5D39.2"
				( objectStatus "@baseboard_fab2_lib.baseboard_fab2(sch_1):page42_i140:b" )
			)
			( pin "C5D44.1"
				( objectStatus "@baseboard_fab2_lib.baseboard_fab2(sch_1):page42_i142:a" )
			)
			( pin "C5D44.2"
				( objectStatus "@baseboard_fab2_lib.baseboard_fab2(sch_1):page42_i142:b" )
			)
			( pin "C6D9.1"
				( objectStatus "@baseboard_fab2_lib.baseboard_fab2(sch_1):page42_i145:a" )
			)
			( pin "C6D9.2"
				( objectStatus "@baseboard_fab2_lib.baseboard_fab2(sch_1):page42_i145:b" )
			)
			( pin "C6D10.1"
				( objectStatus "@baseboard_fab2_lib.baseboard_fab2(sch_1):page42_i147:a" )
			)
			( pin "C6D10.2"
				( objectStatus "@baseboard_fab2_lib.baseboard_fab2(sch_1):page42_i147:b" )
			)
			( pin "C5D36.1"
				( objectStatus "@baseboard_fab2_lib.baseboard_fab2(sch_1):page42_i151:a" )
			)
			( pin "C5D36.2"
				( objectStatus "@baseboard_fab2_lib.baseboard_fab2(sch_1):page42_i151:b" )
			)
			( pin "C5D49.1"
				( objectStatus "@baseboard_fab2_lib.baseboard_fab2(sch_1):page42_i152:a" )
			)
			( pin "C5D49.2"
				( objectStatus "@baseboard_fab2_lib.baseboard_fab2(sch_1):page42_i152:b" )
			)
			( pin "C5D22.1"
				( objectStatus "@baseboard_fab2_lib.baseboard_fab2(sch_1):page42_i153:a" )
			)
			( pin "C5D22.2"
				( objectStatus "@baseboard_fab2_lib.baseboard_fab2(sch_1):page42_i153:b" )
			)
			( pin "C5D26.1"
				( objectStatus "@baseboard_fab2_lib.baseboard_fab2(sch_1):page42_i154:a" )
			)
			( pin "C5D26.2"
				( objectStatus "@baseboard_fab2_lib.baseboard_fab2(sch_1):page42_i154:b" )
			)
			( pin "C5D25.1"
				( objectStatus "@baseboard_fab2_lib.baseboard_fab2(sch_1):page42_i155:a" )
			)
			( pin "C5D25.2"
				( objectStatus "@baseboard_fab2_lib.baseboard_fab2(sch_1):page42_i155:b" )
			)
			( pin "C5D45.1"
				( objectStatus "@baseboard_fab2_lib.baseboard_fab2(sch_1):page42_i156:a" )
			)
			( pin "C5D45.2"
				( objectStatus "@baseboard_fab2_lib.baseboard_fab2(sch_1):page42_i156:b" )
			)
			( pin "C4P6.1"
				( objectStatus "@baseboard_fab2_lib.baseboard_fab2(sch_1):page42_i164:a" )
			)
			( pin "C4P6.2"
				( objectStatus "@baseboard_fab2_lib.baseboard_fab2(sch_1):page42_i164:b" )
			)
			( pin "C5D20.1"
				( objectStatus "@baseboard_fab2_lib.baseboard_fab2(sch_1):page42_i173:a" )
			)
			( pin "C5D20.2"
				( objectStatus "@baseboard_fab2_lib.baseboard_fab2(sch_1):page42_i173:b" )
			)
			( pin "C5D33.1"
				( objectStatus "@baseboard_fab2_lib.baseboard_fab2(sch_1):page42_i174:a" )
			)
			( pin "C5D33.2"
				( objectStatus "@baseboard_fab2_lib.baseboard_fab2(sch_1):page42_i174:b" )
			)
			( pin "C5D34.1"
				( objectStatus "@baseboard_fab2_lib.baseboard_fab2(sch_1):page42_i175:a" )
			)
			( pin "C5D34.2"
				( objectStatus "@baseboard_fab2_lib.baseboard_fab2(sch_1):page42_i175:b" )
			)
			( pin "C5D35.1"
				( objectStatus "@baseboard_fab2_lib.baseboard_fab2(sch_1):page42_i176:a" )
			)
			( pin "C5D35.2"
				( objectStatus "@baseboard_fab2_lib.baseboard_fab2(sch_1):page42_i176:b" )
			)
			( pin "C4P8.1"
				( objectStatus "@baseboard_fab2_lib.baseboard_fab2(sch_1):page42_i178:a" )
			)
			( pin "C4P8.2"
				( objectStatus "@baseboard_fab2_lib.baseboard_fab2(sch_1):page42_i178:b" )
			)
			( pin "C5D53.1"
				( objectStatus "@baseboard_fab2_lib.baseboard_fab2(sch_1):page42_i179:a" )
			)
			( pin "C5D53.2"
				( objectStatus "@baseboard_fab2_lib.baseboard_fab2(sch_1):page42_i179:b" )
			)
			( pin "C5D52.1"
				( objectStatus "@baseboard_fab2_lib.baseboard_fab2(sch_1):page42_i180:a" )
			)
			( pin "C5D52.2"
				( objectStatus "@baseboard_fab2_lib.baseboard_fab2(sch_1):page42_i180:b" )
			)
			( pin "C5P15.1"
				( objectStatus "@baseboard_fab2_lib.baseboard_fab2(sch_1):page42_i187:a" )
			)
			( pin "C5P15.2"
				( objectStatus "@baseboard_fab2_lib.baseboard_fab2(sch_1):page42_i187:b" )
			)
			( pin "C5P16.1"
				( objectStatus "@baseboard_fab2_lib.baseboard_fab2(sch_1):page42_i188:a" )
			)
			( pin "C5P16.2"
				( objectStatus "@baseboard_fab2_lib.baseboard_fab2(sch_1):page42_i188:b" )
			)
			( pin "C5P17.1"
				( objectStatus "@baseboard_fab2_lib.baseboard_fab2(sch_1):page42_i190:a" )
			)
			( pin "C5P17.2"
				( objectStatus "@baseboard_fab2_lib.baseboard_fab2(sch_1):page42_i190:b" )
			)
			( pin "J4G1.79"
				( objectStatus "@baseboard_fab2_lib.baseboard_fab2(sch_1):page43_i1:a0" )
			)
			( pin "J4G1.72"
				( objectStatus "@baseboard_fab2_lib.baseboard_fab2(sch_1):page43_i1:a1" )
			)
			( pin "J4G1.216"
				( objectStatus "@baseboard_fab2_lib.baseboard_fab2(sch_1):page43_i1:a2" )
			)
			( pin "J4G1.71"
				( objectStatus "@baseboard_fab2_lib.baseboard_fab2(sch_1):page43_i1:a3" )
			)
			( pin "J4G1.214"
				( objectStatus "@baseboard_fab2_lib.baseboard_fab2(sch_1):page43_i1:a4" )
			)
			( pin "J4G1.213"
				( objectStatus "@baseboard_fab2_lib.baseboard_fab2(sch_1):page43_i1:a5" )
			)
			( pin "J4G1.69"
				( objectStatus "@baseboard_fab2_lib.baseboard_fab2(sch_1):page43_i1:a6" )
			)
			( pin "J4G1.211"
				( objectStatus "@baseboard_fab2_lib.baseboard_fab2(sch_1):page43_i1:a7" )
			)
			( pin "J4G1.68"
				( objectStatus "@baseboard_fab2_lib.baseboard_fab2(sch_1):page43_i1:a8" )
			)
			( pin "J4G1.66"
				( objectStatus "@baseboard_fab2_lib.baseboard_fab2(sch_1):page43_i1:a9" )
			)
			( pin "J4G1.225"
				( objectStatus "@baseboard_fab2_lib.baseboard_fab2(sch_1):page43_i1:a10" )
			)
			( pin "J4G1.210"
				( objectStatus "@baseboard_fab2_lib.baseboard_fab2(sch_1):page43_i1:a11" )
			)
			( pin "J4G1.65"
				( objectStatus "@baseboard_fab2_lib.baseboard_fab2(sch_1):page43_i1:a12" )
			)
			( pin "J4G1.232"
				( objectStatus "@baseboard_fab2_lib.baseboard_fab2(sch_1):page43_i1:a13" )
			)
			( pin "J4G1.228"
				( objectStatus "@baseboard_fab2_lib.baseboard_fab2(sch_1):page43_i1:a14_we_n" )
			)
			( pin "J4G1.86"
				( objectStatus "@baseboard_fab2_lib.baseboard_fab2(sch_1):page43_i1:a15_cas_n" )
			)
			( pin "J4G1.82"
				( objectStatus "@baseboard_fab2_lib.baseboard_fab2(sch_1):page43_i1:a16_ras_n" )
			)
			( pin "J4G1.234"
				( objectStatus "@baseboard_fab2_lib.baseboard_fab2(sch_1):page43_i1:a17" )
			)
			( pin "J4G1.62"
				( objectStatus "@baseboard_fab2_lib.baseboard_fab2(sch_1):page43_i1:act_n" )
			)
			( pin "J4G1.208"
				( objectStatus "@baseboard_fab2_lib.baseboard_fab2(sch_1):page43_i1:alert_n" )
			)
			( pin "J4G1.81"
				( objectStatus "@baseboard_fab2_lib.baseboard_fab2(sch_1):page43_i1:ba(0)" )
			)
			( pin "J4G1.224"
				( objectStatus "@baseboard_fab2_lib.baseboard_fab2(sch_1):page43_i1:ba(1)" )
			)
			( pin "J4G1.63"
				( objectStatus "@baseboard_fab2_lib.baseboard_fab2(sch_1):page43_i1:bg(0)" )
			)
			( pin "J4G1.207"
				( objectStatus "@baseboard_fab2_lib.baseboard_fab2(sch_1):page43_i1:bg(1)" )
			)
			( pin "J4G1.235"
				( objectStatus "@baseboard_fab2_lib.baseboard_fab2(sch_1):page43_i1:c(2)" )
			)
			( pin "J4G1.49"
				( objectStatus "@baseboard_fab2_lib.baseboard_fab2(sch_1):page43_i1:cb(0)" )
			)
			( pin "J4G1.194"
				( objectStatus "@baseboard_fab2_lib.baseboard_fab2(sch_1):page43_i1:cb(1)" )
			)
			( pin "J4G1.56"
				( objectStatus "@baseboard_fab2_lib.baseboard_fab2(sch_1):page43_i1:cb(2)" )
			)
			( pin "J4G1.201"
				( objectStatus "@baseboard_fab2_lib.baseboard_fab2(sch_1):page43_i1:cb(3)" )
			)
			( pin "J4G1.47"
				( objectStatus "@baseboard_fab2_lib.baseboard_fab2(sch_1):page43_i1:cb(4)" )
			)
			( pin "J4G1.192"
				( objectStatus "@baseboard_fab2_lib.baseboard_fab2(sch_1):page43_i1:cb(5)" )
			)
			( pin "J4G1.54"
				( objectStatus "@baseboard_fab2_lib.baseboard_fab2(sch_1):page43_i1:cb(6)" )
			)
			( pin "J4G1.199"
				( objectStatus "@baseboard_fab2_lib.baseboard_fab2(sch_1):page43_i1:cb(7)" )
			)
			( pin "J4G1.75"
				( objectStatus "@baseboard_fab2_lib.baseboard_fab2(sch_1):page43_i1:ck0n" )
			)
			( pin "J4G1.74"
				( objectStatus "@baseboard_fab2_lib.baseboard_fab2(sch_1):page43_i1:ck0p" )
			)
			( pin "J4G1.219"
				( objectStatus "@baseboard_fab2_lib.baseboard_fab2(sch_1):page43_i1:ck1n" )
			)
			( pin "J4G1.218"
				( objectStatus "@baseboard_fab2_lib.baseboard_fab2(sch_1):page43_i1:ck1p" )
			)
			( pin "J4G1.60"
				( objectStatus "@baseboard_fab2_lib.baseboard_fab2(sch_1):page43_i1:cke(0)" )
			)
			( pin "J4G1.203"
				( objectStatus "@baseboard_fab2_lib.baseboard_fab2(sch_1):page43_i1:cke(1)" )
			)
			( pin "J4G1.5"
				( objectStatus "@baseboard_fab2_lib.baseboard_fab2(sch_1):page43_i1:dq(0)" )
			)
			( pin "J4G1.150"
				( objectStatus "@baseboard_fab2_lib.baseboard_fab2(sch_1):page43_i1:dq(1)" )
			)
			( pin "J4G1.12"
				( objectStatus "@baseboard_fab2_lib.baseboard_fab2(sch_1):page43_i1:dq(2)" )
			)
			( pin "J4G1.157"
				( objectStatus "@baseboard_fab2_lib.baseboard_fab2(sch_1):page43_i1:dq(3)" )
			)
			( pin "J4G1.3"
				( objectStatus "@baseboard_fab2_lib.baseboard_fab2(sch_1):page43_i1:dq(4)" )
			)
			( pin "J4G1.148"
				( objectStatus "@baseboard_fab2_lib.baseboard_fab2(sch_1):page43_i1:dq(5)" )
			)
			( pin "J4G1.10"
				( objectStatus "@baseboard_fab2_lib.baseboard_fab2(sch_1):page43_i1:dq(6)" )
			)
			( pin "J4G1.155"
				( objectStatus "@baseboard_fab2_lib.baseboard_fab2(sch_1):page43_i1:dq(7)" )
			)
			( pin "J4G1.16"
				( objectStatus "@baseboard_fab2_lib.baseboard_fab2(sch_1):page43_i1:dq(8)" )
			)
			( pin "J4G1.161"
				( objectStatus "@baseboard_fab2_lib.baseboard_fab2(sch_1):page43_i1:dq(9)" )
			)
			( pin "J4G1.23"
				( objectStatus "@baseboard_fab2_lib.baseboard_fab2(sch_1):page43_i1:dq(10)" )
			)
			( pin "J4G1.168"
				( objectStatus "@baseboard_fab2_lib.baseboard_fab2(sch_1):page43_i1:dq(11)" )
			)
			( pin "J4G1.14"
				( objectStatus "@baseboard_fab2_lib.baseboard_fab2(sch_1):page43_i1:dq(12)" )
			)
			( pin "J4G1.159"
				( objectStatus "@baseboard_fab2_lib.baseboard_fab2(sch_1):page43_i1:dq(13)" )
			)
			( pin "J4G1.21"
				( objectStatus "@baseboard_fab2_lib.baseboard_fab2(sch_1):page43_i1:dq(14)" )
			)
			( pin "J4G1.166"
				( objectStatus "@baseboard_fab2_lib.baseboard_fab2(sch_1):page43_i1:dq(15)" )
			)
			( pin "J4G1.27"
				( objectStatus "@baseboard_fab2_lib.baseboard_fab2(sch_1):page43_i1:dq(16)" )
			)
			( pin "J4G1.172"
				( objectStatus "@baseboard_fab2_lib.baseboard_fab2(sch_1):page43_i1:dq(17)" )
			)
			( pin "J4G1.34"
				( objectStatus "@baseboard_fab2_lib.baseboard_fab2(sch_1):page43_i1:dq(18)" )
			)
			( pin "J4G1.179"
				( objectStatus "@baseboard_fab2_lib.baseboard_fab2(sch_1):page43_i1:dq(19)" )
			)
			( pin "J4G1.25"
				( objectStatus "@baseboard_fab2_lib.baseboard_fab2(sch_1):page43_i1:dq(20)" )
			)
			( pin "J4G1.170"
				( objectStatus "@baseboard_fab2_lib.baseboard_fab2(sch_1):page43_i1:dq(21)" )
			)
			( pin "J4G1.32"
				( objectStatus "@baseboard_fab2_lib.baseboard_fab2(sch_1):page43_i1:dq(22)" )
			)
			( pin "J4G1.177"
				( objectStatus "@baseboard_fab2_lib.baseboard_fab2(sch_1):page43_i1:dq(23)" )
			)
			( pin "J4G1.38"
				( objectStatus "@baseboard_fab2_lib.baseboard_fab2(sch_1):page43_i1:dq(24)" )
			)
			( pin "J4G1.183"
				( objectStatus "@baseboard_fab2_lib.baseboard_fab2(sch_1):page43_i1:dq(25)" )
			)
			( pin "J4G1.45"
				( objectStatus "@baseboard_fab2_lib.baseboard_fab2(sch_1):page43_i1:dq(26)" )
			)
			( pin "J4G1.190"
				( objectStatus "@baseboard_fab2_lib.baseboard_fab2(sch_1):page43_i1:dq(27)" )
			)
			( pin "J4G1.36"
				( objectStatus "@baseboard_fab2_lib.baseboard_fab2(sch_1):page43_i1:dq(28)" )
			)
			( pin "J4G1.181"
				( objectStatus "@baseboard_fab2_lib.baseboard_fab2(sch_1):page43_i1:dq(29)" )
			)
			( pin "J4G1.43"
				( objectStatus "@baseboard_fab2_lib.baseboard_fab2(sch_1):page43_i1:dq(30)" )
			)
			( pin "J4G1.188"
				( objectStatus "@baseboard_fab2_lib.baseboard_fab2(sch_1):page43_i1:dq(31)" )
			)
			( pin "J4G1.97"
				( objectStatus "@baseboard_fab2_lib.baseboard_fab2(sch_1):page43_i1:dq(32)" )
			)
			( pin "J4G1.242"
				( objectStatus "@baseboard_fab2_lib.baseboard_fab2(sch_1):page43_i1:dq(33)" )
			)
			( pin "J4G1.104"
				( objectStatus "@baseboard_fab2_lib.baseboard_fab2(sch_1):page43_i1:dq(34)" )
			)
			( pin "J4G1.249"
				( objectStatus "@baseboard_fab2_lib.baseboard_fab2(sch_1):page43_i1:dq(35)" )
			)
			( pin "J4G1.95"
				( objectStatus "@baseboard_fab2_lib.baseboard_fab2(sch_1):page43_i1:dq(36)" )
			)
			( pin "J4G1.240"
				( objectStatus "@baseboard_fab2_lib.baseboard_fab2(sch_1):page43_i1:dq(37)" )
			)
			( pin "J4G1.102"
				( objectStatus "@baseboard_fab2_lib.baseboard_fab2(sch_1):page43_i1:dq(38)" )
			)
			( pin "J4G1.247"
				( objectStatus "@baseboard_fab2_lib.baseboard_fab2(sch_1):page43_i1:dq(39)" )
			)
			( pin "J4G1.108"
				( objectStatus "@baseboard_fab2_lib.baseboard_fab2(sch_1):page43_i1:dq(40)" )
			)
			( pin "J4G1.253"
				( objectStatus "@baseboard_fab2_lib.baseboard_fab2(sch_1):page43_i1:dq(41)" )
			)
			( pin "J4G1.115"
				( objectStatus "@baseboard_fab2_lib.baseboard_fab2(sch_1):page43_i1:dq(42)" )
			)
			( pin "J4G1.260"
				( objectStatus "@baseboard_fab2_lib.baseboard_fab2(sch_1):page43_i1:dq(43)" )
			)
			( pin "J4G1.106"
				( objectStatus "@baseboard_fab2_lib.baseboard_fab2(sch_1):page43_i1:dq(44)" )
			)
			( pin "J4G1.251"
				( objectStatus "@baseboard_fab2_lib.baseboard_fab2(sch_1):page43_i1:dq(45)" )
			)
			( pin "J4G1.113"
				( objectStatus "@baseboard_fab2_lib.baseboard_fab2(sch_1):page43_i1:dq(46)" )
			)
			( pin "J4G1.258"
				( objectStatus "@baseboard_fab2_lib.baseboard_fab2(sch_1):page43_i1:dq(47)" )
			)
			( pin "J4G1.119"
				( objectStatus "@baseboard_fab2_lib.baseboard_fab2(sch_1):page43_i1:dq(48)" )
			)
			( pin "J4G1.264"
				( objectStatus "@baseboard_fab2_lib.baseboard_fab2(sch_1):page43_i1:dq(49)" )
			)
			( pin "J4G1.126"
				( objectStatus "@baseboard_fab2_lib.baseboard_fab2(sch_1):page43_i1:dq(50)" )
			)
			( pin "J4G1.271"
				( objectStatus "@baseboard_fab2_lib.baseboard_fab2(sch_1):page43_i1:dq(51)" )
			)
			( pin "J4G1.117"
				( objectStatus "@baseboard_fab2_lib.baseboard_fab2(sch_1):page43_i1:dq(52)" )
			)
			( pin "J4G1.262"
				( objectStatus "@baseboard_fab2_lib.baseboard_fab2(sch_1):page43_i1:dq(53)" )
			)
			( pin "J4G1.124"
				( objectStatus "@baseboard_fab2_lib.baseboard_fab2(sch_1):page43_i1:dq(54)" )
			)
			( pin "J4G1.269"
				( objectStatus "@baseboard_fab2_lib.baseboard_fab2(sch_1):page43_i1:dq(55)" )
			)
			( pin "J4G1.130"
				( objectStatus "@baseboard_fab2_lib.baseboard_fab2(sch_1):page43_i1:dq(56)" )
			)
			( pin "J4G1.275"
				( objectStatus "@baseboard_fab2_lib.baseboard_fab2(sch_1):page43_i1:dq(57)" )
			)
			( pin "J4G1.137"
				( objectStatus "@baseboard_fab2_lib.baseboard_fab2(sch_1):page43_i1:dq(58)" )
			)
			( pin "J4G1.282"
				( objectStatus "@baseboard_fab2_lib.baseboard_fab2(sch_1):page43_i1:dq(59)" )
			)
			( pin "J4G1.128"
				( objectStatus "@baseboard_fab2_lib.baseboard_fab2(sch_1):page43_i1:dq(60)" )
			)
			( pin "J4G1.273"
				( objectStatus "@baseboard_fab2_lib.baseboard_fab2(sch_1):page43_i1:dq(61)" )
			)
			( pin "J4G1.135"
				( objectStatus "@baseboard_fab2_lib.baseboard_fab2(sch_1):page43_i1:dq(62)" )
			)
			( pin "J4G1.280"
				( objectStatus "@baseboard_fab2_lib.baseboard_fab2(sch_1):page43_i1:dq(63)" )
			)
			( pin "J4G1.78"
				( objectStatus "@baseboard_fab2_lib.baseboard_fab2(sch_1):page43_i1:event_n" )
			)
			( pin "J4G1.87"
				( objectStatus "@baseboard_fab2_lib.baseboard_fab2(sch_1):page43_i1:odt(0)" )
			)
			( pin "J4G1.91"
				( objectStatus "@baseboard_fab2_lib.baseboard_fab2(sch_1):page43_i1:odt(1)" )
			)
			( pin "J4G1.222"
				( objectStatus "@baseboard_fab2_lib.baseboard_fab2(sch_1):page43_i1:par" )
			)
			( pin "J4G1.58"
				( objectStatus "@baseboard_fab2_lib.baseboard_fab2(sch_1):page43_i1:reset_n" )
			)
			( pin "J4G1.205"
				( objectStatus "@baseboard_fab2_lib.baseboard_fab2(sch_1):page43_i1:rfu(0)" )
			)
			( pin "J4G1.227"
				( objectStatus "@baseboard_fab2_lib.baseboard_fab2(sch_1):page43_i1:rfu(1)" )
			)
			( pin "J4G1.144"
				( objectStatus "@baseboard_fab2_lib.baseboard_fab2(sch_1):page43_i1:rfu(2)" )
			)
			( pin "J4G1.84"
				( objectStatus "@baseboard_fab2_lib.baseboard_fab2(sch_1):page43_i1:s0_n" )
			)
			( pin "J4G1.89"
				( objectStatus "@baseboard_fab2_lib.baseboard_fab2(sch_1):page43_i1:s1_n" )
			)
			( pin "J4G1.93"
				( objectStatus "@baseboard_fab2_lib.baseboard_fab2(sch_1):page43_i1:s2_n_c(0)" )
			)
			( pin "J4G1.237"
				( objectStatus "@baseboard_fab2_lib.baseboard_fab2(sch_1):page43_i1:s3_n_c(1)" )
			)
			( pin "J4G1.139"
				( objectStatus "@baseboard_fab2_lib.baseboard_fab2(sch_1):page43_i1:sa(0)" )
			)
			( pin "J4G1.140"
				( objectStatus "@baseboard_fab2_lib.baseboard_fab2(sch_1):page43_i1:sa(1)" )
			)
			( pin "J4G1.238"
				( objectStatus "@baseboard_fab2_lib.baseboard_fab2(sch_1):page43_i1:sa(2)" )
			)
			( pin "J4G1.230"
				( objectStatus "@baseboard_fab2_lib.baseboard_fab2(sch_1):page43_i1:save_n_nc" )
			)
			( pin "J4G1.141"
				( objectStatus "@baseboard_fab2_lib.baseboard_fab2(sch_1):page43_i1:scl" )
			)
			( pin "J4G1.285"
				( objectStatus "@baseboard_fab2_lib.baseboard_fab2(sch_1):page43_i1:sda" )
			)
			( pin "J4G1.284"
				( objectStatus "@baseboard_fab2_lib.baseboard_fab2(sch_1):page43_i1:vddspd" )
			)
			( pin "J4G1.146"
				( objectStatus "@baseboard_fab2_lib.baseboard_fab2(sch_1):page43_i1:vrefca" )
			)
			( pin "J4G1.152"
				( objectStatus "@baseboard_fab2_lib.baseboard_fab2(sch_1):page43_i2:dqs0n" )
			)
			( pin "J4G1.153"
				( objectStatus "@baseboard_fab2_lib.baseboard_fab2(sch_1):page43_i2:dqs0p" )
			)
			( pin "J4G1.163"
				( objectStatus "@baseboard_fab2_lib.baseboard_fab2(sch_1):page43_i2:dqs1n" )
			)
			( pin "J4G1.164"
				( objectStatus "@baseboard_fab2_lib.baseboard_fab2(sch_1):page43_i2:dqs1p" )
			)
			( pin "J4G1.174"
				( objectStatus "@baseboard_fab2_lib.baseboard_fab2(sch_1):page43_i2:dqs2n" )
			)
			( pin "J4G1.175"
				( objectStatus "@baseboard_fab2_lib.baseboard_fab2(sch_1):page43_i2:dqs2p" )
			)
			( pin "J4G1.185"
				( objectStatus "@baseboard_fab2_lib.baseboard_fab2(sch_1):page43_i2:dqs3n" )
			)
			( pin "J4G1.186"
				( objectStatus "@baseboard_fab2_lib.baseboard_fab2(sch_1):page43_i2:dqs3p" )
			)
			( pin "J4G1.244"
				( objectStatus "@baseboard_fab2_lib.baseboard_fab2(sch_1):page43_i2:dqs4n" )
			)
			( pin "J4G1.245"
				( objectStatus "@baseboard_fab2_lib.baseboard_fab2(sch_1):page43_i2:dqs4p" )
			)
			( pin "J4G1.255"
				( objectStatus "@baseboard_fab2_lib.baseboard_fab2(sch_1):page43_i2:dqs5n" )
			)
			( pin "J4G1.256"
				( objectStatus "@baseboard_fab2_lib.baseboard_fab2(sch_1):page43_i2:dqs5p" )
			)
			( pin "J4G1.266"
				( objectStatus "@baseboard_fab2_lib.baseboard_fab2(sch_1):page43_i2:dqs6n" )
			)
			( pin "J4G1.267"
				( objectStatus "@baseboard_fab2_lib.baseboard_fab2(sch_1):page43_i2:dqs6p" )
			)
			( pin "J4G1.277"
				( objectStatus "@baseboard_fab2_lib.baseboard_fab2(sch_1):page43_i2:dqs7n" )
			)
			( pin "J4G1.278"
				( objectStatus "@baseboard_fab2_lib.baseboard_fab2(sch_1):page43_i2:dqs7p" )
			)
			( pin "J4G1.196"
				( objectStatus "@baseboard_fab2_lib.baseboard_fab2(sch_1):page43_i2:dqs8n" )
			)
			( pin "J4G1.197"
				( objectStatus "@baseboard_fab2_lib.baseboard_fab2(sch_1):page43_i2:dqs8p" )
			)
			( pin "J4G1.8"
				( objectStatus "@baseboard_fab2_lib.baseboard_fab2(sch_1):page43_i2:dqs9n" )
			)
			( pin "J4G1.7"
				( objectStatus "@baseboard_fab2_lib.baseboard_fab2(sch_1):page43_i2:dqs9p" )
			)
			( pin "J4G1.19"
				( objectStatus "@baseboard_fab2_lib.baseboard_fab2(sch_1):page43_i2:dqs10n" )
			)
			( pin "J4G1.18"
				( objectStatus "@baseboard_fab2_lib.baseboard_fab2(sch_1):page43_i2:dqs10p" )
			)
			( pin "J4G1.30"
				( objectStatus "@baseboard_fab2_lib.baseboard_fab2(sch_1):page43_i2:dqs11n" )
			)
			( pin "J4G1.29"
				( objectStatus "@baseboard_fab2_lib.baseboard_fab2(sch_1):page43_i2:dqs11p" )
			)
			( pin "J4G1.41"
				( objectStatus "@baseboard_fab2_lib.baseboard_fab2(sch_1):page43_i2:dqs12n" )
			)
			( pin "J4G1.40"
				( objectStatus "@baseboard_fab2_lib.baseboard_fab2(sch_1):page43_i2:dqs12p" )
			)
			( pin "J4G1.100"
				( objectStatus "@baseboard_fab2_lib.baseboard_fab2(sch_1):page43_i2:dqs13n" )
			)
			( pin "J4G1.99"
				( objectStatus "@baseboard_fab2_lib.baseboard_fab2(sch_1):page43_i2:dqs13p" )
			)
			( pin "J4G1.111"
				( objectStatus "@baseboard_fab2_lib.baseboard_fab2(sch_1):page43_i2:dqs14n" )
			)
			( pin "J4G1.110"
				( objectStatus "@baseboard_fab2_lib.baseboard_fab2(sch_1):page43_i2:dqs14p" )
			)
			( pin "J4G1.122"
				( objectStatus "@baseboard_fab2_lib.baseboard_fab2(sch_1):page43_i2:dqs15n" )
			)
			( pin "J4G1.121"
				( objectStatus "@baseboard_fab2_lib.baseboard_fab2(sch_1):page43_i2:dqs15p" )
			)
			( pin "J4G1.133"
				( objectStatus "@baseboard_fab2_lib.baseboard_fab2(sch_1):page43_i2:dqs16n" )
			)
			( pin "J4G1.132"
				( objectStatus "@baseboard_fab2_lib.baseboard_fab2(sch_1):page43_i2:dqs16p" )
			)
			( pin "J4G1.52"
				( objectStatus "@baseboard_fab2_lib.baseboard_fab2(sch_1):page43_i2:dqs17n" )
			)
			( pin "J4G1.51"
				( objectStatus "@baseboard_fab2_lib.baseboard_fab2(sch_1):page43_i2:dqs17p" )
			)
			( pin "J4G1.283"
				( objectStatus "@baseboard_fab2_lib.baseboard_fab2(sch_1):page43_i259:vss(0)" )
			)
			( pin "J4G1.281"
				( objectStatus "@baseboard_fab2_lib.baseboard_fab2(sch_1):page43_i259:vss(1)" )
			)
			( pin "J4G1.279"
				( objectStatus "@baseboard_fab2_lib.baseboard_fab2(sch_1):page43_i259:vss(2)" )
			)
			( pin "J4G1.276"
				( objectStatus "@baseboard_fab2_lib.baseboard_fab2(sch_1):page43_i259:vss(3)" )
			)
			( pin "J4G1.274"
				( objectStatus "@baseboard_fab2_lib.baseboard_fab2(sch_1):page43_i259:vss(4)" )
			)
			( pin "J4G1.272"
				( objectStatus "@baseboard_fab2_lib.baseboard_fab2(sch_1):page43_i259:vss(5)" )
			)
			( pin "J4G1.270"
				( objectStatus "@baseboard_fab2_lib.baseboard_fab2(sch_1):page43_i259:vss(6)" )
			)
			( pin "J4G1.268"
				( objectStatus "@baseboard_fab2_lib.baseboard_fab2(sch_1):page43_i259:vss(7)" )
			)
			( pin "J4G1.265"
				( objectStatus "@baseboard_fab2_lib.baseboard_fab2(sch_1):page43_i259:vss(8)" )
			)
			( pin "J4G1.263"
				( objectStatus "@baseboard_fab2_lib.baseboard_fab2(sch_1):page43_i259:vss(9)" )
			)
			( pin "J4G1.261"
				( objectStatus "@baseboard_fab2_lib.baseboard_fab2(sch_1):page43_i259:vss(10)" )
			)
			( pin "J4G1.259"
				( objectStatus "@baseboard_fab2_lib.baseboard_fab2(sch_1):page43_i259:vss(11)" )
			)
			( pin "J4G1.257"
				( objectStatus "@baseboard_fab2_lib.baseboard_fab2(sch_1):page43_i259:vss(12)" )
			)
			( pin "J4G1.254"
				( objectStatus "@baseboard_fab2_lib.baseboard_fab2(sch_1):page43_i259:vss(13)" )
			)
			( pin "J4G1.252"
				( objectStatus "@baseboard_fab2_lib.baseboard_fab2(sch_1):page43_i259:vss(14)" )
			)
			( pin "J4G1.250"
				( objectStatus "@baseboard_fab2_lib.baseboard_fab2(sch_1):page43_i259:vss(15)" )
			)
			( pin "J4G1.248"
				( objectStatus "@baseboard_fab2_lib.baseboard_fab2(sch_1):page43_i259:vss(16)" )
			)
			( pin "J4G1.246"
				( objectStatus "@baseboard_fab2_lib.baseboard_fab2(sch_1):page43_i259:vss(17)" )
			)
			( pin "J4G1.243"
				( objectStatus "@baseboard_fab2_lib.baseboard_fab2(sch_1):page43_i259:vss(18)" )
			)
			( pin "J4G1.241"
				( objectStatus "@baseboard_fab2_lib.baseboard_fab2(sch_1):page43_i259:vss(19)" )
			)
			( pin "J4G1.239"
				( objectStatus "@baseboard_fab2_lib.baseboard_fab2(sch_1):page43_i259:vss(20)" )
			)
			( pin "J4G1.202"
				( objectStatus "@baseboard_fab2_lib.baseboard_fab2(sch_1):page43_i259:vss(21)" )
			)
			( pin "J4G1.200"
				( objectStatus "@baseboard_fab2_lib.baseboard_fab2(sch_1):page43_i259:vss(22)" )
			)
			( pin "J4G1.198"
				( objectStatus "@baseboard_fab2_lib.baseboard_fab2(sch_1):page43_i259:vss(23)" )
			)
			( pin "J4G1.195"
				( objectStatus "@baseboard_fab2_lib.baseboard_fab2(sch_1):page43_i259:vss(24)" )
			)
			( pin "J4G1.193"
				( objectStatus "@baseboard_fab2_lib.baseboard_fab2(sch_1):page43_i259:vss(25)" )
			)
			( pin "J4G1.191"
				( objectStatus "@baseboard_fab2_lib.baseboard_fab2(sch_1):page43_i259:vss(26)" )
			)
			( pin "J4G1.189"
				( objectStatus "@baseboard_fab2_lib.baseboard_fab2(sch_1):page43_i259:vss(27)" )
			)
			( pin "J4G1.187"
				( objectStatus "@baseboard_fab2_lib.baseboard_fab2(sch_1):page43_i259:vss(28)" )
			)
			( pin "J4G1.184"
				( objectStatus "@baseboard_fab2_lib.baseboard_fab2(sch_1):page43_i259:vss(29)" )
			)
			( pin "J4G1.182"
				( objectStatus "@baseboard_fab2_lib.baseboard_fab2(sch_1):page43_i259:vss(30)" )
			)
			( pin "J4G1.180"
				( objectStatus "@baseboard_fab2_lib.baseboard_fab2(sch_1):page43_i259:vss(31)" )
			)
			( pin "J4G1.178"
				( objectStatus "@baseboard_fab2_lib.baseboard_fab2(sch_1):page43_i259:vss(32)" )
			)
			( pin "J4G1.176"
				( objectStatus "@baseboard_fab2_lib.baseboard_fab2(sch_1):page43_i259:vss(33)" )
			)
			( pin "J4G1.173"
				( objectStatus "@baseboard_fab2_lib.baseboard_fab2(sch_1):page43_i259:vss(34)" )
			)
			( pin "J4G1.171"
				( objectStatus "@baseboard_fab2_lib.baseboard_fab2(sch_1):page43_i259:vss(35)" )
			)
			( pin "J4G1.169"
				( objectStatus "@baseboard_fab2_lib.baseboard_fab2(sch_1):page43_i259:vss(36)" )
			)
			( pin "J4G1.167"
				( objectStatus "@baseboard_fab2_lib.baseboard_fab2(sch_1):page43_i259:vss(37)" )
			)
			( pin "J4G1.165"
				( objectStatus "@baseboard_fab2_lib.baseboard_fab2(sch_1):page43_i259:vss(38)" )
			)
			( pin "J4G1.162"
				( objectStatus "@baseboard_fab2_lib.baseboard_fab2(sch_1):page43_i259:vss(39)" )
			)
			( pin "J4G1.160"
				( objectStatus "@baseboard_fab2_lib.baseboard_fab2(sch_1):page43_i259:vss(40)" )
			)
			( pin "J4G1.158"
				( objectStatus "@baseboard_fab2_lib.baseboard_fab2(sch_1):page43_i259:vss(41)" )
			)
			( pin "J4G1.156"
				( objectStatus "@baseboard_fab2_lib.baseboard_fab2(sch_1):page43_i259:vss(42)" )
			)
			( pin "J4G1.154"
				( objectStatus "@baseboard_fab2_lib.baseboard_fab2(sch_1):page43_i259:vss(43)" )
			)
			( pin "J4G1.151"
				( objectStatus "@baseboard_fab2_lib.baseboard_fab2(sch_1):page43_i259:vss(44)" )
			)
			( pin "J4G1.149"
				( objectStatus "@baseboard_fab2_lib.baseboard_fab2(sch_1):page43_i259:vss(45)" )
			)
			( pin "J4G1.147"
				( objectStatus "@baseboard_fab2_lib.baseboard_fab2(sch_1):page43_i259:vss(46)" )
			)
			( pin "J4G1.138"
				( objectStatus "@baseboard_fab2_lib.baseboard_fab2(sch_1):page43_i259:vss(47)" )
			)
			( pin "J4G1.136"
				( objectStatus "@baseboard_fab2_lib.baseboard_fab2(sch_1):page43_i259:vss(48)" )
			)
			( pin "J4G1.134"
				( objectStatus "@baseboard_fab2_lib.baseboard_fab2(sch_1):page43_i259:vss(49)" )
			)
			( pin "J4G1.131"
				( objectStatus "@baseboard_fab2_lib.baseboard_fab2(sch_1):page43_i259:vss(50)" )
			)
			( pin "J4G1.129"
				( objectStatus "@baseboard_fab2_lib.baseboard_fab2(sch_1):page43_i259:vss(51)" )
			)
			( pin "J4G1.127"
				( objectStatus "@baseboard_fab2_lib.baseboard_fab2(sch_1):page43_i259:vss(52)" )
			)
			( pin "J4G1.125"
				( objectStatus "@baseboard_fab2_lib.baseboard_fab2(sch_1):page43_i259:vss(53)" )
			)
			( pin "J4G1.123"
				( objectStatus "@baseboard_fab2_lib.baseboard_fab2(sch_1):page43_i259:vss(54)" )
			)
			( pin "J4G1.120"
				( objectStatus "@baseboard_fab2_lib.baseboard_fab2(sch_1):page43_i259:vss(55)" )
			)
			( pin "J4G1.118"
				( objectStatus "@baseboard_fab2_lib.baseboard_fab2(sch_1):page43_i259:vss(56)" )
			)
			( pin "J4G1.116"
				( objectStatus "@baseboard_fab2_lib.baseboard_fab2(sch_1):page43_i259:vss(57)" )
			)
			( pin "J4G1.114"
				( objectStatus "@baseboard_fab2_lib.baseboard_fab2(sch_1):page43_i259:vss(58)" )
			)
			( pin "J4G1.112"
				( objectStatus "@baseboard_fab2_lib.baseboard_fab2(sch_1):page43_i259:vss(59)" )
			)
			( pin "J4G1.109"
				( objectStatus "@baseboard_fab2_lib.baseboard_fab2(sch_1):page43_i259:vss(60)" )
			)
			( pin "J4G1.107"
				( objectStatus "@baseboard_fab2_lib.baseboard_fab2(sch_1):page43_i259:vss(61)" )
			)
			( pin "J4G1.105"
				( objectStatus "@baseboard_fab2_lib.baseboard_fab2(sch_1):page43_i259:vss(62)" )
			)
			( pin "J4G1.103"
				( objectStatus "@baseboard_fab2_lib.baseboard_fab2(sch_1):page43_i259:vss(63)" )
			)
			( pin "J4G1.101"
				( objectStatus "@baseboard_fab2_lib.baseboard_fab2(sch_1):page43_i259:vss(64)" )
			)
			( pin "J4G1.98"
				( objectStatus "@baseboard_fab2_lib.baseboard_fab2(sch_1):page43_i259:vss(65)" )
			)
			( pin "J4G1.96"
				( objectStatus "@baseboard_fab2_lib.baseboard_fab2(sch_1):page43_i259:vss(66)" )
			)
			( pin "J4G1.94"
				( objectStatus "@baseboard_fab2_lib.baseboard_fab2(sch_1):page43_i259:vss(67)" )
			)
			( pin "J4G1.57"
				( objectStatus "@baseboard_fab2_lib.baseboard_fab2(sch_1):page43_i259:vss(68)" )
			)
			( pin "J4G1.55"
				( objectStatus "@baseboard_fab2_lib.baseboard_fab2(sch_1):page43_i259:vss(69)" )
			)
			( pin "J4G1.53"
				( objectStatus "@baseboard_fab2_lib.baseboard_fab2(sch_1):page43_i259:vss(70)" )
			)
			( pin "J4G1.50"
				( objectStatus "@baseboard_fab2_lib.baseboard_fab2(sch_1):page43_i259:vss(71)" )
			)
			( pin "J4G1.48"
				( objectStatus "@baseboard_fab2_lib.baseboard_fab2(sch_1):page43_i259:vss(72)" )
			)
			( pin "J4G1.46"
				( objectStatus "@baseboard_fab2_lib.baseboard_fab2(sch_1):page43_i259:vss(73)" )
			)
			( pin "J4G1.44"
				( objectStatus "@baseboard_fab2_lib.baseboard_fab2(sch_1):page43_i259:vss(74)" )
			)
			( pin "J4G1.42"
				( objectStatus "@baseboard_fab2_lib.baseboard_fab2(sch_1):page43_i259:vss(75)" )
			)
			( pin "J4G1.39"
				( objectStatus "@baseboard_fab2_lib.baseboard_fab2(sch_1):page43_i259:vss(76)" )
			)
			( pin "J4G1.37"
				( objectStatus "@baseboard_fab2_lib.baseboard_fab2(sch_1):page43_i259:vss(77)" )
			)
			( pin "J4G1.35"
				( objectStatus "@baseboard_fab2_lib.baseboard_fab2(sch_1):page43_i259:vss(78)" )
			)
			( pin "J4G1.33"
				( objectStatus "@baseboard_fab2_lib.baseboard_fab2(sch_1):page43_i259:vss(79)" )
			)
			( pin "J4G1.31"
				( objectStatus "@baseboard_fab2_lib.baseboard_fab2(sch_1):page43_i259:vss(80)" )
			)
			( pin "J4G1.28"
				( objectStatus "@baseboard_fab2_lib.baseboard_fab2(sch_1):page43_i259:vss(81)" )
			)
			( pin "J4G1.26"
				( objectStatus "@baseboard_fab2_lib.baseboard_fab2(sch_1):page43_i259:vss(82)" )
			)
			( pin "J4G1.24"
				( objectStatus "@baseboard_fab2_lib.baseboard_fab2(sch_1):page43_i259:vss(83)" )
			)
			( pin "J4G1.22"
				( objectStatus "@baseboard_fab2_lib.baseboard_fab2(sch_1):page43_i259:vss(84)" )
			)
			( pin "J4G1.20"
				( objectStatus "@baseboard_fab2_lib.baseboard_fab2(sch_1):page43_i259:vss(85)" )
			)
			( pin "J4G1.17"
				( objectStatus "@baseboard_fab2_lib.baseboard_fab2(sch_1):page43_i259:vss(86)" )
			)
			( pin "J4G1.15"
				( objectStatus "@baseboard_fab2_lib.baseboard_fab2(sch_1):page43_i259:vss(87)" )
			)
			( pin "J4G1.13"
				( objectStatus "@baseboard_fab2_lib.baseboard_fab2(sch_1):page43_i259:vss(88)" )
			)
			( pin "J4G1.11"
				( objectStatus "@baseboard_fab2_lib.baseboard_fab2(sch_1):page43_i259:vss(89)" )
			)
			( pin "J4G1.9"
				( objectStatus "@baseboard_fab2_lib.baseboard_fab2(sch_1):page43_i259:vss(90)" )
			)
			( pin "J4G1.6"
				( objectStatus "@baseboard_fab2_lib.baseboard_fab2(sch_1):page43_i259:vss(91)" )
			)
			( pin "J4G1.4"
				( objectStatus "@baseboard_fab2_lib.baseboard_fab2(sch_1):page43_i259:vss(92)" )
			)
			( pin "J4G1.2"
				( objectStatus "@baseboard_fab2_lib.baseboard_fab2(sch_1):page43_i259:vss(93)" )
			)
			( pin "J4G1.145"
				( objectStatus "@baseboard_fab2_lib.baseboard_fab2(sch_1):page43_i260:\12v\(0)" )
			)
			( pin "J4G1.1"
				( objectStatus "@baseboard_fab2_lib.baseboard_fab2(sch_1):page43_i260:\12v\(1)" )
			)
			( pin "J4G1.236"
				( objectStatus "@baseboard_fab2_lib.baseboard_fab2(sch_1):page43_i260:vdd(0)" )
			)
			( pin "J4G1.233"
				( objectStatus "@baseboard_fab2_lib.baseboard_fab2(sch_1):page43_i260:vdd(1)" )
			)
			( pin "J4G1.231"
				( objectStatus "@baseboard_fab2_lib.baseboard_fab2(sch_1):page43_i260:vdd(2)" )
			)
			( pin "J4G1.229"
				( objectStatus "@baseboard_fab2_lib.baseboard_fab2(sch_1):page43_i260:vdd(3)" )
			)
			( pin "J4G1.226"
				( objectStatus "@baseboard_fab2_lib.baseboard_fab2(sch_1):page43_i260:vdd(4)" )
			)
			( pin "J4G1.223"
				( objectStatus "@baseboard_fab2_lib.baseboard_fab2(sch_1):page43_i260:vdd(5)" )
			)
			( pin "J4G1.220"
				( objectStatus "@baseboard_fab2_lib.baseboard_fab2(sch_1):page43_i260:vdd(6)" )
			)
			( pin "J4G1.217"
				( objectStatus "@baseboard_fab2_lib.baseboard_fab2(sch_1):page43_i260:vdd(7)" )
			)
			( pin "J4G1.215"
				( objectStatus "@baseboard_fab2_lib.baseboard_fab2(sch_1):page43_i260:vdd(8)" )
			)
			( pin "J4G1.212"
				( objectStatus "@baseboard_fab2_lib.baseboard_fab2(sch_1):page43_i260:vdd(9)" )
			)
			( pin "J4G1.209"
				( objectStatus "@baseboard_fab2_lib.baseboard_fab2(sch_1):page43_i260:vdd(10)" )
			)
			( pin "J4G1.206"
				( objectStatus "@baseboard_fab2_lib.baseboard_fab2(sch_1):page43_i260:vdd(11)" )
			)
			( pin "J4G1.204"
				( objectStatus "@baseboard_fab2_lib.baseboard_fab2(sch_1):page43_i260:vdd(12)" )
			)
			( pin "J4G1.92"
				( objectStatus "@baseboard_fab2_lib.baseboard_fab2(sch_1):page43_i260:vdd(13)" )
			)
			( pin "J4G1.90"
				( objectStatus "@baseboard_fab2_lib.baseboard_fab2(sch_1):page43_i260:vdd(14)" )
			)
			( pin "J4G1.88"
				( objectStatus "@baseboard_fab2_lib.baseboard_fab2(sch_1):page43_i260:vdd(15)" )
			)
			( pin "J4G1.85"
				( objectStatus "@baseboard_fab2_lib.baseboard_fab2(sch_1):page43_i260:vdd(16)" )
			)
			( pin "J4G1.83"
				( objectStatus "@baseboard_fab2_lib.baseboard_fab2(sch_1):page43_i260:vdd(17)" )
			)
			( pin "J4G1.80"
				( objectStatus "@baseboard_fab2_lib.baseboard_fab2(sch_1):page43_i260:vdd(18)" )
			)
			( pin "J4G1.76"
				( objectStatus "@baseboard_fab2_lib.baseboard_fab2(sch_1):page43_i260:vdd(19)" )
			)
			( pin "J4G1.73"
				( objectStatus "@baseboard_fab2_lib.baseboard_fab2(sch_1):page43_i260:vdd(20)" )
			)
			( pin "J4G1.70"
				( objectStatus "@baseboard_fab2_lib.baseboard_fab2(sch_1):page43_i260:vdd(21)" )
			)
			( pin "J4G1.67"
				( objectStatus "@baseboard_fab2_lib.baseboard_fab2(sch_1):page43_i260:vdd(22)" )
			)
			( pin "J4G1.64"
				( objectStatus "@baseboard_fab2_lib.baseboard_fab2(sch_1):page43_i260:vdd(23)" )
			)
			( pin "J4G1.61"
				( objectStatus "@baseboard_fab2_lib.baseboard_fab2(sch_1):page43_i260:vdd(24)" )
			)
			( pin "J4G1.59"
				( objectStatus "@baseboard_fab2_lib.baseboard_fab2(sch_1):page43_i260:vdd(25)" )
			)
			( pin "J4G1.287"
				( objectStatus "@baseboard_fab2_lib.baseboard_fab2(sch_1):page43_i260:vpp(0)" )
			)
			( pin "J4G1.286"
				( objectStatus "@baseboard_fab2_lib.baseboard_fab2(sch_1):page43_i260:vpp(1)" )
			)
			( pin "J4G1.288"
				( objectStatus "@baseboard_fab2_lib.baseboard_fab2(sch_1):page43_i260:vpp(2)" )
			)
			( pin "J4G1.143"
				( objectStatus "@baseboard_fab2_lib.baseboard_fab2(sch_1):page43_i260:vpp(3)" )
			)
			( pin "J4G1.142"
				( objectStatus "@baseboard_fab2_lib.baseboard_fab2(sch_1):page43_i260:vpp(4)" )
			)
			( pin "J4G1.221"
				( objectStatus "@baseboard_fab2_lib.baseboard_fab2(sch_1):page43_i260:vtt(0)" )
			)
			( pin "J4G1.77"
				( objectStatus "@baseboard_fab2_lib.baseboard_fab2(sch_1):page43_i260:vtt(1)" )
			)
			( pin "C4F10.1"
				( objectStatus "@baseboard_fab2_lib.baseboard_fab2(sch_1):page43_i272:a" )
			)
			( pin "C4F10.2"
				( objectStatus "@baseboard_fab2_lib.baseboard_fab2(sch_1):page43_i272:b" )
			)
			( pin "C6T1.1"
				( objectStatus "@baseboard_fab2_lib.baseboard_fab2(sch_1):page44_i2:a" )
			)
			( pin "C6T1.2"
				( objectStatus "@baseboard_fab2_lib.baseboard_fab2(sch_1):page44_i2:b" )
			)
			( pin "J6T1.79"
				( objectStatus "@baseboard_fab2_lib.baseboard_fab2(sch_1):page44_i13:a0" )
			)
			( pin "J6T1.72"
				( objectStatus "@baseboard_fab2_lib.baseboard_fab2(sch_1):page44_i13:a1" )
			)
			( pin "J6T1.216"
				( objectStatus "@baseboard_fab2_lib.baseboard_fab2(sch_1):page44_i13:a2" )
			)
			( pin "J6T1.71"
				( objectStatus "@baseboard_fab2_lib.baseboard_fab2(sch_1):page44_i13:a3" )
			)
			( pin "J6T1.214"
				( objectStatus "@baseboard_fab2_lib.baseboard_fab2(sch_1):page44_i13:a4" )
			)
			( pin "J6T1.213"
				( objectStatus "@baseboard_fab2_lib.baseboard_fab2(sch_1):page44_i13:a5" )
			)
			( pin "J6T1.69"
				( objectStatus "@baseboard_fab2_lib.baseboard_fab2(sch_1):page44_i13:a6" )
			)
			( pin "J6T1.211"
				( objectStatus "@baseboard_fab2_lib.baseboard_fab2(sch_1):page44_i13:a7" )
			)
			( pin "J6T1.68"
				( objectStatus "@baseboard_fab2_lib.baseboard_fab2(sch_1):page44_i13:a8" )
			)
			( pin "J6T1.66"
				( objectStatus "@baseboard_fab2_lib.baseboard_fab2(sch_1):page44_i13:a9" )
			)
			( pin "J6T1.225"
				( objectStatus "@baseboard_fab2_lib.baseboard_fab2(sch_1):page44_i13:a10" )
			)
			( pin "J6T1.210"
				( objectStatus "@baseboard_fab2_lib.baseboard_fab2(sch_1):page44_i13:a11" )
			)
			( pin "J6T1.65"
				( objectStatus "@baseboard_fab2_lib.baseboard_fab2(sch_1):page44_i13:a12" )
			)
			( pin "J6T1.232"
				( objectStatus "@baseboard_fab2_lib.baseboard_fab2(sch_1):page44_i13:a13" )
			)
			( pin "J6T1.228"
				( objectStatus "@baseboard_fab2_lib.baseboard_fab2(sch_1):page44_i13:a14_we_n" )
			)
			( pin "J6T1.86"
				( objectStatus "@baseboard_fab2_lib.baseboard_fab2(sch_1):page44_i13:a15_cas_n" )
			)
			( pin "J6T1.82"
				( objectStatus "@baseboard_fab2_lib.baseboard_fab2(sch_1):page44_i13:a16_ras_n" )
			)
			( pin "J6T1.234"
				( objectStatus "@baseboard_fab2_lib.baseboard_fab2(sch_1):page44_i13:a17" )
			)
			( pin "J6T1.62"
				( objectStatus "@baseboard_fab2_lib.baseboard_fab2(sch_1):page44_i13:act_n" )
			)
			( pin "J6T1.208"
				( objectStatus "@baseboard_fab2_lib.baseboard_fab2(sch_1):page44_i13:alert_n" )
			)
			( pin "J6T1.81"
				( objectStatus "@baseboard_fab2_lib.baseboard_fab2(sch_1):page44_i13:ba(0)" )
			)
			( pin "J6T1.224"
				( objectStatus "@baseboard_fab2_lib.baseboard_fab2(sch_1):page44_i13:ba(1)" )
			)
			( pin "J6T1.63"
				( objectStatus "@baseboard_fab2_lib.baseboard_fab2(sch_1):page44_i13:bg(0)" )
			)
			( pin "J6T1.207"
				( objectStatus "@baseboard_fab2_lib.baseboard_fab2(sch_1):page44_i13:bg(1)" )
			)
			( pin "J6T1.235"
				( objectStatus "@baseboard_fab2_lib.baseboard_fab2(sch_1):page44_i13:c(2)" )
			)
			( pin "J6T1.49"
				( objectStatus "@baseboard_fab2_lib.baseboard_fab2(sch_1):page44_i13:cb(0)" )
			)
			( pin "J6T1.194"
				( objectStatus "@baseboard_fab2_lib.baseboard_fab2(sch_1):page44_i13:cb(1)" )
			)
			( pin "J6T1.56"
				( objectStatus "@baseboard_fab2_lib.baseboard_fab2(sch_1):page44_i13:cb(2)" )
			)
			( pin "J6T1.201"
				( objectStatus "@baseboard_fab2_lib.baseboard_fab2(sch_1):page44_i13:cb(3)" )
			)
			( pin "J6T1.47"
				( objectStatus "@baseboard_fab2_lib.baseboard_fab2(sch_1):page44_i13:cb(4)" )
			)
			( pin "J6T1.192"
				( objectStatus "@baseboard_fab2_lib.baseboard_fab2(sch_1):page44_i13:cb(5)" )
			)
			( pin "J6T1.54"
				( objectStatus "@baseboard_fab2_lib.baseboard_fab2(sch_1):page44_i13:cb(6)" )
			)
			( pin "J6T1.199"
				( objectStatus "@baseboard_fab2_lib.baseboard_fab2(sch_1):page44_i13:cb(7)" )
			)
			( pin "J6T1.75"
				( objectStatus "@baseboard_fab2_lib.baseboard_fab2(sch_1):page44_i13:ck0n" )
			)
			( pin "J6T1.74"
				( objectStatus "@baseboard_fab2_lib.baseboard_fab2(sch_1):page44_i13:ck0p" )
			)
			( pin "J6T1.219"
				( objectStatus "@baseboard_fab2_lib.baseboard_fab2(sch_1):page44_i13:ck1n" )
			)
			( pin "J6T1.218"
				( objectStatus "@baseboard_fab2_lib.baseboard_fab2(sch_1):page44_i13:ck1p" )
			)
			( pin "J6T1.60"
				( objectStatus "@baseboard_fab2_lib.baseboard_fab2(sch_1):page44_i13:cke(0)" )
			)
			( pin "J6T1.203"
				( objectStatus "@baseboard_fab2_lib.baseboard_fab2(sch_1):page44_i13:cke(1)" )
			)
			( pin "J6T1.5"
				( objectStatus "@baseboard_fab2_lib.baseboard_fab2(sch_1):page44_i13:dq(0)" )
			)
			( pin "J6T1.150"
				( objectStatus "@baseboard_fab2_lib.baseboard_fab2(sch_1):page44_i13:dq(1)" )
			)
			( pin "J6T1.12"
				( objectStatus "@baseboard_fab2_lib.baseboard_fab2(sch_1):page44_i13:dq(2)" )
			)
			( pin "J6T1.157"
				( objectStatus "@baseboard_fab2_lib.baseboard_fab2(sch_1):page44_i13:dq(3)" )
			)
			( pin "J6T1.3"
				( objectStatus "@baseboard_fab2_lib.baseboard_fab2(sch_1):page44_i13:dq(4)" )
			)
			( pin "J6T1.148"
				( objectStatus "@baseboard_fab2_lib.baseboard_fab2(sch_1):page44_i13:dq(5)" )
			)
			( pin "J6T1.10"
				( objectStatus "@baseboard_fab2_lib.baseboard_fab2(sch_1):page44_i13:dq(6)" )
			)
			( pin "J6T1.155"
				( objectStatus "@baseboard_fab2_lib.baseboard_fab2(sch_1):page44_i13:dq(7)" )
			)
			( pin "J6T1.16"
				( objectStatus "@baseboard_fab2_lib.baseboard_fab2(sch_1):page44_i13:dq(8)" )
			)
			( pin "J6T1.161"
				( objectStatus "@baseboard_fab2_lib.baseboard_fab2(sch_1):page44_i13:dq(9)" )
			)
			( pin "J6T1.23"
				( objectStatus "@baseboard_fab2_lib.baseboard_fab2(sch_1):page44_i13:dq(10)" )
			)
			( pin "J6T1.168"
				( objectStatus "@baseboard_fab2_lib.baseboard_fab2(sch_1):page44_i13:dq(11)" )
			)
			( pin "J6T1.14"
				( objectStatus "@baseboard_fab2_lib.baseboard_fab2(sch_1):page44_i13:dq(12)" )
			)
			( pin "J6T1.159"
				( objectStatus "@baseboard_fab2_lib.baseboard_fab2(sch_1):page44_i13:dq(13)" )
			)
			( pin "J6T1.21"
				( objectStatus "@baseboard_fab2_lib.baseboard_fab2(sch_1):page44_i13:dq(14)" )
			)
			( pin "J6T1.166"
				( objectStatus "@baseboard_fab2_lib.baseboard_fab2(sch_1):page44_i13:dq(15)" )
			)
			( pin "J6T1.27"
				( objectStatus "@baseboard_fab2_lib.baseboard_fab2(sch_1):page44_i13:dq(16)" )
			)
			( pin "J6T1.172"
				( objectStatus "@baseboard_fab2_lib.baseboard_fab2(sch_1):page44_i13:dq(17)" )
			)
			( pin "J6T1.34"
				( objectStatus "@baseboard_fab2_lib.baseboard_fab2(sch_1):page44_i13:dq(18)" )
			)
			( pin "J6T1.179"
				( objectStatus "@baseboard_fab2_lib.baseboard_fab2(sch_1):page44_i13:dq(19)" )
			)
			( pin "J6T1.25"
				( objectStatus "@baseboard_fab2_lib.baseboard_fab2(sch_1):page44_i13:dq(20)" )
			)
			( pin "J6T1.170"
				( objectStatus "@baseboard_fab2_lib.baseboard_fab2(sch_1):page44_i13:dq(21)" )
			)
			( pin "J6T1.32"
				( objectStatus "@baseboard_fab2_lib.baseboard_fab2(sch_1):page44_i13:dq(22)" )
			)
			( pin "J6T1.177"
				( objectStatus "@baseboard_fab2_lib.baseboard_fab2(sch_1):page44_i13:dq(23)" )
			)
			( pin "J6T1.38"
				( objectStatus "@baseboard_fab2_lib.baseboard_fab2(sch_1):page44_i13:dq(24)" )
			)
			( pin "J6T1.183"
				( objectStatus "@baseboard_fab2_lib.baseboard_fab2(sch_1):page44_i13:dq(25)" )
			)
			( pin "J6T1.45"
				( objectStatus "@baseboard_fab2_lib.baseboard_fab2(sch_1):page44_i13:dq(26)" )
			)
			( pin "J6T1.190"
				( objectStatus "@baseboard_fab2_lib.baseboard_fab2(sch_1):page44_i13:dq(27)" )
			)
			( pin "J6T1.36"
				( objectStatus "@baseboard_fab2_lib.baseboard_fab2(sch_1):page44_i13:dq(28)" )
			)
			( pin "J6T1.181"
				( objectStatus "@baseboard_fab2_lib.baseboard_fab2(sch_1):page44_i13:dq(29)" )
			)
			( pin "J6T1.43"
				( objectStatus "@baseboard_fab2_lib.baseboard_fab2(sch_1):page44_i13:dq(30)" )
			)
			( pin "J6T1.188"
				( objectStatus "@baseboard_fab2_lib.baseboard_fab2(sch_1):page44_i13:dq(31)" )
			)
			( pin "J6T1.97"
				( objectStatus "@baseboard_fab2_lib.baseboard_fab2(sch_1):page44_i13:dq(32)" )
			)
			( pin "J6T1.242"
				( objectStatus "@baseboard_fab2_lib.baseboard_fab2(sch_1):page44_i13:dq(33)" )
			)
			( pin "J6T1.104"
				( objectStatus "@baseboard_fab2_lib.baseboard_fab2(sch_1):page44_i13:dq(34)" )
			)
			( pin "J6T1.249"
				( objectStatus "@baseboard_fab2_lib.baseboard_fab2(sch_1):page44_i13:dq(35)" )
			)
			( pin "J6T1.95"
				( objectStatus "@baseboard_fab2_lib.baseboard_fab2(sch_1):page44_i13:dq(36)" )
			)
			( pin "J6T1.240"
				( objectStatus "@baseboard_fab2_lib.baseboard_fab2(sch_1):page44_i13:dq(37)" )
			)
			( pin "J6T1.102"
				( objectStatus "@baseboard_fab2_lib.baseboard_fab2(sch_1):page44_i13:dq(38)" )
			)
			( pin "J6T1.247"
				( objectStatus "@baseboard_fab2_lib.baseboard_fab2(sch_1):page44_i13:dq(39)" )
			)
			( pin "J6T1.108"
				( objectStatus "@baseboard_fab2_lib.baseboard_fab2(sch_1):page44_i13:dq(40)" )
			)
			( pin "J6T1.253"
				( objectStatus "@baseboard_fab2_lib.baseboard_fab2(sch_1):page44_i13:dq(41)" )
			)
			( pin "J6T1.115"
				( objectStatus "@baseboard_fab2_lib.baseboard_fab2(sch_1):page44_i13:dq(42)" )
			)
			( pin "J6T1.260"
				( objectStatus "@baseboard_fab2_lib.baseboard_fab2(sch_1):page44_i13:dq(43)" )
			)
			( pin "J6T1.106"
				( objectStatus "@baseboard_fab2_lib.baseboard_fab2(sch_1):page44_i13:dq(44)" )
			)
			( pin "J6T1.251"
				( objectStatus "@baseboard_fab2_lib.baseboard_fab2(sch_1):page44_i13:dq(45)" )
			)
			( pin "J6T1.113"
				( objectStatus "@baseboard_fab2_lib.baseboard_fab2(sch_1):page44_i13:dq(46)" )
			)
			( pin "J6T1.258"
				( objectStatus "@baseboard_fab2_lib.baseboard_fab2(sch_1):page44_i13:dq(47)" )
			)
			( pin "J6T1.119"
				( objectStatus "@baseboard_fab2_lib.baseboard_fab2(sch_1):page44_i13:dq(48)" )
			)
			( pin "J6T1.264"
				( objectStatus "@baseboard_fab2_lib.baseboard_fab2(sch_1):page44_i13:dq(49)" )
			)
			( pin "J6T1.126"
				( objectStatus "@baseboard_fab2_lib.baseboard_fab2(sch_1):page44_i13:dq(50)" )
			)
			( pin "J6T1.271"
				( objectStatus "@baseboard_fab2_lib.baseboard_fab2(sch_1):page44_i13:dq(51)" )
			)
			( pin "J6T1.117"
				( objectStatus "@baseboard_fab2_lib.baseboard_fab2(sch_1):page44_i13:dq(52)" )
			)
			( pin "J6T1.262"
				( objectStatus "@baseboard_fab2_lib.baseboard_fab2(sch_1):page44_i13:dq(53)" )
			)
			( pin "J6T1.124"
				( objectStatus "@baseboard_fab2_lib.baseboard_fab2(sch_1):page44_i13:dq(54)" )
			)
			( pin "J6T1.269"
				( objectStatus "@baseboard_fab2_lib.baseboard_fab2(sch_1):page44_i13:dq(55)" )
			)
			( pin "J6T1.130"
				( objectStatus "@baseboard_fab2_lib.baseboard_fab2(sch_1):page44_i13:dq(56)" )
			)
			( pin "J6T1.275"
				( objectStatus "@baseboard_fab2_lib.baseboard_fab2(sch_1):page44_i13:dq(57)" )
			)
			( pin "J6T1.137"
				( objectStatus "@baseboard_fab2_lib.baseboard_fab2(sch_1):page44_i13:dq(58)" )
			)
			( pin "J6T1.282"
				( objectStatus "@baseboard_fab2_lib.baseboard_fab2(sch_1):page44_i13:dq(59)" )
			)
			( pin "J6T1.128"
				( objectStatus "@baseboard_fab2_lib.baseboard_fab2(sch_1):page44_i13:dq(60)" )
			)
			( pin "J6T1.273"
				( objectStatus "@baseboard_fab2_lib.baseboard_fab2(sch_1):page44_i13:dq(61)" )
			)
			( pin "J6T1.135"
				( objectStatus "@baseboard_fab2_lib.baseboard_fab2(sch_1):page44_i13:dq(62)" )
			)
			( pin "J6T1.280"
				( objectStatus "@baseboard_fab2_lib.baseboard_fab2(sch_1):page44_i13:dq(63)" )
			)
			( pin "J6T1.78"
				( objectStatus "@baseboard_fab2_lib.baseboard_fab2(sch_1):page44_i13:event_n" )
			)
			( pin "J6T1.87"
				( objectStatus "@baseboard_fab2_lib.baseboard_fab2(sch_1):page44_i13:odt(0)" )
			)
			( pin "J6T1.91"
				( objectStatus "@baseboard_fab2_lib.baseboard_fab2(sch_1):page44_i13:odt(1)" )
			)
			( pin "J6T1.222"
				( objectStatus "@baseboard_fab2_lib.baseboard_fab2(sch_1):page44_i13:par" )
			)
			( pin "J6T1.58"
				( objectStatus "@baseboard_fab2_lib.baseboard_fab2(sch_1):page44_i13:reset_n" )
			)
			( pin "J6T1.205"
				( objectStatus "@baseboard_fab2_lib.baseboard_fab2(sch_1):page44_i13:rfu(0)" )
			)
			( pin "J6T1.227"
				( objectStatus "@baseboard_fab2_lib.baseboard_fab2(sch_1):page44_i13:rfu(1)" )
			)
			( pin "J6T1.144"
				( objectStatus "@baseboard_fab2_lib.baseboard_fab2(sch_1):page44_i13:rfu(2)" )
			)
			( pin "J6T1.84"
				( objectStatus "@baseboard_fab2_lib.baseboard_fab2(sch_1):page44_i13:s0_n" )
			)
			( pin "J6T1.89"
				( objectStatus "@baseboard_fab2_lib.baseboard_fab2(sch_1):page44_i13:s1_n" )
			)
			( pin "J6T1.93"
				( objectStatus "@baseboard_fab2_lib.baseboard_fab2(sch_1):page44_i13:s2_n_c(0)" )
			)
			( pin "J6T1.237"
				( objectStatus "@baseboard_fab2_lib.baseboard_fab2(sch_1):page44_i13:s3_n_c(1)" )
			)
			( pin "J6T1.139"
				( objectStatus "@baseboard_fab2_lib.baseboard_fab2(sch_1):page44_i13:sa(0)" )
			)
			( pin "J6T1.140"
				( objectStatus "@baseboard_fab2_lib.baseboard_fab2(sch_1):page44_i13:sa(1)" )
			)
			( pin "J6T1.238"
				( objectStatus "@baseboard_fab2_lib.baseboard_fab2(sch_1):page44_i13:sa(2)" )
			)
			( pin "J6T1.230"
				( objectStatus "@baseboard_fab2_lib.baseboard_fab2(sch_1):page44_i13:save_n_nc" )
			)
			( pin "J6T1.141"
				( objectStatus "@baseboard_fab2_lib.baseboard_fab2(sch_1):page44_i13:scl" )
			)
			( pin "J6T1.285"
				( objectStatus "@baseboard_fab2_lib.baseboard_fab2(sch_1):page44_i13:sda" )
			)
			( pin "J6T1.284"
				( objectStatus "@baseboard_fab2_lib.baseboard_fab2(sch_1):page44_i13:vddspd" )
			)
			( pin "J6T1.146"
				( objectStatus "@baseboard_fab2_lib.baseboard_fab2(sch_1):page44_i13:vrefca" )
			)
			( pin "J6T1.145"
				( objectStatus "@baseboard_fab2_lib.baseboard_fab2(sch_1):page44_i75:\12v\(0)" )
			)
			( pin "J6T1.1"
				( objectStatus "@baseboard_fab2_lib.baseboard_fab2(sch_1):page44_i75:\12v\(1)" )
			)
			( pin "J6T1.236"
				( objectStatus "@baseboard_fab2_lib.baseboard_fab2(sch_1):page44_i75:vdd(0)" )
			)
			( pin "J6T1.233"
				( objectStatus "@baseboard_fab2_lib.baseboard_fab2(sch_1):page44_i75:vdd(1)" )
			)
			( pin "J6T1.231"
				( objectStatus "@baseboard_fab2_lib.baseboard_fab2(sch_1):page44_i75:vdd(2)" )
			)
			( pin "J6T1.229"
				( objectStatus "@baseboard_fab2_lib.baseboard_fab2(sch_1):page44_i75:vdd(3)" )
			)
			( pin "J6T1.226"
				( objectStatus "@baseboard_fab2_lib.baseboard_fab2(sch_1):page44_i75:vdd(4)" )
			)
			( pin "J6T1.223"
				( objectStatus "@baseboard_fab2_lib.baseboard_fab2(sch_1):page44_i75:vdd(5)" )
			)
			( pin "J6T1.220"
				( objectStatus "@baseboard_fab2_lib.baseboard_fab2(sch_1):page44_i75:vdd(6)" )
			)
			( pin "J6T1.217"
				( objectStatus "@baseboard_fab2_lib.baseboard_fab2(sch_1):page44_i75:vdd(7)" )
			)
			( pin "J6T1.215"
				( objectStatus "@baseboard_fab2_lib.baseboard_fab2(sch_1):page44_i75:vdd(8)" )
			)
			( pin "J6T1.212"
				( objectStatus "@baseboard_fab2_lib.baseboard_fab2(sch_1):page44_i75:vdd(9)" )
			)
			( pin "J6T1.209"
				( objectStatus "@baseboard_fab2_lib.baseboard_fab2(sch_1):page44_i75:vdd(10)" )
			)
			( pin "J6T1.206"
				( objectStatus "@baseboard_fab2_lib.baseboard_fab2(sch_1):page44_i75:vdd(11)" )
			)
			( pin "J6T1.204"
				( objectStatus "@baseboard_fab2_lib.baseboard_fab2(sch_1):page44_i75:vdd(12)" )
			)
			( pin "J6T1.92"
				( objectStatus "@baseboard_fab2_lib.baseboard_fab2(sch_1):page44_i75:vdd(13)" )
			)
			( pin "J6T1.90"
				( objectStatus "@baseboard_fab2_lib.baseboard_fab2(sch_1):page44_i75:vdd(14)" )
			)
			( pin "J6T1.88"
				( objectStatus "@baseboard_fab2_lib.baseboard_fab2(sch_1):page44_i75:vdd(15)" )
			)
			( pin "J6T1.85"
				( objectStatus "@baseboard_fab2_lib.baseboard_fab2(sch_1):page44_i75:vdd(16)" )
			)
			( pin "J6T1.83"
				( objectStatus "@baseboard_fab2_lib.baseboard_fab2(sch_1):page44_i75:vdd(17)" )
			)
			( pin "J6T1.80"
				( objectStatus "@baseboard_fab2_lib.baseboard_fab2(sch_1):page44_i75:vdd(18)" )
			)
			( pin "J6T1.76"
				( objectStatus "@baseboard_fab2_lib.baseboard_fab2(sch_1):page44_i75:vdd(19)" )
			)
			( pin "J6T1.73"
				( objectStatus "@baseboard_fab2_lib.baseboard_fab2(sch_1):page44_i75:vdd(20)" )
			)
			( pin "J6T1.70"
				( objectStatus "@baseboard_fab2_lib.baseboard_fab2(sch_1):page44_i75:vdd(21)" )
			)
			( pin "J6T1.67"
				( objectStatus "@baseboard_fab2_lib.baseboard_fab2(sch_1):page44_i75:vdd(22)" )
			)
			( pin "J6T1.64"
				( objectStatus "@baseboard_fab2_lib.baseboard_fab2(sch_1):page44_i75:vdd(23)" )
			)
			( pin "J6T1.61"
				( objectStatus "@baseboard_fab2_lib.baseboard_fab2(sch_1):page44_i75:vdd(24)" )
			)
			( pin "J6T1.59"
				( objectStatus "@baseboard_fab2_lib.baseboard_fab2(sch_1):page44_i75:vdd(25)" )
			)
			( pin "J6T1.287"
				( objectStatus "@baseboard_fab2_lib.baseboard_fab2(sch_1):page44_i75:vpp(0)" )
			)
			( pin "J6T1.286"
				( objectStatus "@baseboard_fab2_lib.baseboard_fab2(sch_1):page44_i75:vpp(1)" )
			)
			( pin "J6T1.288"
				( objectStatus "@baseboard_fab2_lib.baseboard_fab2(sch_1):page44_i75:vpp(2)" )
			)
			( pin "J6T1.143"
				( objectStatus "@baseboard_fab2_lib.baseboard_fab2(sch_1):page44_i75:vpp(3)" )
			)
			( pin "J6T1.142"
				( objectStatus "@baseboard_fab2_lib.baseboard_fab2(sch_1):page44_i75:vpp(4)" )
			)
			( pin "J6T1.221"
				( objectStatus "@baseboard_fab2_lib.baseboard_fab2(sch_1):page44_i75:vtt(0)" )
			)
			( pin "J6T1.77"
				( objectStatus "@baseboard_fab2_lib.baseboard_fab2(sch_1):page44_i75:vtt(1)" )
			)
			( pin "J6T1.152"
				( objectStatus "@baseboard_fab2_lib.baseboard_fab2(sch_1):page44_i120:dqs0n" )
			)
			( pin "J6T1.153"
				( objectStatus "@baseboard_fab2_lib.baseboard_fab2(sch_1):page44_i120:dqs0p" )
			)
			( pin "J6T1.163"
				( objectStatus "@baseboard_fab2_lib.baseboard_fab2(sch_1):page44_i120:dqs1n" )
			)
			( pin "J6T1.164"
				( objectStatus "@baseboard_fab2_lib.baseboard_fab2(sch_1):page44_i120:dqs1p" )
			)
			( pin "J6T1.174"
				( objectStatus "@baseboard_fab2_lib.baseboard_fab2(sch_1):page44_i120:dqs2n" )
			)
			( pin "J6T1.175"
				( objectStatus "@baseboard_fab2_lib.baseboard_fab2(sch_1):page44_i120:dqs2p" )
			)
			( pin "J6T1.185"
				( objectStatus "@baseboard_fab2_lib.baseboard_fab2(sch_1):page44_i120:dqs3n" )
			)
			( pin "J6T1.186"
				( objectStatus "@baseboard_fab2_lib.baseboard_fab2(sch_1):page44_i120:dqs3p" )
			)
			( pin "J6T1.244"
				( objectStatus "@baseboard_fab2_lib.baseboard_fab2(sch_1):page44_i120:dqs4n" )
			)
			( pin "J6T1.245"
				( objectStatus "@baseboard_fab2_lib.baseboard_fab2(sch_1):page44_i120:dqs4p" )
			)
			( pin "J6T1.255"
				( objectStatus "@baseboard_fab2_lib.baseboard_fab2(sch_1):page44_i120:dqs5n" )
			)
			( pin "J6T1.256"
				( objectStatus "@baseboard_fab2_lib.baseboard_fab2(sch_1):page44_i120:dqs5p" )
			)
			( pin "J6T1.266"
				( objectStatus "@baseboard_fab2_lib.baseboard_fab2(sch_1):page44_i120:dqs6n" )
			)
			( pin "J6T1.267"
				( objectStatus "@baseboard_fab2_lib.baseboard_fab2(sch_1):page44_i120:dqs6p" )
			)
			( pin "J6T1.277"
				( objectStatus "@baseboard_fab2_lib.baseboard_fab2(sch_1):page44_i120:dqs7n" )
			)
			( pin "J6T1.278"
				( objectStatus "@baseboard_fab2_lib.baseboard_fab2(sch_1):page44_i120:dqs7p" )
			)
			( pin "J6T1.196"
				( objectStatus "@baseboard_fab2_lib.baseboard_fab2(sch_1):page44_i120:dqs8n" )
			)
			( pin "J6T1.197"
				( objectStatus "@baseboard_fab2_lib.baseboard_fab2(sch_1):page44_i120:dqs8p" )
			)
			( pin "J6T1.8"
				( objectStatus "@baseboard_fab2_lib.baseboard_fab2(sch_1):page44_i120:dqs9n" )
			)
			( pin "J6T1.7"
				( objectStatus "@baseboard_fab2_lib.baseboard_fab2(sch_1):page44_i120:dqs9p" )
			)
			( pin "J6T1.19"
				( objectStatus "@baseboard_fab2_lib.baseboard_fab2(sch_1):page44_i120:dqs10n" )
			)
			( pin "J6T1.18"
				( objectStatus "@baseboard_fab2_lib.baseboard_fab2(sch_1):page44_i120:dqs10p" )
			)
			( pin "J6T1.30"
				( objectStatus "@baseboard_fab2_lib.baseboard_fab2(sch_1):page44_i120:dqs11n" )
			)
			( pin "J6T1.29"
				( objectStatus "@baseboard_fab2_lib.baseboard_fab2(sch_1):page44_i120:dqs11p" )
			)
			( pin "J6T1.41"
				( objectStatus "@baseboard_fab2_lib.baseboard_fab2(sch_1):page44_i120:dqs12n" )
			)
			( pin "J6T1.40"
				( objectStatus "@baseboard_fab2_lib.baseboard_fab2(sch_1):page44_i120:dqs12p" )
			)
			( pin "J6T1.100"
				( objectStatus "@baseboard_fab2_lib.baseboard_fab2(sch_1):page44_i120:dqs13n" )
			)
			( pin "J6T1.99"
				( objectStatus "@baseboard_fab2_lib.baseboard_fab2(sch_1):page44_i120:dqs13p" )
			)
			( pin "J6T1.111"
				( objectStatus "@baseboard_fab2_lib.baseboard_fab2(sch_1):page44_i120:dqs14n" )
			)
			( pin "J6T1.110"
				( objectStatus "@baseboard_fab2_lib.baseboard_fab2(sch_1):page44_i120:dqs14p" )
			)
			( pin "J6T1.122"
				( objectStatus "@baseboard_fab2_lib.baseboard_fab2(sch_1):page44_i120:dqs15n" )
			)
			( pin "J6T1.121"
				( objectStatus "@baseboard_fab2_lib.baseboard_fab2(sch_1):page44_i120:dqs15p" )
			)
			( pin "J6T1.133"
				( objectStatus "@baseboard_fab2_lib.baseboard_fab2(sch_1):page44_i120:dqs16n" )
			)
			( pin "J6T1.132"
				( objectStatus "@baseboard_fab2_lib.baseboard_fab2(sch_1):page44_i120:dqs16p" )
			)
			( pin "J6T1.52"
				( objectStatus "@baseboard_fab2_lib.baseboard_fab2(sch_1):page44_i120:dqs17n" )
			)
			( pin "J6T1.51"
				( objectStatus "@baseboard_fab2_lib.baseboard_fab2(sch_1):page44_i120:dqs17p" )
			)
			( pin "J6T1.283"
				( objectStatus "@baseboard_fab2_lib.baseboard_fab2(sch_1):page44_i139:vss(0)" )
			)
			( pin "J6T1.281"
				( objectStatus "@baseboard_fab2_lib.baseboard_fab2(sch_1):page44_i139:vss(1)" )
			)
			( pin "J6T1.279"
				( objectStatus "@baseboard_fab2_lib.baseboard_fab2(sch_1):page44_i139:vss(2)" )
			)
			( pin "J6T1.276"
				( objectStatus "@baseboard_fab2_lib.baseboard_fab2(sch_1):page44_i139:vss(3)" )
			)
			( pin "J6T1.274"
				( objectStatus "@baseboard_fab2_lib.baseboard_fab2(sch_1):page44_i139:vss(4)" )
			)
			( pin "J6T1.272"
				( objectStatus "@baseboard_fab2_lib.baseboard_fab2(sch_1):page44_i139:vss(5)" )
			)
			( pin "J6T1.270"
				( objectStatus "@baseboard_fab2_lib.baseboard_fab2(sch_1):page44_i139:vss(6)" )
			)
			( pin "J6T1.268"
				( objectStatus "@baseboard_fab2_lib.baseboard_fab2(sch_1):page44_i139:vss(7)" )
			)
			( pin "J6T1.265"
				( objectStatus "@baseboard_fab2_lib.baseboard_fab2(sch_1):page44_i139:vss(8)" )
			)
			( pin "J6T1.263"
				( objectStatus "@baseboard_fab2_lib.baseboard_fab2(sch_1):page44_i139:vss(9)" )
			)
			( pin "J6T1.261"
				( objectStatus "@baseboard_fab2_lib.baseboard_fab2(sch_1):page44_i139:vss(10)" )
			)
			( pin "J6T1.259"
				( objectStatus "@baseboard_fab2_lib.baseboard_fab2(sch_1):page44_i139:vss(11)" )
			)
			( pin "J6T1.257"
				( objectStatus "@baseboard_fab2_lib.baseboard_fab2(sch_1):page44_i139:vss(12)" )
			)
			( pin "J6T1.254"
				( objectStatus "@baseboard_fab2_lib.baseboard_fab2(sch_1):page44_i139:vss(13)" )
			)
			( pin "J6T1.252"
				( objectStatus "@baseboard_fab2_lib.baseboard_fab2(sch_1):page44_i139:vss(14)" )
			)
			( pin "J6T1.250"
				( objectStatus "@baseboard_fab2_lib.baseboard_fab2(sch_1):page44_i139:vss(15)" )
			)
			( pin "J6T1.248"
				( objectStatus "@baseboard_fab2_lib.baseboard_fab2(sch_1):page44_i139:vss(16)" )
			)
			( pin "J6T1.246"
				( objectStatus "@baseboard_fab2_lib.baseboard_fab2(sch_1):page44_i139:vss(17)" )
			)
			( pin "J6T1.243"
				( objectStatus "@baseboard_fab2_lib.baseboard_fab2(sch_1):page44_i139:vss(18)" )
			)
			( pin "J6T1.241"
				( objectStatus "@baseboard_fab2_lib.baseboard_fab2(sch_1):page44_i139:vss(19)" )
			)
			( pin "J6T1.239"
				( objectStatus "@baseboard_fab2_lib.baseboard_fab2(sch_1):page44_i139:vss(20)" )
			)
			( pin "J6T1.202"
				( objectStatus "@baseboard_fab2_lib.baseboard_fab2(sch_1):page44_i139:vss(21)" )
			)
			( pin "J6T1.200"
				( objectStatus "@baseboard_fab2_lib.baseboard_fab2(sch_1):page44_i139:vss(22)" )
			)
			( pin "J6T1.198"
				( objectStatus "@baseboard_fab2_lib.baseboard_fab2(sch_1):page44_i139:vss(23)" )
			)
			( pin "J6T1.195"
				( objectStatus "@baseboard_fab2_lib.baseboard_fab2(sch_1):page44_i139:vss(24)" )
			)
			( pin "J6T1.193"
				( objectStatus "@baseboard_fab2_lib.baseboard_fab2(sch_1):page44_i139:vss(25)" )
			)
			( pin "J6T1.191"
				( objectStatus "@baseboard_fab2_lib.baseboard_fab2(sch_1):page44_i139:vss(26)" )
			)
			( pin "J6T1.189"
				( objectStatus "@baseboard_fab2_lib.baseboard_fab2(sch_1):page44_i139:vss(27)" )
			)
			( pin "J6T1.187"
				( objectStatus "@baseboard_fab2_lib.baseboard_fab2(sch_1):page44_i139:vss(28)" )
			)
			( pin "J6T1.184"
				( objectStatus "@baseboard_fab2_lib.baseboard_fab2(sch_1):page44_i139:vss(29)" )
			)
			( pin "J6T1.182"
				( objectStatus "@baseboard_fab2_lib.baseboard_fab2(sch_1):page44_i139:vss(30)" )
			)
			( pin "J6T1.180"
				( objectStatus "@baseboard_fab2_lib.baseboard_fab2(sch_1):page44_i139:vss(31)" )
			)
			( pin "J6T1.178"
				( objectStatus "@baseboard_fab2_lib.baseboard_fab2(sch_1):page44_i139:vss(32)" )
			)
			( pin "J6T1.176"
				( objectStatus "@baseboard_fab2_lib.baseboard_fab2(sch_1):page44_i139:vss(33)" )
			)
			( pin "J6T1.173"
				( objectStatus "@baseboard_fab2_lib.baseboard_fab2(sch_1):page44_i139:vss(34)" )
			)
			( pin "J6T1.171"
				( objectStatus "@baseboard_fab2_lib.baseboard_fab2(sch_1):page44_i139:vss(35)" )
			)
			( pin "J6T1.169"
				( objectStatus "@baseboard_fab2_lib.baseboard_fab2(sch_1):page44_i139:vss(36)" )
			)
			( pin "J6T1.167"
				( objectStatus "@baseboard_fab2_lib.baseboard_fab2(sch_1):page44_i139:vss(37)" )
			)
			( pin "J6T1.165"
				( objectStatus "@baseboard_fab2_lib.baseboard_fab2(sch_1):page44_i139:vss(38)" )
			)
			( pin "J6T1.162"
				( objectStatus "@baseboard_fab2_lib.baseboard_fab2(sch_1):page44_i139:vss(39)" )
			)
			( pin "J6T1.160"
				( objectStatus "@baseboard_fab2_lib.baseboard_fab2(sch_1):page44_i139:vss(40)" )
			)
			( pin "J6T1.158"
				( objectStatus "@baseboard_fab2_lib.baseboard_fab2(sch_1):page44_i139:vss(41)" )
			)
			( pin "J6T1.156"
				( objectStatus "@baseboard_fab2_lib.baseboard_fab2(sch_1):page44_i139:vss(42)" )
			)
			( pin "J6T1.154"
				( objectStatus "@baseboard_fab2_lib.baseboard_fab2(sch_1):page44_i139:vss(43)" )
			)
			( pin "J6T1.151"
				( objectStatus "@baseboard_fab2_lib.baseboard_fab2(sch_1):page44_i139:vss(44)" )
			)
			( pin "J6T1.149"
				( objectStatus "@baseboard_fab2_lib.baseboard_fab2(sch_1):page44_i139:vss(45)" )
			)
			( pin "J6T1.147"
				( objectStatus "@baseboard_fab2_lib.baseboard_fab2(sch_1):page44_i139:vss(46)" )
			)
			( pin "J6T1.138"
				( objectStatus "@baseboard_fab2_lib.baseboard_fab2(sch_1):page44_i139:vss(47)" )
			)
			( pin "J6T1.136"
				( objectStatus "@baseboard_fab2_lib.baseboard_fab2(sch_1):page44_i139:vss(48)" )
			)
			( pin "J6T1.134"
				( objectStatus "@baseboard_fab2_lib.baseboard_fab2(sch_1):page44_i139:vss(49)" )
			)
			( pin "J6T1.131"
				( objectStatus "@baseboard_fab2_lib.baseboard_fab2(sch_1):page44_i139:vss(50)" )
			)
			( pin "J6T1.129"
				( objectStatus "@baseboard_fab2_lib.baseboard_fab2(sch_1):page44_i139:vss(51)" )
			)
			( pin "J6T1.127"
				( objectStatus "@baseboard_fab2_lib.baseboard_fab2(sch_1):page44_i139:vss(52)" )
			)
			( pin "J6T1.125"
				( objectStatus "@baseboard_fab2_lib.baseboard_fab2(sch_1):page44_i139:vss(53)" )
			)
			( pin "J6T1.123"
				( objectStatus "@baseboard_fab2_lib.baseboard_fab2(sch_1):page44_i139:vss(54)" )
			)
			( pin "J6T1.120"
				( objectStatus "@baseboard_fab2_lib.baseboard_fab2(sch_1):page44_i139:vss(55)" )
			)
			( pin "J6T1.118"
				( objectStatus "@baseboard_fab2_lib.baseboard_fab2(sch_1):page44_i139:vss(56)" )
			)
			( pin "J6T1.116"
				( objectStatus "@baseboard_fab2_lib.baseboard_fab2(sch_1):page44_i139:vss(57)" )
			)
			( pin "J6T1.114"
				( objectStatus "@baseboard_fab2_lib.baseboard_fab2(sch_1):page44_i139:vss(58)" )
			)
			( pin "J6T1.112"
				( objectStatus "@baseboard_fab2_lib.baseboard_fab2(sch_1):page44_i139:vss(59)" )
			)
			( pin "J6T1.109"
				( objectStatus "@baseboard_fab2_lib.baseboard_fab2(sch_1):page44_i139:vss(60)" )
			)
			( pin "J6T1.107"
				( objectStatus "@baseboard_fab2_lib.baseboard_fab2(sch_1):page44_i139:vss(61)" )
			)
			( pin "J6T1.105"
				( objectStatus "@baseboard_fab2_lib.baseboard_fab2(sch_1):page44_i139:vss(62)" )
			)
			( pin "J6T1.103"
				( objectStatus "@baseboard_fab2_lib.baseboard_fab2(sch_1):page44_i139:vss(63)" )
			)
			( pin "J6T1.101"
				( objectStatus "@baseboard_fab2_lib.baseboard_fab2(sch_1):page44_i139:vss(64)" )
			)
			( pin "J6T1.98"
				( objectStatus "@baseboard_fab2_lib.baseboard_fab2(sch_1):page44_i139:vss(65)" )
			)
			( pin "J6T1.96"
				( objectStatus "@baseboard_fab2_lib.baseboard_fab2(sch_1):page44_i139:vss(66)" )
			)
			( pin "J6T1.94"
				( objectStatus "@baseboard_fab2_lib.baseboard_fab2(sch_1):page44_i139:vss(67)" )
			)
			( pin "J6T1.57"
				( objectStatus "@baseboard_fab2_lib.baseboard_fab2(sch_1):page44_i139:vss(68)" )
			)
			( pin "J6T1.55"
				( objectStatus "@baseboard_fab2_lib.baseboard_fab2(sch_1):page44_i139:vss(69)" )
			)
			( pin "J6T1.53"
				( objectStatus "@baseboard_fab2_lib.baseboard_fab2(sch_1):page44_i139:vss(70)" )
			)
			( pin "J6T1.50"
				( objectStatus "@baseboard_fab2_lib.baseboard_fab2(sch_1):page44_i139:vss(71)" )
			)
			( pin "J6T1.48"
				( objectStatus "@baseboard_fab2_lib.baseboard_fab2(sch_1):page44_i139:vss(72)" )
			)
			( pin "J6T1.46"
				( objectStatus "@baseboard_fab2_lib.baseboard_fab2(sch_1):page44_i139:vss(73)" )
			)
			( pin "J6T1.44"
				( objectStatus "@baseboard_fab2_lib.baseboard_fab2(sch_1):page44_i139:vss(74)" )
			)
			( pin "J6T1.42"
				( objectStatus "@baseboard_fab2_lib.baseboard_fab2(sch_1):page44_i139:vss(75)" )
			)
			( pin "J6T1.39"
				( objectStatus "@baseboard_fab2_lib.baseboard_fab2(sch_1):page44_i139:vss(76)" )
			)
			( pin "J6T1.37"
				( objectStatus "@baseboard_fab2_lib.baseboard_fab2(sch_1):page44_i139:vss(77)" )
			)
			( pin "J6T1.35"
				( objectStatus "@baseboard_fab2_lib.baseboard_fab2(sch_1):page44_i139:vss(78)" )
			)
			( pin "J6T1.33"
				( objectStatus "@baseboard_fab2_lib.baseboard_fab2(sch_1):page44_i139:vss(79)" )
			)
			( pin "J6T1.31"
				( objectStatus "@baseboard_fab2_lib.baseboard_fab2(sch_1):page44_i139:vss(80)" )
			)
			( pin "J6T1.28"
				( objectStatus "@baseboard_fab2_lib.baseboard_fab2(sch_1):page44_i139:vss(81)" )
			)
			( pin "J6T1.26"
				( objectStatus "@baseboard_fab2_lib.baseboard_fab2(sch_1):page44_i139:vss(82)" )
			)
			( pin "J6T1.24"
				( objectStatus "@baseboard_fab2_lib.baseboard_fab2(sch_1):page44_i139:vss(83)" )
			)
			( pin "J6T1.22"
				( objectStatus "@baseboard_fab2_lib.baseboard_fab2(sch_1):page44_i139:vss(84)" )
			)
			( pin "J6T1.20"
				( objectStatus "@baseboard_fab2_lib.baseboard_fab2(sch_1):page44_i139:vss(85)" )
			)
			( pin "J6T1.17"
				( objectStatus "@baseboard_fab2_lib.baseboard_fab2(sch_1):page44_i139:vss(86)" )
			)
			( pin "J6T1.15"
				( objectStatus "@baseboard_fab2_lib.baseboard_fab2(sch_1):page44_i139:vss(87)" )
			)
			( pin "J6T1.13"
				( objectStatus "@baseboard_fab2_lib.baseboard_fab2(sch_1):page44_i139:vss(88)" )
			)
			( pin "J6T1.11"
				( objectStatus "@baseboard_fab2_lib.baseboard_fab2(sch_1):page44_i139:vss(89)" )
			)
			( pin "J6T1.9"
				( objectStatus "@baseboard_fab2_lib.baseboard_fab2(sch_1):page44_i139:vss(90)" )
			)
			( pin "J6T1.6"
				( objectStatus "@baseboard_fab2_lib.baseboard_fab2(sch_1):page44_i139:vss(91)" )
			)
			( pin "J6T1.4"
				( objectStatus "@baseboard_fab2_lib.baseboard_fab2(sch_1):page44_i139:vss(92)" )
			)
			( pin "J6T1.2"
				( objectStatus "@baseboard_fab2_lib.baseboard_fab2(sch_1):page44_i139:vss(93)" )
			)
			( pin "J4G2.283"
				( objectStatus "@baseboard_fab2_lib.baseboard_fab2(sch_1):page45_i43:vss(0)" )
			)
			( pin "J4G2.281"
				( objectStatus "@baseboard_fab2_lib.baseboard_fab2(sch_1):page45_i43:vss(1)" )
			)
			( pin "J4G2.279"
				( objectStatus "@baseboard_fab2_lib.baseboard_fab2(sch_1):page45_i43:vss(2)" )
			)
			( pin "J4G2.276"
				( objectStatus "@baseboard_fab2_lib.baseboard_fab2(sch_1):page45_i43:vss(3)" )
			)
			( pin "J4G2.274"
				( objectStatus "@baseboard_fab2_lib.baseboard_fab2(sch_1):page45_i43:vss(4)" )
			)
			( pin "J4G2.272"
				( objectStatus "@baseboard_fab2_lib.baseboard_fab2(sch_1):page45_i43:vss(5)" )
			)
			( pin "J4G2.270"
				( objectStatus "@baseboard_fab2_lib.baseboard_fab2(sch_1):page45_i43:vss(6)" )
			)
			( pin "J4G2.268"
				( objectStatus "@baseboard_fab2_lib.baseboard_fab2(sch_1):page45_i43:vss(7)" )
			)
			( pin "J4G2.265"
				( objectStatus "@baseboard_fab2_lib.baseboard_fab2(sch_1):page45_i43:vss(8)" )
			)
			( pin "J4G2.263"
				( objectStatus "@baseboard_fab2_lib.baseboard_fab2(sch_1):page45_i43:vss(9)" )
			)
			( pin "J4G2.261"
				( objectStatus "@baseboard_fab2_lib.baseboard_fab2(sch_1):page45_i43:vss(10)" )
			)
			( pin "J4G2.259"
				( objectStatus "@baseboard_fab2_lib.baseboard_fab2(sch_1):page45_i43:vss(11)" )
			)
			( pin "J4G2.257"
				( objectStatus "@baseboard_fab2_lib.baseboard_fab2(sch_1):page45_i43:vss(12)" )
			)
			( pin "J4G2.254"
				( objectStatus "@baseboard_fab2_lib.baseboard_fab2(sch_1):page45_i43:vss(13)" )
			)
			( pin "J4G2.252"
				( objectStatus "@baseboard_fab2_lib.baseboard_fab2(sch_1):page45_i43:vss(14)" )
			)
			( pin "J4G2.250"
				( objectStatus "@baseboard_fab2_lib.baseboard_fab2(sch_1):page45_i43:vss(15)" )
			)
			( pin "J4G2.248"
				( objectStatus "@baseboard_fab2_lib.baseboard_fab2(sch_1):page45_i43:vss(16)" )
			)
			( pin "J4G2.246"
				( objectStatus "@baseboard_fab2_lib.baseboard_fab2(sch_1):page45_i43:vss(17)" )
			)
			( pin "J4G2.243"
				( objectStatus "@baseboard_fab2_lib.baseboard_fab2(sch_1):page45_i43:vss(18)" )
			)
			( pin "J4G2.241"
				( objectStatus "@baseboard_fab2_lib.baseboard_fab2(sch_1):page45_i43:vss(19)" )
			)
			( pin "J4G2.239"
				( objectStatus "@baseboard_fab2_lib.baseboard_fab2(sch_1):page45_i43:vss(20)" )
			)
			( pin "J4G2.202"
				( objectStatus "@baseboard_fab2_lib.baseboard_fab2(sch_1):page45_i43:vss(21)" )
			)
			( pin "J4G2.200"
				( objectStatus "@baseboard_fab2_lib.baseboard_fab2(sch_1):page45_i43:vss(22)" )
			)
			( pin "J4G2.198"
				( objectStatus "@baseboard_fab2_lib.baseboard_fab2(sch_1):page45_i43:vss(23)" )
			)
			( pin "J4G2.195"
				( objectStatus "@baseboard_fab2_lib.baseboard_fab2(sch_1):page45_i43:vss(24)" )
			)
			( pin "J4G2.193"
				( objectStatus "@baseboard_fab2_lib.baseboard_fab2(sch_1):page45_i43:vss(25)" )
			)
			( pin "J4G2.191"
				( objectStatus "@baseboard_fab2_lib.baseboard_fab2(sch_1):page45_i43:vss(26)" )
			)
			( pin "J4G2.189"
				( objectStatus "@baseboard_fab2_lib.baseboard_fab2(sch_1):page45_i43:vss(27)" )
			)
			( pin "J4G2.187"
				( objectStatus "@baseboard_fab2_lib.baseboard_fab2(sch_1):page45_i43:vss(28)" )
			)
			( pin "J4G2.184"
				( objectStatus "@baseboard_fab2_lib.baseboard_fab2(sch_1):page45_i43:vss(29)" )
			)
			( pin "J4G2.182"
				( objectStatus "@baseboard_fab2_lib.baseboard_fab2(sch_1):page45_i43:vss(30)" )
			)
			( pin "J4G2.180"
				( objectStatus "@baseboard_fab2_lib.baseboard_fab2(sch_1):page45_i43:vss(31)" )
			)
			( pin "J4G2.178"
				( objectStatus "@baseboard_fab2_lib.baseboard_fab2(sch_1):page45_i43:vss(32)" )
			)
			( pin "J4G2.176"
				( objectStatus "@baseboard_fab2_lib.baseboard_fab2(sch_1):page45_i43:vss(33)" )
			)
			( pin "J4G2.173"
				( objectStatus "@baseboard_fab2_lib.baseboard_fab2(sch_1):page45_i43:vss(34)" )
			)
			( pin "J4G2.171"
				( objectStatus "@baseboard_fab2_lib.baseboard_fab2(sch_1):page45_i43:vss(35)" )
			)
			( pin "J4G2.169"
				( objectStatus "@baseboard_fab2_lib.baseboard_fab2(sch_1):page45_i43:vss(36)" )
			)
			( pin "J4G2.167"
				( objectStatus "@baseboard_fab2_lib.baseboard_fab2(sch_1):page45_i43:vss(37)" )
			)
			( pin "J4G2.165"
				( objectStatus "@baseboard_fab2_lib.baseboard_fab2(sch_1):page45_i43:vss(38)" )
			)
			( pin "J4G2.162"
				( objectStatus "@baseboard_fab2_lib.baseboard_fab2(sch_1):page45_i43:vss(39)" )
			)
			( pin "J4G2.160"
				( objectStatus "@baseboard_fab2_lib.baseboard_fab2(sch_1):page45_i43:vss(40)" )
			)
			( pin "J4G2.158"
				( objectStatus "@baseboard_fab2_lib.baseboard_fab2(sch_1):page45_i43:vss(41)" )
			)
			( pin "J4G2.156"
				( objectStatus "@baseboard_fab2_lib.baseboard_fab2(sch_1):page45_i43:vss(42)" )
			)
			( pin "J4G2.154"
				( objectStatus "@baseboard_fab2_lib.baseboard_fab2(sch_1):page45_i43:vss(43)" )
			)
			( pin "J4G2.151"
				( objectStatus "@baseboard_fab2_lib.baseboard_fab2(sch_1):page45_i43:vss(44)" )
			)
			( pin "J4G2.149"
				( objectStatus "@baseboard_fab2_lib.baseboard_fab2(sch_1):page45_i43:vss(45)" )
			)
			( pin "J4G2.147"
				( objectStatus "@baseboard_fab2_lib.baseboard_fab2(sch_1):page45_i43:vss(46)" )
			)
			( pin "J4G2.138"
				( objectStatus "@baseboard_fab2_lib.baseboard_fab2(sch_1):page45_i43:vss(47)" )
			)
			( pin "J4G2.136"
				( objectStatus "@baseboard_fab2_lib.baseboard_fab2(sch_1):page45_i43:vss(48)" )
			)
			( pin "J4G2.134"
				( objectStatus "@baseboard_fab2_lib.baseboard_fab2(sch_1):page45_i43:vss(49)" )
			)
			( pin "J4G2.131"
				( objectStatus "@baseboard_fab2_lib.baseboard_fab2(sch_1):page45_i43:vss(50)" )
			)
			( pin "J4G2.129"
				( objectStatus "@baseboard_fab2_lib.baseboard_fab2(sch_1):page45_i43:vss(51)" )
			)
			( pin "J4G2.127"
				( objectStatus "@baseboard_fab2_lib.baseboard_fab2(sch_1):page45_i43:vss(52)" )
			)
			( pin "J4G2.125"
				( objectStatus "@baseboard_fab2_lib.baseboard_fab2(sch_1):page45_i43:vss(53)" )
			)
			( pin "J4G2.123"
				( objectStatus "@baseboard_fab2_lib.baseboard_fab2(sch_1):page45_i43:vss(54)" )
			)
			( pin "J4G2.120"
				( objectStatus "@baseboard_fab2_lib.baseboard_fab2(sch_1):page45_i43:vss(55)" )
			)
			( pin "J4G2.118"
				( objectStatus "@baseboard_fab2_lib.baseboard_fab2(sch_1):page45_i43:vss(56)" )
			)
			( pin "J4G2.116"
				( objectStatus "@baseboard_fab2_lib.baseboard_fab2(sch_1):page45_i43:vss(57)" )
			)
			( pin "J4G2.114"
				( objectStatus "@baseboard_fab2_lib.baseboard_fab2(sch_1):page45_i43:vss(58)" )
			)
			( pin "J4G2.112"
				( objectStatus "@baseboard_fab2_lib.baseboard_fab2(sch_1):page45_i43:vss(59)" )
			)
			( pin "J4G2.109"
				( objectStatus "@baseboard_fab2_lib.baseboard_fab2(sch_1):page45_i43:vss(60)" )
			)
			( pin "J4G2.107"
				( objectStatus "@baseboard_fab2_lib.baseboard_fab2(sch_1):page45_i43:vss(61)" )
			)
			( pin "J4G2.105"
				( objectStatus "@baseboard_fab2_lib.baseboard_fab2(sch_1):page45_i43:vss(62)" )
			)
			( pin "J4G2.103"
				( objectStatus "@baseboard_fab2_lib.baseboard_fab2(sch_1):page45_i43:vss(63)" )
			)
			( pin "J4G2.101"
				( objectStatus "@baseboard_fab2_lib.baseboard_fab2(sch_1):page45_i43:vss(64)" )
			)
			( pin "J4G2.98"
				( objectStatus "@baseboard_fab2_lib.baseboard_fab2(sch_1):page45_i43:vss(65)" )
			)
			( pin "J4G2.96"
				( objectStatus "@baseboard_fab2_lib.baseboard_fab2(sch_1):page45_i43:vss(66)" )
			)
			( pin "J4G2.94"
				( objectStatus "@baseboard_fab2_lib.baseboard_fab2(sch_1):page45_i43:vss(67)" )
			)
			( pin "J4G2.57"
				( objectStatus "@baseboard_fab2_lib.baseboard_fab2(sch_1):page45_i43:vss(68)" )
			)
			( pin "J4G2.55"
				( objectStatus "@baseboard_fab2_lib.baseboard_fab2(sch_1):page45_i43:vss(69)" )
			)
			( pin "J4G2.53"
				( objectStatus "@baseboard_fab2_lib.baseboard_fab2(sch_1):page45_i43:vss(70)" )
			)
			( pin "J4G2.50"
				( objectStatus "@baseboard_fab2_lib.baseboard_fab2(sch_1):page45_i43:vss(71)" )
			)
			( pin "J4G2.48"
				( objectStatus "@baseboard_fab2_lib.baseboard_fab2(sch_1):page45_i43:vss(72)" )
			)
			( pin "J4G2.46"
				( objectStatus "@baseboard_fab2_lib.baseboard_fab2(sch_1):page45_i43:vss(73)" )
			)
			( pin "J4G2.44"
				( objectStatus "@baseboard_fab2_lib.baseboard_fab2(sch_1):page45_i43:vss(74)" )
			)
			( pin "J4G2.42"
				( objectStatus "@baseboard_fab2_lib.baseboard_fab2(sch_1):page45_i43:vss(75)" )
			)
			( pin "J4G2.39"
				( objectStatus "@baseboard_fab2_lib.baseboard_fab2(sch_1):page45_i43:vss(76)" )
			)
			( pin "J4G2.37"
				( objectStatus "@baseboard_fab2_lib.baseboard_fab2(sch_1):page45_i43:vss(77)" )
			)
			( pin "J4G2.35"
				( objectStatus "@baseboard_fab2_lib.baseboard_fab2(sch_1):page45_i43:vss(78)" )
			)
			( pin "J4G2.33"
				( objectStatus "@baseboard_fab2_lib.baseboard_fab2(sch_1):page45_i43:vss(79)" )
			)
			( pin "J4G2.31"
				( objectStatus "@baseboard_fab2_lib.baseboard_fab2(sch_1):page45_i43:vss(80)" )
			)
			( pin "J4G2.28"
				( objectStatus "@baseboard_fab2_lib.baseboard_fab2(sch_1):page45_i43:vss(81)" )
			)
			( pin "J4G2.26"
				( objectStatus "@baseboard_fab2_lib.baseboard_fab2(sch_1):page45_i43:vss(82)" )
			)
			( pin "J4G2.24"
				( objectStatus "@baseboard_fab2_lib.baseboard_fab2(sch_1):page45_i43:vss(83)" )
			)
			( pin "J4G2.22"
				( objectStatus "@baseboard_fab2_lib.baseboard_fab2(sch_1):page45_i43:vss(84)" )
			)
			( pin "J4G2.20"
				( objectStatus "@baseboard_fab2_lib.baseboard_fab2(sch_1):page45_i43:vss(85)" )
			)
			( pin "J4G2.17"
				( objectStatus "@baseboard_fab2_lib.baseboard_fab2(sch_1):page45_i43:vss(86)" )
			)
			( pin "J4G2.15"
				( objectStatus "@baseboard_fab2_lib.baseboard_fab2(sch_1):page45_i43:vss(87)" )
			)
			( pin "J4G2.13"
				( objectStatus "@baseboard_fab2_lib.baseboard_fab2(sch_1):page45_i43:vss(88)" )
			)
			( pin "J4G2.11"
				( objectStatus "@baseboard_fab2_lib.baseboard_fab2(sch_1):page45_i43:vss(89)" )
			)
			( pin "J4G2.9"
				( objectStatus "@baseboard_fab2_lib.baseboard_fab2(sch_1):page45_i43:vss(90)" )
			)
			( pin "J4G2.6"
				( objectStatus "@baseboard_fab2_lib.baseboard_fab2(sch_1):page45_i43:vss(91)" )
			)
			( pin "J4G2.4"
				( objectStatus "@baseboard_fab2_lib.baseboard_fab2(sch_1):page45_i43:vss(92)" )
			)
			( pin "J4G2.2"
				( objectStatus "@baseboard_fab2_lib.baseboard_fab2(sch_1):page45_i43:vss(93)" )
			)
			( pin "J4G2.152"
				( objectStatus "@baseboard_fab2_lib.baseboard_fab2(sch_1):page45_i61:dqs0n" )
			)
			( pin "J4G2.153"
				( objectStatus "@baseboard_fab2_lib.baseboard_fab2(sch_1):page45_i61:dqs0p" )
			)
			( pin "J4G2.163"
				( objectStatus "@baseboard_fab2_lib.baseboard_fab2(sch_1):page45_i61:dqs1n" )
			)
			( pin "J4G2.164"
				( objectStatus "@baseboard_fab2_lib.baseboard_fab2(sch_1):page45_i61:dqs1p" )
			)
			( pin "J4G2.174"
				( objectStatus "@baseboard_fab2_lib.baseboard_fab2(sch_1):page45_i61:dqs2n" )
			)
			( pin "J4G2.175"
				( objectStatus "@baseboard_fab2_lib.baseboard_fab2(sch_1):page45_i61:dqs2p" )
			)
			( pin "J4G2.185"
				( objectStatus "@baseboard_fab2_lib.baseboard_fab2(sch_1):page45_i61:dqs3n" )
			)
			( pin "J4G2.186"
				( objectStatus "@baseboard_fab2_lib.baseboard_fab2(sch_1):page45_i61:dqs3p" )
			)
			( pin "J4G2.244"
				( objectStatus "@baseboard_fab2_lib.baseboard_fab2(sch_1):page45_i61:dqs4n" )
			)
			( pin "J4G2.245"
				( objectStatus "@baseboard_fab2_lib.baseboard_fab2(sch_1):page45_i61:dqs4p" )
			)
			( pin "J4G2.255"
				( objectStatus "@baseboard_fab2_lib.baseboard_fab2(sch_1):page45_i61:dqs5n" )
			)
			( pin "J4G2.256"
				( objectStatus "@baseboard_fab2_lib.baseboard_fab2(sch_1):page45_i61:dqs5p" )
			)
			( pin "J4G2.266"
				( objectStatus "@baseboard_fab2_lib.baseboard_fab2(sch_1):page45_i61:dqs6n" )
			)
			( pin "J4G2.267"
				( objectStatus "@baseboard_fab2_lib.baseboard_fab2(sch_1):page45_i61:dqs6p" )
			)
			( pin "J4G2.277"
				( objectStatus "@baseboard_fab2_lib.baseboard_fab2(sch_1):page45_i61:dqs7n" )
			)
			( pin "J4G2.278"
				( objectStatus "@baseboard_fab2_lib.baseboard_fab2(sch_1):page45_i61:dqs7p" )
			)
			( pin "J4G2.196"
				( objectStatus "@baseboard_fab2_lib.baseboard_fab2(sch_1):page45_i61:dqs8n" )
			)
			( pin "J4G2.197"
				( objectStatus "@baseboard_fab2_lib.baseboard_fab2(sch_1):page45_i61:dqs8p" )
			)
			( pin "J4G2.8"
				( objectStatus "@baseboard_fab2_lib.baseboard_fab2(sch_1):page45_i61:dqs9n" )
			)
			( pin "J4G2.7"
				( objectStatus "@baseboard_fab2_lib.baseboard_fab2(sch_1):page45_i61:dqs9p" )
			)
			( pin "J4G2.19"
				( objectStatus "@baseboard_fab2_lib.baseboard_fab2(sch_1):page45_i61:dqs10n" )
			)
			( pin "J4G2.18"
				( objectStatus "@baseboard_fab2_lib.baseboard_fab2(sch_1):page45_i61:dqs10p" )
			)
			( pin "J4G2.30"
				( objectStatus "@baseboard_fab2_lib.baseboard_fab2(sch_1):page45_i61:dqs11n" )
			)
			( pin "J4G2.29"
				( objectStatus "@baseboard_fab2_lib.baseboard_fab2(sch_1):page45_i61:dqs11p" )
			)
			( pin "J4G2.41"
				( objectStatus "@baseboard_fab2_lib.baseboard_fab2(sch_1):page45_i61:dqs12n" )
			)
			( pin "J4G2.40"
				( objectStatus "@baseboard_fab2_lib.baseboard_fab2(sch_1):page45_i61:dqs12p" )
			)
			( pin "J4G2.100"
				( objectStatus "@baseboard_fab2_lib.baseboard_fab2(sch_1):page45_i61:dqs13n" )
			)
			( pin "J4G2.99"
				( objectStatus "@baseboard_fab2_lib.baseboard_fab2(sch_1):page45_i61:dqs13p" )
			)
			( pin "J4G2.111"
				( objectStatus "@baseboard_fab2_lib.baseboard_fab2(sch_1):page45_i61:dqs14n" )
			)
			( pin "J4G2.110"
				( objectStatus "@baseboard_fab2_lib.baseboard_fab2(sch_1):page45_i61:dqs14p" )
			)
			( pin "J4G2.122"
				( objectStatus "@baseboard_fab2_lib.baseboard_fab2(sch_1):page45_i61:dqs15n" )
			)
			( pin "J4G2.121"
				( objectStatus "@baseboard_fab2_lib.baseboard_fab2(sch_1):page45_i61:dqs15p" )
			)
			( pin "J4G2.133"
				( objectStatus "@baseboard_fab2_lib.baseboard_fab2(sch_1):page45_i61:dqs16n" )
			)
			( pin "J4G2.132"
				( objectStatus "@baseboard_fab2_lib.baseboard_fab2(sch_1):page45_i61:dqs16p" )
			)
			( pin "J4G2.52"
				( objectStatus "@baseboard_fab2_lib.baseboard_fab2(sch_1):page45_i61:dqs17n" )
			)
			( pin "J4G2.51"
				( objectStatus "@baseboard_fab2_lib.baseboard_fab2(sch_1):page45_i61:dqs17p" )
			)
			( pin "J4G2.79"
				( objectStatus "@baseboard_fab2_lib.baseboard_fab2(sch_1):page45_i111:a0" )
			)
			( pin "J4G2.72"
				( objectStatus "@baseboard_fab2_lib.baseboard_fab2(sch_1):page45_i111:a1" )
			)
			( pin "J4G2.216"
				( objectStatus "@baseboard_fab2_lib.baseboard_fab2(sch_1):page45_i111:a2" )
			)
			( pin "J4G2.71"
				( objectStatus "@baseboard_fab2_lib.baseboard_fab2(sch_1):page45_i111:a3" )
			)
			( pin "J4G2.214"
				( objectStatus "@baseboard_fab2_lib.baseboard_fab2(sch_1):page45_i111:a4" )
			)
			( pin "J4G2.213"
				( objectStatus "@baseboard_fab2_lib.baseboard_fab2(sch_1):page45_i111:a5" )
			)
			( pin "J4G2.69"
				( objectStatus "@baseboard_fab2_lib.baseboard_fab2(sch_1):page45_i111:a6" )
			)
			( pin "J4G2.211"
				( objectStatus "@baseboard_fab2_lib.baseboard_fab2(sch_1):page45_i111:a7" )
			)
			( pin "J4G2.68"
				( objectStatus "@baseboard_fab2_lib.baseboard_fab2(sch_1):page45_i111:a8" )
			)
			( pin "J4G2.66"
				( objectStatus "@baseboard_fab2_lib.baseboard_fab2(sch_1):page45_i111:a9" )
			)
			( pin "J4G2.225"
				( objectStatus "@baseboard_fab2_lib.baseboard_fab2(sch_1):page45_i111:a10" )
			)
			( pin "J4G2.210"
				( objectStatus "@baseboard_fab2_lib.baseboard_fab2(sch_1):page45_i111:a11" )
			)
			( pin "J4G2.65"
				( objectStatus "@baseboard_fab2_lib.baseboard_fab2(sch_1):page45_i111:a12" )
			)
			( pin "J4G2.232"
				( objectStatus "@baseboard_fab2_lib.baseboard_fab2(sch_1):page45_i111:a13" )
			)
			( pin "J4G2.228"
				( objectStatus "@baseboard_fab2_lib.baseboard_fab2(sch_1):page45_i111:a14_we_n" )
			)
			( pin "J4G2.86"
				( objectStatus "@baseboard_fab2_lib.baseboard_fab2(sch_1):page45_i111:a15_cas_n" )
			)
			( pin "J4G2.82"
				( objectStatus "@baseboard_fab2_lib.baseboard_fab2(sch_1):page45_i111:a16_ras_n" )
			)
			( pin "J4G2.234"
				( objectStatus "@baseboard_fab2_lib.baseboard_fab2(sch_1):page45_i111:a17" )
			)
			( pin "J4G2.62"
				( objectStatus "@baseboard_fab2_lib.baseboard_fab2(sch_1):page45_i111:act_n" )
			)
			( pin "J4G2.208"
				( objectStatus "@baseboard_fab2_lib.baseboard_fab2(sch_1):page45_i111:alert_n" )
			)
			( pin "J4G2.81"
				( objectStatus "@baseboard_fab2_lib.baseboard_fab2(sch_1):page45_i111:ba(0)" )
			)
			( pin "J4G2.224"
				( objectStatus "@baseboard_fab2_lib.baseboard_fab2(sch_1):page45_i111:ba(1)" )
			)
			( pin "J4G2.63"
				( objectStatus "@baseboard_fab2_lib.baseboard_fab2(sch_1):page45_i111:bg(0)" )
			)
			( pin "J4G2.207"
				( objectStatus "@baseboard_fab2_lib.baseboard_fab2(sch_1):page45_i111:bg(1)" )
			)
			( pin "J4G2.235"
				( objectStatus "@baseboard_fab2_lib.baseboard_fab2(sch_1):page45_i111:c(2)" )
			)
			( pin "J4G2.49"
				( objectStatus "@baseboard_fab2_lib.baseboard_fab2(sch_1):page45_i111:cb(0)" )
			)
			( pin "J4G2.194"
				( objectStatus "@baseboard_fab2_lib.baseboard_fab2(sch_1):page45_i111:cb(1)" )
			)
			( pin "J4G2.56"
				( objectStatus "@baseboard_fab2_lib.baseboard_fab2(sch_1):page45_i111:cb(2)" )
			)
			( pin "J4G2.201"
				( objectStatus "@baseboard_fab2_lib.baseboard_fab2(sch_1):page45_i111:cb(3)" )
			)
			( pin "J4G2.47"
				( objectStatus "@baseboard_fab2_lib.baseboard_fab2(sch_1):page45_i111:cb(4)" )
			)
			( pin "J4G2.192"
				( objectStatus "@baseboard_fab2_lib.baseboard_fab2(sch_1):page45_i111:cb(5)" )
			)
			( pin "J4G2.54"
				( objectStatus "@baseboard_fab2_lib.baseboard_fab2(sch_1):page45_i111:cb(6)" )
			)
			( pin "J4G2.199"
				( objectStatus "@baseboard_fab2_lib.baseboard_fab2(sch_1):page45_i111:cb(7)" )
			)
			( pin "J4G2.75"
				( objectStatus "@baseboard_fab2_lib.baseboard_fab2(sch_1):page45_i111:ck0n" )
			)
			( pin "J4G2.74"
				( objectStatus "@baseboard_fab2_lib.baseboard_fab2(sch_1):page45_i111:ck0p" )
			)
			( pin "J4G2.219"
				( objectStatus "@baseboard_fab2_lib.baseboard_fab2(sch_1):page45_i111:ck1n" )
			)
			( pin "J4G2.218"
				( objectStatus "@baseboard_fab2_lib.baseboard_fab2(sch_1):page45_i111:ck1p" )
			)
			( pin "J4G2.60"
				( objectStatus "@baseboard_fab2_lib.baseboard_fab2(sch_1):page45_i111:cke(0)" )
			)
			( pin "J4G2.203"
				( objectStatus "@baseboard_fab2_lib.baseboard_fab2(sch_1):page45_i111:cke(1)" )
			)
			( pin "J4G2.5"
				( objectStatus "@baseboard_fab2_lib.baseboard_fab2(sch_1):page45_i111:dq(0)" )
			)
			( pin "J4G2.150"
				( objectStatus "@baseboard_fab2_lib.baseboard_fab2(sch_1):page45_i111:dq(1)" )
			)
			( pin "J4G2.12"
				( objectStatus "@baseboard_fab2_lib.baseboard_fab2(sch_1):page45_i111:dq(2)" )
			)
			( pin "J4G2.157"
				( objectStatus "@baseboard_fab2_lib.baseboard_fab2(sch_1):page45_i111:dq(3)" )
			)
			( pin "J4G2.3"
				( objectStatus "@baseboard_fab2_lib.baseboard_fab2(sch_1):page45_i111:dq(4)" )
			)
			( pin "J4G2.148"
				( objectStatus "@baseboard_fab2_lib.baseboard_fab2(sch_1):page45_i111:dq(5)" )
			)
			( pin "J4G2.10"
				( objectStatus "@baseboard_fab2_lib.baseboard_fab2(sch_1):page45_i111:dq(6)" )
			)
			( pin "J4G2.155"
				( objectStatus "@baseboard_fab2_lib.baseboard_fab2(sch_1):page45_i111:dq(7)" )
			)
			( pin "J4G2.16"
				( objectStatus "@baseboard_fab2_lib.baseboard_fab2(sch_1):page45_i111:dq(8)" )
			)
			( pin "J4G2.161"
				( objectStatus "@baseboard_fab2_lib.baseboard_fab2(sch_1):page45_i111:dq(9)" )
			)
			( pin "J4G2.23"
				( objectStatus "@baseboard_fab2_lib.baseboard_fab2(sch_1):page45_i111:dq(10)" )
			)
			( pin "J4G2.168"
				( objectStatus "@baseboard_fab2_lib.baseboard_fab2(sch_1):page45_i111:dq(11)" )
			)
			( pin "J4G2.14"
				( objectStatus "@baseboard_fab2_lib.baseboard_fab2(sch_1):page45_i111:dq(12)" )
			)
			( pin "J4G2.159"
				( objectStatus "@baseboard_fab2_lib.baseboard_fab2(sch_1):page45_i111:dq(13)" )
			)
			( pin "J4G2.21"
				( objectStatus "@baseboard_fab2_lib.baseboard_fab2(sch_1):page45_i111:dq(14)" )
			)
			( pin "J4G2.166"
				( objectStatus "@baseboard_fab2_lib.baseboard_fab2(sch_1):page45_i111:dq(15)" )
			)
			( pin "J4G2.27"
				( objectStatus "@baseboard_fab2_lib.baseboard_fab2(sch_1):page45_i111:dq(16)" )
			)
			( pin "J4G2.172"
				( objectStatus "@baseboard_fab2_lib.baseboard_fab2(sch_1):page45_i111:dq(17)" )
			)
			( pin "J4G2.34"
				( objectStatus "@baseboard_fab2_lib.baseboard_fab2(sch_1):page45_i111:dq(18)" )
			)
			( pin "J4G2.179"
				( objectStatus "@baseboard_fab2_lib.baseboard_fab2(sch_1):page45_i111:dq(19)" )
			)
			( pin "J4G2.25"
				( objectStatus "@baseboard_fab2_lib.baseboard_fab2(sch_1):page45_i111:dq(20)" )
			)
			( pin "J4G2.170"
				( objectStatus "@baseboard_fab2_lib.baseboard_fab2(sch_1):page45_i111:dq(21)" )
			)
			( pin "J4G2.32"
				( objectStatus "@baseboard_fab2_lib.baseboard_fab2(sch_1):page45_i111:dq(22)" )
			)
			( pin "J4G2.177"
				( objectStatus "@baseboard_fab2_lib.baseboard_fab2(sch_1):page45_i111:dq(23)" )
			)
			( pin "J4G2.38"
				( objectStatus "@baseboard_fab2_lib.baseboard_fab2(sch_1):page45_i111:dq(24)" )
			)
			( pin "J4G2.183"
				( objectStatus "@baseboard_fab2_lib.baseboard_fab2(sch_1):page45_i111:dq(25)" )
			)
			( pin "J4G2.45"
				( objectStatus "@baseboard_fab2_lib.baseboard_fab2(sch_1):page45_i111:dq(26)" )
			)
			( pin "J4G2.190"
				( objectStatus "@baseboard_fab2_lib.baseboard_fab2(sch_1):page45_i111:dq(27)" )
			)
			( pin "J4G2.36"
				( objectStatus "@baseboard_fab2_lib.baseboard_fab2(sch_1):page45_i111:dq(28)" )
			)
			( pin "J4G2.181"
				( objectStatus "@baseboard_fab2_lib.baseboard_fab2(sch_1):page45_i111:dq(29)" )
			)
			( pin "J4G2.43"
				( objectStatus "@baseboard_fab2_lib.baseboard_fab2(sch_1):page45_i111:dq(30)" )
			)
			( pin "J4G2.188"
				( objectStatus "@baseboard_fab2_lib.baseboard_fab2(sch_1):page45_i111:dq(31)" )
			)
			( pin "J4G2.97"
				( objectStatus "@baseboard_fab2_lib.baseboard_fab2(sch_1):page45_i111:dq(32)" )
			)
			( pin "J4G2.242"
				( objectStatus "@baseboard_fab2_lib.baseboard_fab2(sch_1):page45_i111:dq(33)" )
			)
			( pin "J4G2.104"
				( objectStatus "@baseboard_fab2_lib.baseboard_fab2(sch_1):page45_i111:dq(34)" )
			)
			( pin "J4G2.249"
				( objectStatus "@baseboard_fab2_lib.baseboard_fab2(sch_1):page45_i111:dq(35)" )
			)
			( pin "J4G2.95"
				( objectStatus "@baseboard_fab2_lib.baseboard_fab2(sch_1):page45_i111:dq(36)" )
			)
			( pin "J4G2.240"
				( objectStatus "@baseboard_fab2_lib.baseboard_fab2(sch_1):page45_i111:dq(37)" )
			)
			( pin "J4G2.102"
				( objectStatus "@baseboard_fab2_lib.baseboard_fab2(sch_1):page45_i111:dq(38)" )
			)
			( pin "J4G2.247"
				( objectStatus "@baseboard_fab2_lib.baseboard_fab2(sch_1):page45_i111:dq(39)" )
			)
			( pin "J4G2.108"
				( objectStatus "@baseboard_fab2_lib.baseboard_fab2(sch_1):page45_i111:dq(40)" )
			)
			( pin "J4G2.253"
				( objectStatus "@baseboard_fab2_lib.baseboard_fab2(sch_1):page45_i111:dq(41)" )
			)
			( pin "J4G2.115"
				( objectStatus "@baseboard_fab2_lib.baseboard_fab2(sch_1):page45_i111:dq(42)" )
			)
			( pin "J4G2.260"
				( objectStatus "@baseboard_fab2_lib.baseboard_fab2(sch_1):page45_i111:dq(43)" )
			)
			( pin "J4G2.106"
				( objectStatus "@baseboard_fab2_lib.baseboard_fab2(sch_1):page45_i111:dq(44)" )
			)
			( pin "J4G2.251"
				( objectStatus "@baseboard_fab2_lib.baseboard_fab2(sch_1):page45_i111:dq(45)" )
			)
			( pin "J4G2.113"
				( objectStatus "@baseboard_fab2_lib.baseboard_fab2(sch_1):page45_i111:dq(46)" )
			)
			( pin "J4G2.258"
				( objectStatus "@baseboard_fab2_lib.baseboard_fab2(sch_1):page45_i111:dq(47)" )
			)
			( pin "J4G2.119"
				( objectStatus "@baseboard_fab2_lib.baseboard_fab2(sch_1):page45_i111:dq(48)" )
			)
			( pin "J4G2.264"
				( objectStatus "@baseboard_fab2_lib.baseboard_fab2(sch_1):page45_i111:dq(49)" )
			)
			( pin "J4G2.126"
				( objectStatus "@baseboard_fab2_lib.baseboard_fab2(sch_1):page45_i111:dq(50)" )
			)
			( pin "J4G2.271"
				( objectStatus "@baseboard_fab2_lib.baseboard_fab2(sch_1):page45_i111:dq(51)" )
			)
			( pin "J4G2.117"
				( objectStatus "@baseboard_fab2_lib.baseboard_fab2(sch_1):page45_i111:dq(52)" )
			)
			( pin "J4G2.262"
				( objectStatus "@baseboard_fab2_lib.baseboard_fab2(sch_1):page45_i111:dq(53)" )
			)
			( pin "J4G2.124"
				( objectStatus "@baseboard_fab2_lib.baseboard_fab2(sch_1):page45_i111:dq(54)" )
			)
			( pin "J4G2.269"
				( objectStatus "@baseboard_fab2_lib.baseboard_fab2(sch_1):page45_i111:dq(55)" )
			)
			( pin "J4G2.130"
				( objectStatus "@baseboard_fab2_lib.baseboard_fab2(sch_1):page45_i111:dq(56)" )
			)
			( pin "J4G2.275"
				( objectStatus "@baseboard_fab2_lib.baseboard_fab2(sch_1):page45_i111:dq(57)" )
			)
			( pin "J4G2.137"
				( objectStatus "@baseboard_fab2_lib.baseboard_fab2(sch_1):page45_i111:dq(58)" )
			)
			( pin "J4G2.282"
				( objectStatus "@baseboard_fab2_lib.baseboard_fab2(sch_1):page45_i111:dq(59)" )
			)
			( pin "J4G2.128"
				( objectStatus "@baseboard_fab2_lib.baseboard_fab2(sch_1):page45_i111:dq(60)" )
			)
			( pin "J4G2.273"
				( objectStatus "@baseboard_fab2_lib.baseboard_fab2(sch_1):page45_i111:dq(61)" )
			)
			( pin "J4G2.135"
				( objectStatus "@baseboard_fab2_lib.baseboard_fab2(sch_1):page45_i111:dq(62)" )
			)
			( pin "J4G2.280"
				( objectStatus "@baseboard_fab2_lib.baseboard_fab2(sch_1):page45_i111:dq(63)" )
			)
			( pin "J4G2.78"
				( objectStatus "@baseboard_fab2_lib.baseboard_fab2(sch_1):page45_i111:event_n" )
			)
			( pin "J4G2.87"
				( objectStatus "@baseboard_fab2_lib.baseboard_fab2(sch_1):page45_i111:odt(0)" )
			)
			( pin "J4G2.91"
				( objectStatus "@baseboard_fab2_lib.baseboard_fab2(sch_1):page45_i111:odt(1)" )
			)
			( pin "J4G2.222"
				( objectStatus "@baseboard_fab2_lib.baseboard_fab2(sch_1):page45_i111:par" )
			)
			( pin "J4G2.58"
				( objectStatus "@baseboard_fab2_lib.baseboard_fab2(sch_1):page45_i111:reset_n" )
			)
			( pin "J4G2.205"
				( objectStatus "@baseboard_fab2_lib.baseboard_fab2(sch_1):page45_i111:rfu(0)" )
			)
			( pin "J4G2.227"
				( objectStatus "@baseboard_fab2_lib.baseboard_fab2(sch_1):page45_i111:rfu(1)" )
			)
			( pin "J4G2.144"
				( objectStatus "@baseboard_fab2_lib.baseboard_fab2(sch_1):page45_i111:rfu(2)" )
			)
			( pin "J4G2.84"
				( objectStatus "@baseboard_fab2_lib.baseboard_fab2(sch_1):page45_i111:s0_n" )
			)
			( pin "J4G2.89"
				( objectStatus "@baseboard_fab2_lib.baseboard_fab2(sch_1):page45_i111:s1_n" )
			)
			( pin "J4G2.93"
				( objectStatus "@baseboard_fab2_lib.baseboard_fab2(sch_1):page45_i111:s2_n_c(0)" )
			)
			( pin "J4G2.237"
				( objectStatus "@baseboard_fab2_lib.baseboard_fab2(sch_1):page45_i111:s3_n_c(1)" )
			)
			( pin "J4G2.139"
				( objectStatus "@baseboard_fab2_lib.baseboard_fab2(sch_1):page45_i111:sa(0)" )
			)
			( pin "J4G2.140"
				( objectStatus "@baseboard_fab2_lib.baseboard_fab2(sch_1):page45_i111:sa(1)" )
			)
			( pin "J4G2.238"
				( objectStatus "@baseboard_fab2_lib.baseboard_fab2(sch_1):page45_i111:sa(2)" )
			)
			( pin "J4G2.230"
				( objectStatus "@baseboard_fab2_lib.baseboard_fab2(sch_1):page45_i111:save_n_nc" )
			)
			( pin "J4G2.141"
				( objectStatus "@baseboard_fab2_lib.baseboard_fab2(sch_1):page45_i111:scl" )
			)
			( pin "J4G2.285"
				( objectStatus "@baseboard_fab2_lib.baseboard_fab2(sch_1):page45_i111:sda" )
			)
			( pin "J4G2.284"
				( objectStatus "@baseboard_fab2_lib.baseboard_fab2(sch_1):page45_i111:vddspd" )
			)
			( pin "J4G2.146"
				( objectStatus "@baseboard_fab2_lib.baseboard_fab2(sch_1):page45_i111:vrefca" )
			)
			( pin "J4G2.145"
				( objectStatus "@baseboard_fab2_lib.baseboard_fab2(sch_1):page45_i169:\12v\(0)" )
			)
			( pin "J4G2.1"
				( objectStatus "@baseboard_fab2_lib.baseboard_fab2(sch_1):page45_i169:\12v\(1)" )
			)
			( pin "J4G2.236"
				( objectStatus "@baseboard_fab2_lib.baseboard_fab2(sch_1):page45_i169:vdd(0)" )
			)
			( pin "J4G2.233"
				( objectStatus "@baseboard_fab2_lib.baseboard_fab2(sch_1):page45_i169:vdd(1)" )
			)
			( pin "J4G2.231"
				( objectStatus "@baseboard_fab2_lib.baseboard_fab2(sch_1):page45_i169:vdd(2)" )
			)
			( pin "J4G2.229"
				( objectStatus "@baseboard_fab2_lib.baseboard_fab2(sch_1):page45_i169:vdd(3)" )
			)
			( pin "J4G2.226"
				( objectStatus "@baseboard_fab2_lib.baseboard_fab2(sch_1):page45_i169:vdd(4)" )
			)
			( pin "J4G2.223"
				( objectStatus "@baseboard_fab2_lib.baseboard_fab2(sch_1):page45_i169:vdd(5)" )
			)
			( pin "J4G2.220"
				( objectStatus "@baseboard_fab2_lib.baseboard_fab2(sch_1):page45_i169:vdd(6)" )
			)
			( pin "J4G2.217"
				( objectStatus "@baseboard_fab2_lib.baseboard_fab2(sch_1):page45_i169:vdd(7)" )
			)
			( pin "J4G2.215"
				( objectStatus "@baseboard_fab2_lib.baseboard_fab2(sch_1):page45_i169:vdd(8)" )
			)
			( pin "J4G2.212"
				( objectStatus "@baseboard_fab2_lib.baseboard_fab2(sch_1):page45_i169:vdd(9)" )
			)
			( pin "J4G2.209"
				( objectStatus "@baseboard_fab2_lib.baseboard_fab2(sch_1):page45_i169:vdd(10)" )
			)
			( pin "J4G2.206"
				( objectStatus "@baseboard_fab2_lib.baseboard_fab2(sch_1):page45_i169:vdd(11)" )
			)
			( pin "J4G2.204"
				( objectStatus "@baseboard_fab2_lib.baseboard_fab2(sch_1):page45_i169:vdd(12)" )
			)
			( pin "J4G2.92"
				( objectStatus "@baseboard_fab2_lib.baseboard_fab2(sch_1):page45_i169:vdd(13)" )
			)
			( pin "J4G2.90"
				( objectStatus "@baseboard_fab2_lib.baseboard_fab2(sch_1):page45_i169:vdd(14)" )
			)
			( pin "J4G2.88"
				( objectStatus "@baseboard_fab2_lib.baseboard_fab2(sch_1):page45_i169:vdd(15)" )
			)
			( pin "J4G2.85"
				( objectStatus "@baseboard_fab2_lib.baseboard_fab2(sch_1):page45_i169:vdd(16)" )
			)
			( pin "J4G2.83"
				( objectStatus "@baseboard_fab2_lib.baseboard_fab2(sch_1):page45_i169:vdd(17)" )
			)
			( pin "J4G2.80"
				( objectStatus "@baseboard_fab2_lib.baseboard_fab2(sch_1):page45_i169:vdd(18)" )
			)
			( pin "J4G2.76"
				( objectStatus "@baseboard_fab2_lib.baseboard_fab2(sch_1):page45_i169:vdd(19)" )
			)
			( pin "J4G2.73"
				( objectStatus "@baseboard_fab2_lib.baseboard_fab2(sch_1):page45_i169:vdd(20)" )
			)
			( pin "J4G2.70"
				( objectStatus "@baseboard_fab2_lib.baseboard_fab2(sch_1):page45_i169:vdd(21)" )
			)
			( pin "J4G2.67"
				( objectStatus "@baseboard_fab2_lib.baseboard_fab2(sch_1):page45_i169:vdd(22)" )
			)
			( pin "J4G2.64"
				( objectStatus "@baseboard_fab2_lib.baseboard_fab2(sch_1):page45_i169:vdd(23)" )
			)
			( pin "J4G2.61"
				( objectStatus "@baseboard_fab2_lib.baseboard_fab2(sch_1):page45_i169:vdd(24)" )
			)
			( pin "J4G2.59"
				( objectStatus "@baseboard_fab2_lib.baseboard_fab2(sch_1):page45_i169:vdd(25)" )
			)
			( pin "J4G2.287"
				( objectStatus "@baseboard_fab2_lib.baseboard_fab2(sch_1):page45_i169:vpp(0)" )
			)
			( pin "J4G2.286"
				( objectStatus "@baseboard_fab2_lib.baseboard_fab2(sch_1):page45_i169:vpp(1)" )
			)
			( pin "J4G2.288"
				( objectStatus "@baseboard_fab2_lib.baseboard_fab2(sch_1):page45_i169:vpp(2)" )
			)
			( pin "J4G2.143"
				( objectStatus "@baseboard_fab2_lib.baseboard_fab2(sch_1):page45_i169:vpp(3)" )
			)
			( pin "J4G2.142"
				( objectStatus "@baseboard_fab2_lib.baseboard_fab2(sch_1):page45_i169:vpp(4)" )
			)
			( pin "J4G2.221"
				( objectStatus "@baseboard_fab2_lib.baseboard_fab2(sch_1):page45_i169:vtt(0)" )
			)
			( pin "J4G2.77"
				( objectStatus "@baseboard_fab2_lib.baseboard_fab2(sch_1):page45_i169:vtt(1)" )
			)
			( pin "C4G3.1"
				( objectStatus "@baseboard_fab2_lib.baseboard_fab2(sch_1):page45_i179:a" )
			)
			( pin "C4G3.2"
				( objectStatus "@baseboard_fab2_lib.baseboard_fab2(sch_1):page45_i179:b" )
			)
			( pin "C6U9.1"
				( objectStatus "@baseboard_fab2_lib.baseboard_fab2(sch_1):page46_i5:a" )
			)
			( pin "C6U9.2"
				( objectStatus "@baseboard_fab2_lib.baseboard_fab2(sch_1):page46_i5:b" )
			)
			( pin "J6U1.79"
				( objectStatus "@baseboard_fab2_lib.baseboard_fab2(sch_1):page46_i14:a0" )
			)
			( pin "J6U1.72"
				( objectStatus "@baseboard_fab2_lib.baseboard_fab2(sch_1):page46_i14:a1" )
			)
			( pin "J6U1.216"
				( objectStatus "@baseboard_fab2_lib.baseboard_fab2(sch_1):page46_i14:a2" )
			)
			( pin "J6U1.71"
				( objectStatus "@baseboard_fab2_lib.baseboard_fab2(sch_1):page46_i14:a3" )
			)
			( pin "J6U1.214"
				( objectStatus "@baseboard_fab2_lib.baseboard_fab2(sch_1):page46_i14:a4" )
			)
			( pin "J6U1.213"
				( objectStatus "@baseboard_fab2_lib.baseboard_fab2(sch_1):page46_i14:a5" )
			)
			( pin "J6U1.69"
				( objectStatus "@baseboard_fab2_lib.baseboard_fab2(sch_1):page46_i14:a6" )
			)
			( pin "J6U1.211"
				( objectStatus "@baseboard_fab2_lib.baseboard_fab2(sch_1):page46_i14:a7" )
			)
			( pin "J6U1.68"
				( objectStatus "@baseboard_fab2_lib.baseboard_fab2(sch_1):page46_i14:a8" )
			)
			( pin "J6U1.66"
				( objectStatus "@baseboard_fab2_lib.baseboard_fab2(sch_1):page46_i14:a9" )
			)
			( pin "J6U1.225"
				( objectStatus "@baseboard_fab2_lib.baseboard_fab2(sch_1):page46_i14:a10" )
			)
			( pin "J6U1.210"
				( objectStatus "@baseboard_fab2_lib.baseboard_fab2(sch_1):page46_i14:a11" )
			)
			( pin "J6U1.65"
				( objectStatus "@baseboard_fab2_lib.baseboard_fab2(sch_1):page46_i14:a12" )
			)
			( pin "J6U1.232"
				( objectStatus "@baseboard_fab2_lib.baseboard_fab2(sch_1):page46_i14:a13" )
			)
			( pin "J6U1.228"
				( objectStatus "@baseboard_fab2_lib.baseboard_fab2(sch_1):page46_i14:a14_we_n" )
			)
			( pin "J6U1.86"
				( objectStatus "@baseboard_fab2_lib.baseboard_fab2(sch_1):page46_i14:a15_cas_n" )
			)
			( pin "J6U1.82"
				( objectStatus "@baseboard_fab2_lib.baseboard_fab2(sch_1):page46_i14:a16_ras_n" )
			)
			( pin "J6U1.234"
				( objectStatus "@baseboard_fab2_lib.baseboard_fab2(sch_1):page46_i14:a17" )
			)
			( pin "J6U1.62"
				( objectStatus "@baseboard_fab2_lib.baseboard_fab2(sch_1):page46_i14:act_n" )
			)
			( pin "J6U1.208"
				( objectStatus "@baseboard_fab2_lib.baseboard_fab2(sch_1):page46_i14:alert_n" )
			)
			( pin "J6U1.81"
				( objectStatus "@baseboard_fab2_lib.baseboard_fab2(sch_1):page46_i14:ba(0)" )
			)
			( pin "J6U1.224"
				( objectStatus "@baseboard_fab2_lib.baseboard_fab2(sch_1):page46_i14:ba(1)" )
			)
			( pin "J6U1.63"
				( objectStatus "@baseboard_fab2_lib.baseboard_fab2(sch_1):page46_i14:bg(0)" )
			)
			( pin "J6U1.207"
				( objectStatus "@baseboard_fab2_lib.baseboard_fab2(sch_1):page46_i14:bg(1)" )
			)
			( pin "J6U1.235"
				( objectStatus "@baseboard_fab2_lib.baseboard_fab2(sch_1):page46_i14:c(2)" )
			)
			( pin "J6U1.49"
				( objectStatus "@baseboard_fab2_lib.baseboard_fab2(sch_1):page46_i14:cb(0)" )
			)
			( pin "J6U1.194"
				( objectStatus "@baseboard_fab2_lib.baseboard_fab2(sch_1):page46_i14:cb(1)" )
			)
			( pin "J6U1.56"
				( objectStatus "@baseboard_fab2_lib.baseboard_fab2(sch_1):page46_i14:cb(2)" )
			)
			( pin "J6U1.201"
				( objectStatus "@baseboard_fab2_lib.baseboard_fab2(sch_1):page46_i14:cb(3)" )
			)
			( pin "J6U1.47"
				( objectStatus "@baseboard_fab2_lib.baseboard_fab2(sch_1):page46_i14:cb(4)" )
			)
			( pin "J6U1.192"
				( objectStatus "@baseboard_fab2_lib.baseboard_fab2(sch_1):page46_i14:cb(5)" )
			)
			( pin "J6U1.54"
				( objectStatus "@baseboard_fab2_lib.baseboard_fab2(sch_1):page46_i14:cb(6)" )
			)
			( pin "J6U1.199"
				( objectStatus "@baseboard_fab2_lib.baseboard_fab2(sch_1):page46_i14:cb(7)" )
			)
			( pin "J6U1.75"
				( objectStatus "@baseboard_fab2_lib.baseboard_fab2(sch_1):page46_i14:ck0n" )
			)
			( pin "J6U1.74"
				( objectStatus "@baseboard_fab2_lib.baseboard_fab2(sch_1):page46_i14:ck0p" )
			)
			( pin "J6U1.219"
				( objectStatus "@baseboard_fab2_lib.baseboard_fab2(sch_1):page46_i14:ck1n" )
			)
			( pin "J6U1.218"
				( objectStatus "@baseboard_fab2_lib.baseboard_fab2(sch_1):page46_i14:ck1p" )
			)
			( pin "J6U1.60"
				( objectStatus "@baseboard_fab2_lib.baseboard_fab2(sch_1):page46_i14:cke(0)" )
			)
			( pin "J6U1.203"
				( objectStatus "@baseboard_fab2_lib.baseboard_fab2(sch_1):page46_i14:cke(1)" )
			)
			( pin "J6U1.5"
				( objectStatus "@baseboard_fab2_lib.baseboard_fab2(sch_1):page46_i14:dq(0)" )
			)
			( pin "J6U1.150"
				( objectStatus "@baseboard_fab2_lib.baseboard_fab2(sch_1):page46_i14:dq(1)" )
			)
			( pin "J6U1.12"
				( objectStatus "@baseboard_fab2_lib.baseboard_fab2(sch_1):page46_i14:dq(2)" )
			)
			( pin "J6U1.157"
				( objectStatus "@baseboard_fab2_lib.baseboard_fab2(sch_1):page46_i14:dq(3)" )
			)
			( pin "J6U1.3"
				( objectStatus "@baseboard_fab2_lib.baseboard_fab2(sch_1):page46_i14:dq(4)" )
			)
			( pin "J6U1.148"
				( objectStatus "@baseboard_fab2_lib.baseboard_fab2(sch_1):page46_i14:dq(5)" )
			)
			( pin "J6U1.10"
				( objectStatus "@baseboard_fab2_lib.baseboard_fab2(sch_1):page46_i14:dq(6)" )
			)
			( pin "J6U1.155"
				( objectStatus "@baseboard_fab2_lib.baseboard_fab2(sch_1):page46_i14:dq(7)" )
			)
			( pin "J6U1.16"
				( objectStatus "@baseboard_fab2_lib.baseboard_fab2(sch_1):page46_i14:dq(8)" )
			)
			( pin "J6U1.161"
				( objectStatus "@baseboard_fab2_lib.baseboard_fab2(sch_1):page46_i14:dq(9)" )
			)
			( pin "J6U1.23"
				( objectStatus "@baseboard_fab2_lib.baseboard_fab2(sch_1):page46_i14:dq(10)" )
			)
			( pin "J6U1.168"
				( objectStatus "@baseboard_fab2_lib.baseboard_fab2(sch_1):page46_i14:dq(11)" )
			)
			( pin "J6U1.14"
				( objectStatus "@baseboard_fab2_lib.baseboard_fab2(sch_1):page46_i14:dq(12)" )
			)
			( pin "J6U1.159"
				( objectStatus "@baseboard_fab2_lib.baseboard_fab2(sch_1):page46_i14:dq(13)" )
			)
			( pin "J6U1.21"
				( objectStatus "@baseboard_fab2_lib.baseboard_fab2(sch_1):page46_i14:dq(14)" )
			)
			( pin "J6U1.166"
				( objectStatus "@baseboard_fab2_lib.baseboard_fab2(sch_1):page46_i14:dq(15)" )
			)
			( pin "J6U1.27"
				( objectStatus "@baseboard_fab2_lib.baseboard_fab2(sch_1):page46_i14:dq(16)" )
			)
			( pin "J6U1.172"
				( objectStatus "@baseboard_fab2_lib.baseboard_fab2(sch_1):page46_i14:dq(17)" )
			)
			( pin "J6U1.34"
				( objectStatus "@baseboard_fab2_lib.baseboard_fab2(sch_1):page46_i14:dq(18)" )
			)
			( pin "J6U1.179"
				( objectStatus "@baseboard_fab2_lib.baseboard_fab2(sch_1):page46_i14:dq(19)" )
			)
			( pin "J6U1.25"
				( objectStatus "@baseboard_fab2_lib.baseboard_fab2(sch_1):page46_i14:dq(20)" )
			)
			( pin "J6U1.170"
				( objectStatus "@baseboard_fab2_lib.baseboard_fab2(sch_1):page46_i14:dq(21)" )
			)
			( pin "J6U1.32"
				( objectStatus "@baseboard_fab2_lib.baseboard_fab2(sch_1):page46_i14:dq(22)" )
			)
			( pin "J6U1.177"
				( objectStatus "@baseboard_fab2_lib.baseboard_fab2(sch_1):page46_i14:dq(23)" )
			)
			( pin "J6U1.38"
				( objectStatus "@baseboard_fab2_lib.baseboard_fab2(sch_1):page46_i14:dq(24)" )
			)
			( pin "J6U1.183"
				( objectStatus "@baseboard_fab2_lib.baseboard_fab2(sch_1):page46_i14:dq(25)" )
			)
			( pin "J6U1.45"
				( objectStatus "@baseboard_fab2_lib.baseboard_fab2(sch_1):page46_i14:dq(26)" )
			)
			( pin "J6U1.190"
				( objectStatus "@baseboard_fab2_lib.baseboard_fab2(sch_1):page46_i14:dq(27)" )
			)
			( pin "J6U1.36"
				( objectStatus "@baseboard_fab2_lib.baseboard_fab2(sch_1):page46_i14:dq(28)" )
			)
			( pin "J6U1.181"
				( objectStatus "@baseboard_fab2_lib.baseboard_fab2(sch_1):page46_i14:dq(29)" )
			)
			( pin "J6U1.43"
				( objectStatus "@baseboard_fab2_lib.baseboard_fab2(sch_1):page46_i14:dq(30)" )
			)
			( pin "J6U1.188"
				( objectStatus "@baseboard_fab2_lib.baseboard_fab2(sch_1):page46_i14:dq(31)" )
			)
			( pin "J6U1.97"
				( objectStatus "@baseboard_fab2_lib.baseboard_fab2(sch_1):page46_i14:dq(32)" )
			)
			( pin "J6U1.242"
				( objectStatus "@baseboard_fab2_lib.baseboard_fab2(sch_1):page46_i14:dq(33)" )
			)
			( pin "J6U1.104"
				( objectStatus "@baseboard_fab2_lib.baseboard_fab2(sch_1):page46_i14:dq(34)" )
			)
			( pin "J6U1.249"
				( objectStatus "@baseboard_fab2_lib.baseboard_fab2(sch_1):page46_i14:dq(35)" )
			)
			( pin "J6U1.95"
				( objectStatus "@baseboard_fab2_lib.baseboard_fab2(sch_1):page46_i14:dq(36)" )
			)
			( pin "J6U1.240"
				( objectStatus "@baseboard_fab2_lib.baseboard_fab2(sch_1):page46_i14:dq(37)" )
			)
			( pin "J6U1.102"
				( objectStatus "@baseboard_fab2_lib.baseboard_fab2(sch_1):page46_i14:dq(38)" )
			)
			( pin "J6U1.247"
				( objectStatus "@baseboard_fab2_lib.baseboard_fab2(sch_1):page46_i14:dq(39)" )
			)
			( pin "J6U1.108"
				( objectStatus "@baseboard_fab2_lib.baseboard_fab2(sch_1):page46_i14:dq(40)" )
			)
			( pin "J6U1.253"
				( objectStatus "@baseboard_fab2_lib.baseboard_fab2(sch_1):page46_i14:dq(41)" )
			)
			( pin "J6U1.115"
				( objectStatus "@baseboard_fab2_lib.baseboard_fab2(sch_1):page46_i14:dq(42)" )
			)
			( pin "J6U1.260"
				( objectStatus "@baseboard_fab2_lib.baseboard_fab2(sch_1):page46_i14:dq(43)" )
			)
			( pin "J6U1.106"
				( objectStatus "@baseboard_fab2_lib.baseboard_fab2(sch_1):page46_i14:dq(44)" )
			)
			( pin "J6U1.251"
				( objectStatus "@baseboard_fab2_lib.baseboard_fab2(sch_1):page46_i14:dq(45)" )
			)
			( pin "J6U1.113"
				( objectStatus "@baseboard_fab2_lib.baseboard_fab2(sch_1):page46_i14:dq(46)" )
			)
			( pin "J6U1.258"
				( objectStatus "@baseboard_fab2_lib.baseboard_fab2(sch_1):page46_i14:dq(47)" )
			)
			( pin "J6U1.119"
				( objectStatus "@baseboard_fab2_lib.baseboard_fab2(sch_1):page46_i14:dq(48)" )
			)
			( pin "J6U1.264"
				( objectStatus "@baseboard_fab2_lib.baseboard_fab2(sch_1):page46_i14:dq(49)" )
			)
			( pin "J6U1.126"
				( objectStatus "@baseboard_fab2_lib.baseboard_fab2(sch_1):page46_i14:dq(50)" )
			)
			( pin "J6U1.271"
				( objectStatus "@baseboard_fab2_lib.baseboard_fab2(sch_1):page46_i14:dq(51)" )
			)
			( pin "J6U1.117"
				( objectStatus "@baseboard_fab2_lib.baseboard_fab2(sch_1):page46_i14:dq(52)" )
			)
			( pin "J6U1.262"
				( objectStatus "@baseboard_fab2_lib.baseboard_fab2(sch_1):page46_i14:dq(53)" )
			)
			( pin "J6U1.124"
				( objectStatus "@baseboard_fab2_lib.baseboard_fab2(sch_1):page46_i14:dq(54)" )
			)
			( pin "J6U1.269"
				( objectStatus "@baseboard_fab2_lib.baseboard_fab2(sch_1):page46_i14:dq(55)" )
			)
			( pin "J6U1.130"
				( objectStatus "@baseboard_fab2_lib.baseboard_fab2(sch_1):page46_i14:dq(56)" )
			)
			( pin "J6U1.275"
				( objectStatus "@baseboard_fab2_lib.baseboard_fab2(sch_1):page46_i14:dq(57)" )
			)
			( pin "J6U1.137"
				( objectStatus "@baseboard_fab2_lib.baseboard_fab2(sch_1):page46_i14:dq(58)" )
			)
			( pin "J6U1.282"
				( objectStatus "@baseboard_fab2_lib.baseboard_fab2(sch_1):page46_i14:dq(59)" )
			)
			( pin "J6U1.128"
				( objectStatus "@baseboard_fab2_lib.baseboard_fab2(sch_1):page46_i14:dq(60)" )
			)
			( pin "J6U1.273"
				( objectStatus "@baseboard_fab2_lib.baseboard_fab2(sch_1):page46_i14:dq(61)" )
			)
			( pin "J6U1.135"
				( objectStatus "@baseboard_fab2_lib.baseboard_fab2(sch_1):page46_i14:dq(62)" )
			)
			( pin "J6U1.280"
				( objectStatus "@baseboard_fab2_lib.baseboard_fab2(sch_1):page46_i14:dq(63)" )
			)
			( pin "J6U1.78"
				( objectStatus "@baseboard_fab2_lib.baseboard_fab2(sch_1):page46_i14:event_n" )
			)
			( pin "J6U1.87"
				( objectStatus "@baseboard_fab2_lib.baseboard_fab2(sch_1):page46_i14:odt(0)" )
			)
			( pin "J6U1.91"
				( objectStatus "@baseboard_fab2_lib.baseboard_fab2(sch_1):page46_i14:odt(1)" )
			)
			( pin "J6U1.222"
				( objectStatus "@baseboard_fab2_lib.baseboard_fab2(sch_1):page46_i14:par" )
			)
			( pin "J6U1.58"
				( objectStatus "@baseboard_fab2_lib.baseboard_fab2(sch_1):page46_i14:reset_n" )
			)
			( pin "J6U1.205"
				( objectStatus "@baseboard_fab2_lib.baseboard_fab2(sch_1):page46_i14:rfu(0)" )
			)
			( pin "J6U1.227"
				( objectStatus "@baseboard_fab2_lib.baseboard_fab2(sch_1):page46_i14:rfu(1)" )
			)
			( pin "J6U1.144"
				( objectStatus "@baseboard_fab2_lib.baseboard_fab2(sch_1):page46_i14:rfu(2)" )
			)
			( pin "J6U1.84"
				( objectStatus "@baseboard_fab2_lib.baseboard_fab2(sch_1):page46_i14:s0_n" )
			)
			( pin "J6U1.89"
				( objectStatus "@baseboard_fab2_lib.baseboard_fab2(sch_1):page46_i14:s1_n" )
			)
			( pin "J6U1.93"
				( objectStatus "@baseboard_fab2_lib.baseboard_fab2(sch_1):page46_i14:s2_n_c(0)" )
			)
			( pin "J6U1.237"
				( objectStatus "@baseboard_fab2_lib.baseboard_fab2(sch_1):page46_i14:s3_n_c(1)" )
			)
			( pin "J6U1.139"
				( objectStatus "@baseboard_fab2_lib.baseboard_fab2(sch_1):page46_i14:sa(0)" )
			)
			( pin "J6U1.140"
				( objectStatus "@baseboard_fab2_lib.baseboard_fab2(sch_1):page46_i14:sa(1)" )
			)
			( pin "J6U1.238"
				( objectStatus "@baseboard_fab2_lib.baseboard_fab2(sch_1):page46_i14:sa(2)" )
			)
			( pin "J6U1.230"
				( objectStatus "@baseboard_fab2_lib.baseboard_fab2(sch_1):page46_i14:save_n_nc" )
			)
			( pin "J6U1.141"
				( objectStatus "@baseboard_fab2_lib.baseboard_fab2(sch_1):page46_i14:scl" )
			)
			( pin "J6U1.285"
				( objectStatus "@baseboard_fab2_lib.baseboard_fab2(sch_1):page46_i14:sda" )
			)
			( pin "J6U1.284"
				( objectStatus "@baseboard_fab2_lib.baseboard_fab2(sch_1):page46_i14:vddspd" )
			)
			( pin "J6U1.146"
				( objectStatus "@baseboard_fab2_lib.baseboard_fab2(sch_1):page46_i14:vrefca" )
			)
			( pin "J6U1.145"
				( objectStatus "@baseboard_fab2_lib.baseboard_fab2(sch_1):page46_i67:\12v\(0)" )
			)
			( pin "J6U1.1"
				( objectStatus "@baseboard_fab2_lib.baseboard_fab2(sch_1):page46_i67:\12v\(1)" )
			)
			( pin "J6U1.236"
				( objectStatus "@baseboard_fab2_lib.baseboard_fab2(sch_1):page46_i67:vdd(0)" )
			)
			( pin "J6U1.233"
				( objectStatus "@baseboard_fab2_lib.baseboard_fab2(sch_1):page46_i67:vdd(1)" )
			)
			( pin "J6U1.231"
				( objectStatus "@baseboard_fab2_lib.baseboard_fab2(sch_1):page46_i67:vdd(2)" )
			)
			( pin "J6U1.229"
				( objectStatus "@baseboard_fab2_lib.baseboard_fab2(sch_1):page46_i67:vdd(3)" )
			)
			( pin "J6U1.226"
				( objectStatus "@baseboard_fab2_lib.baseboard_fab2(sch_1):page46_i67:vdd(4)" )
			)
			( pin "J6U1.223"
				( objectStatus "@baseboard_fab2_lib.baseboard_fab2(sch_1):page46_i67:vdd(5)" )
			)
			( pin "J6U1.220"
				( objectStatus "@baseboard_fab2_lib.baseboard_fab2(sch_1):page46_i67:vdd(6)" )
			)
			( pin "J6U1.217"
				( objectStatus "@baseboard_fab2_lib.baseboard_fab2(sch_1):page46_i67:vdd(7)" )
			)
			( pin "J6U1.215"
				( objectStatus "@baseboard_fab2_lib.baseboard_fab2(sch_1):page46_i67:vdd(8)" )
			)
			( pin "J6U1.212"
				( objectStatus "@baseboard_fab2_lib.baseboard_fab2(sch_1):page46_i67:vdd(9)" )
			)
			( pin "J6U1.209"
				( objectStatus "@baseboard_fab2_lib.baseboard_fab2(sch_1):page46_i67:vdd(10)" )
			)
			( pin "J6U1.206"
				( objectStatus "@baseboard_fab2_lib.baseboard_fab2(sch_1):page46_i67:vdd(11)" )
			)
			( pin "J6U1.204"
				( objectStatus "@baseboard_fab2_lib.baseboard_fab2(sch_1):page46_i67:vdd(12)" )
			)
			( pin "J6U1.92"
				( objectStatus "@baseboard_fab2_lib.baseboard_fab2(sch_1):page46_i67:vdd(13)" )
			)
			( pin "J6U1.90"
				( objectStatus "@baseboard_fab2_lib.baseboard_fab2(sch_1):page46_i67:vdd(14)" )
			)
			( pin "J6U1.88"
				( objectStatus "@baseboard_fab2_lib.baseboard_fab2(sch_1):page46_i67:vdd(15)" )
			)
			( pin "J6U1.85"
				( objectStatus "@baseboard_fab2_lib.baseboard_fab2(sch_1):page46_i67:vdd(16)" )
			)
			( pin "J6U1.83"
				( objectStatus "@baseboard_fab2_lib.baseboard_fab2(sch_1):page46_i67:vdd(17)" )
			)
			( pin "J6U1.80"
				( objectStatus "@baseboard_fab2_lib.baseboard_fab2(sch_1):page46_i67:vdd(18)" )
			)
			( pin "J6U1.76"
				( objectStatus "@baseboard_fab2_lib.baseboard_fab2(sch_1):page46_i67:vdd(19)" )
			)
			( pin "J6U1.73"
				( objectStatus "@baseboard_fab2_lib.baseboard_fab2(sch_1):page46_i67:vdd(20)" )
			)
			( pin "J6U1.70"
				( objectStatus "@baseboard_fab2_lib.baseboard_fab2(sch_1):page46_i67:vdd(21)" )
			)
			( pin "J6U1.67"
				( objectStatus "@baseboard_fab2_lib.baseboard_fab2(sch_1):page46_i67:vdd(22)" )
			)
			( pin "J6U1.64"
				( objectStatus "@baseboard_fab2_lib.baseboard_fab2(sch_1):page46_i67:vdd(23)" )
			)
			( pin "J6U1.61"
				( objectStatus "@baseboard_fab2_lib.baseboard_fab2(sch_1):page46_i67:vdd(24)" )
			)
			( pin "J6U1.59"
				( objectStatus "@baseboard_fab2_lib.baseboard_fab2(sch_1):page46_i67:vdd(25)" )
			)
			( pin "J6U1.287"
				( objectStatus "@baseboard_fab2_lib.baseboard_fab2(sch_1):page46_i67:vpp(0)" )
			)
			( pin "J6U1.286"
				( objectStatus "@baseboard_fab2_lib.baseboard_fab2(sch_1):page46_i67:vpp(1)" )
			)
			( pin "J6U1.288"
				( objectStatus "@baseboard_fab2_lib.baseboard_fab2(sch_1):page46_i67:vpp(2)" )
			)
			( pin "J6U1.143"
				( objectStatus "@baseboard_fab2_lib.baseboard_fab2(sch_1):page46_i67:vpp(3)" )
			)
			( pin "J6U1.142"
				( objectStatus "@baseboard_fab2_lib.baseboard_fab2(sch_1):page46_i67:vpp(4)" )
			)
			( pin "J6U1.221"
				( objectStatus "@baseboard_fab2_lib.baseboard_fab2(sch_1):page46_i67:vtt(0)" )
			)
			( pin "J6U1.77"
				( objectStatus "@baseboard_fab2_lib.baseboard_fab2(sch_1):page46_i67:vtt(1)" )
			)
			( pin "J6U1.152"
				( objectStatus "@baseboard_fab2_lib.baseboard_fab2(sch_1):page46_i112:dqs0n" )
			)
			( pin "J6U1.153"
				( objectStatus "@baseboard_fab2_lib.baseboard_fab2(sch_1):page46_i112:dqs0p" )
			)
			( pin "J6U1.163"
				( objectStatus "@baseboard_fab2_lib.baseboard_fab2(sch_1):page46_i112:dqs1n" )
			)
			( pin "J6U1.164"
				( objectStatus "@baseboard_fab2_lib.baseboard_fab2(sch_1):page46_i112:dqs1p" )
			)
			( pin "J6U1.174"
				( objectStatus "@baseboard_fab2_lib.baseboard_fab2(sch_1):page46_i112:dqs2n" )
			)
			( pin "J6U1.175"
				( objectStatus "@baseboard_fab2_lib.baseboard_fab2(sch_1):page46_i112:dqs2p" )
			)
			( pin "J6U1.185"
				( objectStatus "@baseboard_fab2_lib.baseboard_fab2(sch_1):page46_i112:dqs3n" )
			)
			( pin "J6U1.186"
				( objectStatus "@baseboard_fab2_lib.baseboard_fab2(sch_1):page46_i112:dqs3p" )
			)
			( pin "J6U1.244"
				( objectStatus "@baseboard_fab2_lib.baseboard_fab2(sch_1):page46_i112:dqs4n" )
			)
			( pin "J6U1.245"
				( objectStatus "@baseboard_fab2_lib.baseboard_fab2(sch_1):page46_i112:dqs4p" )
			)
			( pin "J6U1.255"
				( objectStatus "@baseboard_fab2_lib.baseboard_fab2(sch_1):page46_i112:dqs5n" )
			)
			( pin "J6U1.256"
				( objectStatus "@baseboard_fab2_lib.baseboard_fab2(sch_1):page46_i112:dqs5p" )
			)
			( pin "J6U1.266"
				( objectStatus "@baseboard_fab2_lib.baseboard_fab2(sch_1):page46_i112:dqs6n" )
			)
			( pin "J6U1.267"
				( objectStatus "@baseboard_fab2_lib.baseboard_fab2(sch_1):page46_i112:dqs6p" )
			)
			( pin "J6U1.277"
				( objectStatus "@baseboard_fab2_lib.baseboard_fab2(sch_1):page46_i112:dqs7n" )
			)
			( pin "J6U1.278"
				( objectStatus "@baseboard_fab2_lib.baseboard_fab2(sch_1):page46_i112:dqs7p" )
			)
			( pin "J6U1.196"
				( objectStatus "@baseboard_fab2_lib.baseboard_fab2(sch_1):page46_i112:dqs8n" )
			)
			( pin "J6U1.197"
				( objectStatus "@baseboard_fab2_lib.baseboard_fab2(sch_1):page46_i112:dqs8p" )
			)
			( pin "J6U1.8"
				( objectStatus "@baseboard_fab2_lib.baseboard_fab2(sch_1):page46_i112:dqs9n" )
			)
			( pin "J6U1.7"
				( objectStatus "@baseboard_fab2_lib.baseboard_fab2(sch_1):page46_i112:dqs9p" )
			)
			( pin "J6U1.19"
				( objectStatus "@baseboard_fab2_lib.baseboard_fab2(sch_1):page46_i112:dqs10n" )
			)
			( pin "J6U1.18"
				( objectStatus "@baseboard_fab2_lib.baseboard_fab2(sch_1):page46_i112:dqs10p" )
			)
			( pin "J6U1.30"
				( objectStatus "@baseboard_fab2_lib.baseboard_fab2(sch_1):page46_i112:dqs11n" )
			)
			( pin "J6U1.29"
				( objectStatus "@baseboard_fab2_lib.baseboard_fab2(sch_1):page46_i112:dqs11p" )
			)
			( pin "J6U1.41"
				( objectStatus "@baseboard_fab2_lib.baseboard_fab2(sch_1):page46_i112:dqs12n" )
			)
			( pin "J6U1.40"
				( objectStatus "@baseboard_fab2_lib.baseboard_fab2(sch_1):page46_i112:dqs12p" )
			)
			( pin "J6U1.100"
				( objectStatus "@baseboard_fab2_lib.baseboard_fab2(sch_1):page46_i112:dqs13n" )
			)
			( pin "J6U1.99"
				( objectStatus "@baseboard_fab2_lib.baseboard_fab2(sch_1):page46_i112:dqs13p" )
			)
			( pin "J6U1.111"
				( objectStatus "@baseboard_fab2_lib.baseboard_fab2(sch_1):page46_i112:dqs14n" )
			)
			( pin "J6U1.110"
				( objectStatus "@baseboard_fab2_lib.baseboard_fab2(sch_1):page46_i112:dqs14p" )
			)
			( pin "J6U1.122"
				( objectStatus "@baseboard_fab2_lib.baseboard_fab2(sch_1):page46_i112:dqs15n" )
			)
			( pin "J6U1.121"
				( objectStatus "@baseboard_fab2_lib.baseboard_fab2(sch_1):page46_i112:dqs15p" )
			)
			( pin "J6U1.133"
				( objectStatus "@baseboard_fab2_lib.baseboard_fab2(sch_1):page46_i112:dqs16n" )
			)
			( pin "J6U1.132"
				( objectStatus "@baseboard_fab2_lib.baseboard_fab2(sch_1):page46_i112:dqs16p" )
			)
			( pin "J6U1.52"
				( objectStatus "@baseboard_fab2_lib.baseboard_fab2(sch_1):page46_i112:dqs17n" )
			)
			( pin "J6U1.51"
				( objectStatus "@baseboard_fab2_lib.baseboard_fab2(sch_1):page46_i112:dqs17p" )
			)
			( pin "J6U1.283"
				( objectStatus "@baseboard_fab2_lib.baseboard_fab2(sch_1):page46_i138:vss(0)" )
			)
			( pin "J6U1.281"
				( objectStatus "@baseboard_fab2_lib.baseboard_fab2(sch_1):page46_i138:vss(1)" )
			)
			( pin "J6U1.279"
				( objectStatus "@baseboard_fab2_lib.baseboard_fab2(sch_1):page46_i138:vss(2)" )
			)
			( pin "J6U1.276"
				( objectStatus "@baseboard_fab2_lib.baseboard_fab2(sch_1):page46_i138:vss(3)" )
			)
			( pin "J6U1.274"
				( objectStatus "@baseboard_fab2_lib.baseboard_fab2(sch_1):page46_i138:vss(4)" )
			)
			( pin "J6U1.272"
				( objectStatus "@baseboard_fab2_lib.baseboard_fab2(sch_1):page46_i138:vss(5)" )
			)
			( pin "J6U1.270"
				( objectStatus "@baseboard_fab2_lib.baseboard_fab2(sch_1):page46_i138:vss(6)" )
			)
			( pin "J6U1.268"
				( objectStatus "@baseboard_fab2_lib.baseboard_fab2(sch_1):page46_i138:vss(7)" )
			)
			( pin "J6U1.265"
				( objectStatus "@baseboard_fab2_lib.baseboard_fab2(sch_1):page46_i138:vss(8)" )
			)
			( pin "J6U1.263"
				( objectStatus "@baseboard_fab2_lib.baseboard_fab2(sch_1):page46_i138:vss(9)" )
			)
			( pin "J6U1.261"
				( objectStatus "@baseboard_fab2_lib.baseboard_fab2(sch_1):page46_i138:vss(10)" )
			)
			( pin "J6U1.259"
				( objectStatus "@baseboard_fab2_lib.baseboard_fab2(sch_1):page46_i138:vss(11)" )
			)
			( pin "J6U1.257"
				( objectStatus "@baseboard_fab2_lib.baseboard_fab2(sch_1):page46_i138:vss(12)" )
			)
			( pin "J6U1.254"
				( objectStatus "@baseboard_fab2_lib.baseboard_fab2(sch_1):page46_i138:vss(13)" )
			)
			( pin "J6U1.252"
				( objectStatus "@baseboard_fab2_lib.baseboard_fab2(sch_1):page46_i138:vss(14)" )
			)
			( pin "J6U1.250"
				( objectStatus "@baseboard_fab2_lib.baseboard_fab2(sch_1):page46_i138:vss(15)" )
			)
			( pin "J6U1.248"
				( objectStatus "@baseboard_fab2_lib.baseboard_fab2(sch_1):page46_i138:vss(16)" )
			)
			( pin "J6U1.246"
				( objectStatus "@baseboard_fab2_lib.baseboard_fab2(sch_1):page46_i138:vss(17)" )
			)
			( pin "J6U1.243"
				( objectStatus "@baseboard_fab2_lib.baseboard_fab2(sch_1):page46_i138:vss(18)" )
			)
			( pin "J6U1.241"
				( objectStatus "@baseboard_fab2_lib.baseboard_fab2(sch_1):page46_i138:vss(19)" )
			)
			( pin "J6U1.239"
				( objectStatus "@baseboard_fab2_lib.baseboard_fab2(sch_1):page46_i138:vss(20)" )
			)
			( pin "J6U1.202"
				( objectStatus "@baseboard_fab2_lib.baseboard_fab2(sch_1):page46_i138:vss(21)" )
			)
			( pin "J6U1.200"
				( objectStatus "@baseboard_fab2_lib.baseboard_fab2(sch_1):page46_i138:vss(22)" )
			)
			( pin "J6U1.198"
				( objectStatus "@baseboard_fab2_lib.baseboard_fab2(sch_1):page46_i138:vss(23)" )
			)
			( pin "J6U1.195"
				( objectStatus "@baseboard_fab2_lib.baseboard_fab2(sch_1):page46_i138:vss(24)" )
			)
			( pin "J6U1.193"
				( objectStatus "@baseboard_fab2_lib.baseboard_fab2(sch_1):page46_i138:vss(25)" )
			)
			( pin "J6U1.191"
				( objectStatus "@baseboard_fab2_lib.baseboard_fab2(sch_1):page46_i138:vss(26)" )
			)
			( pin "J6U1.189"
				( objectStatus "@baseboard_fab2_lib.baseboard_fab2(sch_1):page46_i138:vss(27)" )
			)
			( pin "J6U1.187"
				( objectStatus "@baseboard_fab2_lib.baseboard_fab2(sch_1):page46_i138:vss(28)" )
			)
			( pin "J6U1.184"
				( objectStatus "@baseboard_fab2_lib.baseboard_fab2(sch_1):page46_i138:vss(29)" )
			)
			( pin "J6U1.182"
				( objectStatus "@baseboard_fab2_lib.baseboard_fab2(sch_1):page46_i138:vss(30)" )
			)
			( pin "J6U1.180"
				( objectStatus "@baseboard_fab2_lib.baseboard_fab2(sch_1):page46_i138:vss(31)" )
			)
			( pin "J6U1.178"
				( objectStatus "@baseboard_fab2_lib.baseboard_fab2(sch_1):page46_i138:vss(32)" )
			)
			( pin "J6U1.176"
				( objectStatus "@baseboard_fab2_lib.baseboard_fab2(sch_1):page46_i138:vss(33)" )
			)
			( pin "J6U1.173"
				( objectStatus "@baseboard_fab2_lib.baseboard_fab2(sch_1):page46_i138:vss(34)" )
			)
			( pin "J6U1.171"
				( objectStatus "@baseboard_fab2_lib.baseboard_fab2(sch_1):page46_i138:vss(35)" )
			)
			( pin "J6U1.169"
				( objectStatus "@baseboard_fab2_lib.baseboard_fab2(sch_1):page46_i138:vss(36)" )
			)
			( pin "J6U1.167"
				( objectStatus "@baseboard_fab2_lib.baseboard_fab2(sch_1):page46_i138:vss(37)" )
			)
			( pin "J6U1.165"
				( objectStatus "@baseboard_fab2_lib.baseboard_fab2(sch_1):page46_i138:vss(38)" )
			)
			( pin "J6U1.162"
				( objectStatus "@baseboard_fab2_lib.baseboard_fab2(sch_1):page46_i138:vss(39)" )
			)
			( pin "J6U1.160"
				( objectStatus "@baseboard_fab2_lib.baseboard_fab2(sch_1):page46_i138:vss(40)" )
			)
			( pin "J6U1.158"
				( objectStatus "@baseboard_fab2_lib.baseboard_fab2(sch_1):page46_i138:vss(41)" )
			)
			( pin "J6U1.156"
				( objectStatus "@baseboard_fab2_lib.baseboard_fab2(sch_1):page46_i138:vss(42)" )
			)
			( pin "J6U1.154"
				( objectStatus "@baseboard_fab2_lib.baseboard_fab2(sch_1):page46_i138:vss(43)" )
			)
			( pin "J6U1.151"
				( objectStatus "@baseboard_fab2_lib.baseboard_fab2(sch_1):page46_i138:vss(44)" )
			)
			( pin "J6U1.149"
				( objectStatus "@baseboard_fab2_lib.baseboard_fab2(sch_1):page46_i138:vss(45)" )
			)
			( pin "J6U1.147"
				( objectStatus "@baseboard_fab2_lib.baseboard_fab2(sch_1):page46_i138:vss(46)" )
			)
			( pin "J6U1.138"
				( objectStatus "@baseboard_fab2_lib.baseboard_fab2(sch_1):page46_i138:vss(47)" )
			)
			( pin "J6U1.136"
				( objectStatus "@baseboard_fab2_lib.baseboard_fab2(sch_1):page46_i138:vss(48)" )
			)
			( pin "J6U1.134"
				( objectStatus "@baseboard_fab2_lib.baseboard_fab2(sch_1):page46_i138:vss(49)" )
			)
			( pin "J6U1.131"
				( objectStatus "@baseboard_fab2_lib.baseboard_fab2(sch_1):page46_i138:vss(50)" )
			)
			( pin "J6U1.129"
				( objectStatus "@baseboard_fab2_lib.baseboard_fab2(sch_1):page46_i138:vss(51)" )
			)
			( pin "J6U1.127"
				( objectStatus "@baseboard_fab2_lib.baseboard_fab2(sch_1):page46_i138:vss(52)" )
			)
			( pin "J6U1.125"
				( objectStatus "@baseboard_fab2_lib.baseboard_fab2(sch_1):page46_i138:vss(53)" )
			)
			( pin "J6U1.123"
				( objectStatus "@baseboard_fab2_lib.baseboard_fab2(sch_1):page46_i138:vss(54)" )
			)
			( pin "J6U1.120"
				( objectStatus "@baseboard_fab2_lib.baseboard_fab2(sch_1):page46_i138:vss(55)" )
			)
			( pin "J6U1.118"
				( objectStatus "@baseboard_fab2_lib.baseboard_fab2(sch_1):page46_i138:vss(56)" )
			)
			( pin "J6U1.116"
				( objectStatus "@baseboard_fab2_lib.baseboard_fab2(sch_1):page46_i138:vss(57)" )
			)
			( pin "J6U1.114"
				( objectStatus "@baseboard_fab2_lib.baseboard_fab2(sch_1):page46_i138:vss(58)" )
			)
			( pin "J6U1.112"
				( objectStatus "@baseboard_fab2_lib.baseboard_fab2(sch_1):page46_i138:vss(59)" )
			)
			( pin "J6U1.109"
				( objectStatus "@baseboard_fab2_lib.baseboard_fab2(sch_1):page46_i138:vss(60)" )
			)
			( pin "J6U1.107"
				( objectStatus "@baseboard_fab2_lib.baseboard_fab2(sch_1):page46_i138:vss(61)" )
			)
			( pin "J6U1.105"
				( objectStatus "@baseboard_fab2_lib.baseboard_fab2(sch_1):page46_i138:vss(62)" )
			)
			( pin "J6U1.103"
				( objectStatus "@baseboard_fab2_lib.baseboard_fab2(sch_1):page46_i138:vss(63)" )
			)
			( pin "J6U1.101"
				( objectStatus "@baseboard_fab2_lib.baseboard_fab2(sch_1):page46_i138:vss(64)" )
			)
			( pin "J6U1.98"
				( objectStatus "@baseboard_fab2_lib.baseboard_fab2(sch_1):page46_i138:vss(65)" )
			)
			( pin "J6U1.96"
				( objectStatus "@baseboard_fab2_lib.baseboard_fab2(sch_1):page46_i138:vss(66)" )
			)
			( pin "J6U1.94"
				( objectStatus "@baseboard_fab2_lib.baseboard_fab2(sch_1):page46_i138:vss(67)" )
			)
			( pin "J6U1.57"
				( objectStatus "@baseboard_fab2_lib.baseboard_fab2(sch_1):page46_i138:vss(68)" )
			)
			( pin "J6U1.55"
				( objectStatus "@baseboard_fab2_lib.baseboard_fab2(sch_1):page46_i138:vss(69)" )
			)
			( pin "J6U1.53"
				( objectStatus "@baseboard_fab2_lib.baseboard_fab2(sch_1):page46_i138:vss(70)" )
			)
			( pin "J6U1.50"
				( objectStatus "@baseboard_fab2_lib.baseboard_fab2(sch_1):page46_i138:vss(71)" )
			)
			( pin "J6U1.48"
				( objectStatus "@baseboard_fab2_lib.baseboard_fab2(sch_1):page46_i138:vss(72)" )
			)
			( pin "J6U1.46"
				( objectStatus "@baseboard_fab2_lib.baseboard_fab2(sch_1):page46_i138:vss(73)" )
			)
			( pin "J6U1.44"
				( objectStatus "@baseboard_fab2_lib.baseboard_fab2(sch_1):page46_i138:vss(74)" )
			)
			( pin "J6U1.42"
				( objectStatus "@baseboard_fab2_lib.baseboard_fab2(sch_1):page46_i138:vss(75)" )
			)
			( pin "J6U1.39"
				( objectStatus "@baseboard_fab2_lib.baseboard_fab2(sch_1):page46_i138:vss(76)" )
			)
			( pin "J6U1.37"
				( objectStatus "@baseboard_fab2_lib.baseboard_fab2(sch_1):page46_i138:vss(77)" )
			)
			( pin "J6U1.35"
				( objectStatus "@baseboard_fab2_lib.baseboard_fab2(sch_1):page46_i138:vss(78)" )
			)
			( pin "J6U1.33"
				( objectStatus "@baseboard_fab2_lib.baseboard_fab2(sch_1):page46_i138:vss(79)" )
			)
			( pin "J6U1.31"
				( objectStatus "@baseboard_fab2_lib.baseboard_fab2(sch_1):page46_i138:vss(80)" )
			)
			( pin "J6U1.28"
				( objectStatus "@baseboard_fab2_lib.baseboard_fab2(sch_1):page46_i138:vss(81)" )
			)
			( pin "J6U1.26"
				( objectStatus "@baseboard_fab2_lib.baseboard_fab2(sch_1):page46_i138:vss(82)" )
			)
			( pin "J6U1.24"
				( objectStatus "@baseboard_fab2_lib.baseboard_fab2(sch_1):page46_i138:vss(83)" )
			)
			( pin "J6U1.22"
				( objectStatus "@baseboard_fab2_lib.baseboard_fab2(sch_1):page46_i138:vss(84)" )
			)
			( pin "J6U1.20"
				( objectStatus "@baseboard_fab2_lib.baseboard_fab2(sch_1):page46_i138:vss(85)" )
			)
			( pin "J6U1.17"
				( objectStatus "@baseboard_fab2_lib.baseboard_fab2(sch_1):page46_i138:vss(86)" )
			)
			( pin "J6U1.15"
				( objectStatus "@baseboard_fab2_lib.baseboard_fab2(sch_1):page46_i138:vss(87)" )
			)
			( pin "J6U1.13"
				( objectStatus "@baseboard_fab2_lib.baseboard_fab2(sch_1):page46_i138:vss(88)" )
			)
			( pin "J6U1.11"
				( objectStatus "@baseboard_fab2_lib.baseboard_fab2(sch_1):page46_i138:vss(89)" )
			)
			( pin "J6U1.9"
				( objectStatus "@baseboard_fab2_lib.baseboard_fab2(sch_1):page46_i138:vss(90)" )
			)
			( pin "J6U1.6"
				( objectStatus "@baseboard_fab2_lib.baseboard_fab2(sch_1):page46_i138:vss(91)" )
			)
			( pin "J6U1.4"
				( objectStatus "@baseboard_fab2_lib.baseboard_fab2(sch_1):page46_i138:vss(92)" )
			)
			( pin "J6U1.2"
				( objectStatus "@baseboard_fab2_lib.baseboard_fab2(sch_1):page46_i138:vss(93)" )
			)
			( pin "J4G3.283"
				( objectStatus "@baseboard_fab2_lib.baseboard_fab2(sch_1):page47_i43:vss(0)" )
			)
			( pin "J4G3.281"
				( objectStatus "@baseboard_fab2_lib.baseboard_fab2(sch_1):page47_i43:vss(1)" )
			)
			( pin "J4G3.279"
				( objectStatus "@baseboard_fab2_lib.baseboard_fab2(sch_1):page47_i43:vss(2)" )
			)
			( pin "J4G3.276"
				( objectStatus "@baseboard_fab2_lib.baseboard_fab2(sch_1):page47_i43:vss(3)" )
			)
			( pin "J4G3.274"
				( objectStatus "@baseboard_fab2_lib.baseboard_fab2(sch_1):page47_i43:vss(4)" )
			)
			( pin "J4G3.272"
				( objectStatus "@baseboard_fab2_lib.baseboard_fab2(sch_1):page47_i43:vss(5)" )
			)
			( pin "J4G3.270"
				( objectStatus "@baseboard_fab2_lib.baseboard_fab2(sch_1):page47_i43:vss(6)" )
			)
			( pin "J4G3.268"
				( objectStatus "@baseboard_fab2_lib.baseboard_fab2(sch_1):page47_i43:vss(7)" )
			)
			( pin "J4G3.265"
				( objectStatus "@baseboard_fab2_lib.baseboard_fab2(sch_1):page47_i43:vss(8)" )
			)
			( pin "J4G3.263"
				( objectStatus "@baseboard_fab2_lib.baseboard_fab2(sch_1):page47_i43:vss(9)" )
			)
			( pin "J4G3.261"
				( objectStatus "@baseboard_fab2_lib.baseboard_fab2(sch_1):page47_i43:vss(10)" )
			)
			( pin "J4G3.259"
				( objectStatus "@baseboard_fab2_lib.baseboard_fab2(sch_1):page47_i43:vss(11)" )
			)
			( pin "J4G3.257"
				( objectStatus "@baseboard_fab2_lib.baseboard_fab2(sch_1):page47_i43:vss(12)" )
			)
			( pin "J4G3.254"
				( objectStatus "@baseboard_fab2_lib.baseboard_fab2(sch_1):page47_i43:vss(13)" )
			)
			( pin "J4G3.252"
				( objectStatus "@baseboard_fab2_lib.baseboard_fab2(sch_1):page47_i43:vss(14)" )
			)
			( pin "J4G3.250"
				( objectStatus "@baseboard_fab2_lib.baseboard_fab2(sch_1):page47_i43:vss(15)" )
			)
			( pin "J4G3.248"
				( objectStatus "@baseboard_fab2_lib.baseboard_fab2(sch_1):page47_i43:vss(16)" )
			)
			( pin "J4G3.246"
				( objectStatus "@baseboard_fab2_lib.baseboard_fab2(sch_1):page47_i43:vss(17)" )
			)
			( pin "J4G3.243"
				( objectStatus "@baseboard_fab2_lib.baseboard_fab2(sch_1):page47_i43:vss(18)" )
			)
			( pin "J4G3.241"
				( objectStatus "@baseboard_fab2_lib.baseboard_fab2(sch_1):page47_i43:vss(19)" )
			)
			( pin "J4G3.239"
				( objectStatus "@baseboard_fab2_lib.baseboard_fab2(sch_1):page47_i43:vss(20)" )
			)
			( pin "J4G3.202"
				( objectStatus "@baseboard_fab2_lib.baseboard_fab2(sch_1):page47_i43:vss(21)" )
			)
			( pin "J4G3.200"
				( objectStatus "@baseboard_fab2_lib.baseboard_fab2(sch_1):page47_i43:vss(22)" )
			)
			( pin "J4G3.198"
				( objectStatus "@baseboard_fab2_lib.baseboard_fab2(sch_1):page47_i43:vss(23)" )
			)
			( pin "J4G3.195"
				( objectStatus "@baseboard_fab2_lib.baseboard_fab2(sch_1):page47_i43:vss(24)" )
			)
			( pin "J4G3.193"
				( objectStatus "@baseboard_fab2_lib.baseboard_fab2(sch_1):page47_i43:vss(25)" )
			)
			( pin "J4G3.191"
				( objectStatus "@baseboard_fab2_lib.baseboard_fab2(sch_1):page47_i43:vss(26)" )
			)
			( pin "J4G3.189"
				( objectStatus "@baseboard_fab2_lib.baseboard_fab2(sch_1):page47_i43:vss(27)" )
			)
			( pin "J4G3.187"
				( objectStatus "@baseboard_fab2_lib.baseboard_fab2(sch_1):page47_i43:vss(28)" )
			)
			( pin "J4G3.184"
				( objectStatus "@baseboard_fab2_lib.baseboard_fab2(sch_1):page47_i43:vss(29)" )
			)
			( pin "J4G3.182"
				( objectStatus "@baseboard_fab2_lib.baseboard_fab2(sch_1):page47_i43:vss(30)" )
			)
			( pin "J4G3.180"
				( objectStatus "@baseboard_fab2_lib.baseboard_fab2(sch_1):page47_i43:vss(31)" )
			)
			( pin "J4G3.178"
				( objectStatus "@baseboard_fab2_lib.baseboard_fab2(sch_1):page47_i43:vss(32)" )
			)
			( pin "J4G3.176"
				( objectStatus "@baseboard_fab2_lib.baseboard_fab2(sch_1):page47_i43:vss(33)" )
			)
			( pin "J4G3.173"
				( objectStatus "@baseboard_fab2_lib.baseboard_fab2(sch_1):page47_i43:vss(34)" )
			)
			( pin "J4G3.171"
				( objectStatus "@baseboard_fab2_lib.baseboard_fab2(sch_1):page47_i43:vss(35)" )
			)
			( pin "J4G3.169"
				( objectStatus "@baseboard_fab2_lib.baseboard_fab2(sch_1):page47_i43:vss(36)" )
			)
			( pin "J4G3.167"
				( objectStatus "@baseboard_fab2_lib.baseboard_fab2(sch_1):page47_i43:vss(37)" )
			)
			( pin "J4G3.165"
				( objectStatus "@baseboard_fab2_lib.baseboard_fab2(sch_1):page47_i43:vss(38)" )
			)
			( pin "J4G3.162"
				( objectStatus "@baseboard_fab2_lib.baseboard_fab2(sch_1):page47_i43:vss(39)" )
			)
			( pin "J4G3.160"
				( objectStatus "@baseboard_fab2_lib.baseboard_fab2(sch_1):page47_i43:vss(40)" )
			)
			( pin "J4G3.158"
				( objectStatus "@baseboard_fab2_lib.baseboard_fab2(sch_1):page47_i43:vss(41)" )
			)
			( pin "J4G3.156"
				( objectStatus "@baseboard_fab2_lib.baseboard_fab2(sch_1):page47_i43:vss(42)" )
			)
			( pin "J4G3.154"
				( objectStatus "@baseboard_fab2_lib.baseboard_fab2(sch_1):page47_i43:vss(43)" )
			)
			( pin "J4G3.151"
				( objectStatus "@baseboard_fab2_lib.baseboard_fab2(sch_1):page47_i43:vss(44)" )
			)
			( pin "J4G3.149"
				( objectStatus "@baseboard_fab2_lib.baseboard_fab2(sch_1):page47_i43:vss(45)" )
			)
			( pin "J4G3.147"
				( objectStatus "@baseboard_fab2_lib.baseboard_fab2(sch_1):page47_i43:vss(46)" )
			)
			( pin "J4G3.138"
				( objectStatus "@baseboard_fab2_lib.baseboard_fab2(sch_1):page47_i43:vss(47)" )
			)
			( pin "J4G3.136"
				( objectStatus "@baseboard_fab2_lib.baseboard_fab2(sch_1):page47_i43:vss(48)" )
			)
			( pin "J4G3.134"
				( objectStatus "@baseboard_fab2_lib.baseboard_fab2(sch_1):page47_i43:vss(49)" )
			)
			( pin "J4G3.131"
				( objectStatus "@baseboard_fab2_lib.baseboard_fab2(sch_1):page47_i43:vss(50)" )
			)
			( pin "J4G3.129"
				( objectStatus "@baseboard_fab2_lib.baseboard_fab2(sch_1):page47_i43:vss(51)" )
			)
			( pin "J4G3.127"
				( objectStatus "@baseboard_fab2_lib.baseboard_fab2(sch_1):page47_i43:vss(52)" )
			)
			( pin "J4G3.125"
				( objectStatus "@baseboard_fab2_lib.baseboard_fab2(sch_1):page47_i43:vss(53)" )
			)
			( pin "J4G3.123"
				( objectStatus "@baseboard_fab2_lib.baseboard_fab2(sch_1):page47_i43:vss(54)" )
			)
			( pin "J4G3.120"
				( objectStatus "@baseboard_fab2_lib.baseboard_fab2(sch_1):page47_i43:vss(55)" )
			)
			( pin "J4G3.118"
				( objectStatus "@baseboard_fab2_lib.baseboard_fab2(sch_1):page47_i43:vss(56)" )
			)
			( pin "J4G3.116"
				( objectStatus "@baseboard_fab2_lib.baseboard_fab2(sch_1):page47_i43:vss(57)" )
			)
			( pin "J4G3.114"
				( objectStatus "@baseboard_fab2_lib.baseboard_fab2(sch_1):page47_i43:vss(58)" )
			)
			( pin "J4G3.112"
				( objectStatus "@baseboard_fab2_lib.baseboard_fab2(sch_1):page47_i43:vss(59)" )
			)
			( pin "J4G3.109"
				( objectStatus "@baseboard_fab2_lib.baseboard_fab2(sch_1):page47_i43:vss(60)" )
			)
			( pin "J4G3.107"
				( objectStatus "@baseboard_fab2_lib.baseboard_fab2(sch_1):page47_i43:vss(61)" )
			)
			( pin "J4G3.105"
				( objectStatus "@baseboard_fab2_lib.baseboard_fab2(sch_1):page47_i43:vss(62)" )
			)
			( pin "J4G3.103"
				( objectStatus "@baseboard_fab2_lib.baseboard_fab2(sch_1):page47_i43:vss(63)" )
			)
			( pin "J4G3.101"
				( objectStatus "@baseboard_fab2_lib.baseboard_fab2(sch_1):page47_i43:vss(64)" )
			)
			( pin "J4G3.98"
				( objectStatus "@baseboard_fab2_lib.baseboard_fab2(sch_1):page47_i43:vss(65)" )
			)
			( pin "J4G3.96"
				( objectStatus "@baseboard_fab2_lib.baseboard_fab2(sch_1):page47_i43:vss(66)" )
			)
			( pin "J4G3.94"
				( objectStatus "@baseboard_fab2_lib.baseboard_fab2(sch_1):page47_i43:vss(67)" )
			)
			( pin "J4G3.57"
				( objectStatus "@baseboard_fab2_lib.baseboard_fab2(sch_1):page47_i43:vss(68)" )
			)
			( pin "J4G3.55"
				( objectStatus "@baseboard_fab2_lib.baseboard_fab2(sch_1):page47_i43:vss(69)" )
			)
			( pin "J4G3.53"
				( objectStatus "@baseboard_fab2_lib.baseboard_fab2(sch_1):page47_i43:vss(70)" )
			)
			( pin "J4G3.50"
				( objectStatus "@baseboard_fab2_lib.baseboard_fab2(sch_1):page47_i43:vss(71)" )
			)
			( pin "J4G3.48"
				( objectStatus "@baseboard_fab2_lib.baseboard_fab2(sch_1):page47_i43:vss(72)" )
			)
			( pin "J4G3.46"
				( objectStatus "@baseboard_fab2_lib.baseboard_fab2(sch_1):page47_i43:vss(73)" )
			)
			( pin "J4G3.44"
				( objectStatus "@baseboard_fab2_lib.baseboard_fab2(sch_1):page47_i43:vss(74)" )
			)
			( pin "J4G3.42"
				( objectStatus "@baseboard_fab2_lib.baseboard_fab2(sch_1):page47_i43:vss(75)" )
			)
			( pin "J4G3.39"
				( objectStatus "@baseboard_fab2_lib.baseboard_fab2(sch_1):page47_i43:vss(76)" )
			)
			( pin "J4G3.37"
				( objectStatus "@baseboard_fab2_lib.baseboard_fab2(sch_1):page47_i43:vss(77)" )
			)
			( pin "J4G3.35"
				( objectStatus "@baseboard_fab2_lib.baseboard_fab2(sch_1):page47_i43:vss(78)" )
			)
			( pin "J4G3.33"
				( objectStatus "@baseboard_fab2_lib.baseboard_fab2(sch_1):page47_i43:vss(79)" )
			)
			( pin "J4G3.31"
				( objectStatus "@baseboard_fab2_lib.baseboard_fab2(sch_1):page47_i43:vss(80)" )
			)
			( pin "J4G3.28"
				( objectStatus "@baseboard_fab2_lib.baseboard_fab2(sch_1):page47_i43:vss(81)" )
			)
			( pin "J4G3.26"
				( objectStatus "@baseboard_fab2_lib.baseboard_fab2(sch_1):page47_i43:vss(82)" )
			)
			( pin "J4G3.24"
				( objectStatus "@baseboard_fab2_lib.baseboard_fab2(sch_1):page47_i43:vss(83)" )
			)
			( pin "J4G3.22"
				( objectStatus "@baseboard_fab2_lib.baseboard_fab2(sch_1):page47_i43:vss(84)" )
			)
			( pin "J4G3.20"
				( objectStatus "@baseboard_fab2_lib.baseboard_fab2(sch_1):page47_i43:vss(85)" )
			)
			( pin "J4G3.17"
				( objectStatus "@baseboard_fab2_lib.baseboard_fab2(sch_1):page47_i43:vss(86)" )
			)
			( pin "J4G3.15"
				( objectStatus "@baseboard_fab2_lib.baseboard_fab2(sch_1):page47_i43:vss(87)" )
			)
			( pin "J4G3.13"
				( objectStatus "@baseboard_fab2_lib.baseboard_fab2(sch_1):page47_i43:vss(88)" )
			)
			( pin "J4G3.11"
				( objectStatus "@baseboard_fab2_lib.baseboard_fab2(sch_1):page47_i43:vss(89)" )
			)
			( pin "J4G3.9"
				( objectStatus "@baseboard_fab2_lib.baseboard_fab2(sch_1):page47_i43:vss(90)" )
			)
			( pin "J4G3.6"
				( objectStatus "@baseboard_fab2_lib.baseboard_fab2(sch_1):page47_i43:vss(91)" )
			)
			( pin "J4G3.4"
				( objectStatus "@baseboard_fab2_lib.baseboard_fab2(sch_1):page47_i43:vss(92)" )
			)
			( pin "J4G3.2"
				( objectStatus "@baseboard_fab2_lib.baseboard_fab2(sch_1):page47_i43:vss(93)" )
			)
			( pin "J4G3.152"
				( objectStatus "@baseboard_fab2_lib.baseboard_fab2(sch_1):page47_i61:dqs0n" )
			)
			( pin "J4G3.153"
				( objectStatus "@baseboard_fab2_lib.baseboard_fab2(sch_1):page47_i61:dqs0p" )
			)
			( pin "J4G3.163"
				( objectStatus "@baseboard_fab2_lib.baseboard_fab2(sch_1):page47_i61:dqs1n" )
			)
			( pin "J4G3.164"
				( objectStatus "@baseboard_fab2_lib.baseboard_fab2(sch_1):page47_i61:dqs1p" )
			)
			( pin "J4G3.174"
				( objectStatus "@baseboard_fab2_lib.baseboard_fab2(sch_1):page47_i61:dqs2n" )
			)
			( pin "J4G3.175"
				( objectStatus "@baseboard_fab2_lib.baseboard_fab2(sch_1):page47_i61:dqs2p" )
			)
			( pin "J4G3.185"
				( objectStatus "@baseboard_fab2_lib.baseboard_fab2(sch_1):page47_i61:dqs3n" )
			)
			( pin "J4G3.186"
				( objectStatus "@baseboard_fab2_lib.baseboard_fab2(sch_1):page47_i61:dqs3p" )
			)
			( pin "J4G3.244"
				( objectStatus "@baseboard_fab2_lib.baseboard_fab2(sch_1):page47_i61:dqs4n" )
			)
			( pin "J4G3.245"
				( objectStatus "@baseboard_fab2_lib.baseboard_fab2(sch_1):page47_i61:dqs4p" )
			)
			( pin "J4G3.255"
				( objectStatus "@baseboard_fab2_lib.baseboard_fab2(sch_1):page47_i61:dqs5n" )
			)
			( pin "J4G3.256"
				( objectStatus "@baseboard_fab2_lib.baseboard_fab2(sch_1):page47_i61:dqs5p" )
			)
			( pin "J4G3.266"
				( objectStatus "@baseboard_fab2_lib.baseboard_fab2(sch_1):page47_i61:dqs6n" )
			)
			( pin "J4G3.267"
				( objectStatus "@baseboard_fab2_lib.baseboard_fab2(sch_1):page47_i61:dqs6p" )
			)
			( pin "J4G3.277"
				( objectStatus "@baseboard_fab2_lib.baseboard_fab2(sch_1):page47_i61:dqs7n" )
			)
			( pin "J4G3.278"
				( objectStatus "@baseboard_fab2_lib.baseboard_fab2(sch_1):page47_i61:dqs7p" )
			)
			( pin "J4G3.196"
				( objectStatus "@baseboard_fab2_lib.baseboard_fab2(sch_1):page47_i61:dqs8n" )
			)
			( pin "J4G3.197"
				( objectStatus "@baseboard_fab2_lib.baseboard_fab2(sch_1):page47_i61:dqs8p" )
			)
			( pin "J4G3.8"
				( objectStatus "@baseboard_fab2_lib.baseboard_fab2(sch_1):page47_i61:dqs9n" )
			)
			( pin "J4G3.7"
				( objectStatus "@baseboard_fab2_lib.baseboard_fab2(sch_1):page47_i61:dqs9p" )
			)
			( pin "J4G3.19"
				( objectStatus "@baseboard_fab2_lib.baseboard_fab2(sch_1):page47_i61:dqs10n" )
			)
			( pin "J4G3.18"
				( objectStatus "@baseboard_fab2_lib.baseboard_fab2(sch_1):page47_i61:dqs10p" )
			)
			( pin "J4G3.30"
				( objectStatus "@baseboard_fab2_lib.baseboard_fab2(sch_1):page47_i61:dqs11n" )
			)
			( pin "J4G3.29"
				( objectStatus "@baseboard_fab2_lib.baseboard_fab2(sch_1):page47_i61:dqs11p" )
			)
			( pin "J4G3.41"
				( objectStatus "@baseboard_fab2_lib.baseboard_fab2(sch_1):page47_i61:dqs12n" )
			)
			( pin "J4G3.40"
				( objectStatus "@baseboard_fab2_lib.baseboard_fab2(sch_1):page47_i61:dqs12p" )
			)
			( pin "J4G3.100"
				( objectStatus "@baseboard_fab2_lib.baseboard_fab2(sch_1):page47_i61:dqs13n" )
			)
			( pin "J4G3.99"
				( objectStatus "@baseboard_fab2_lib.baseboard_fab2(sch_1):page47_i61:dqs13p" )
			)
			( pin "J4G3.111"
				( objectStatus "@baseboard_fab2_lib.baseboard_fab2(sch_1):page47_i61:dqs14n" )
			)
			( pin "J4G3.110"
				( objectStatus "@baseboard_fab2_lib.baseboard_fab2(sch_1):page47_i61:dqs14p" )
			)
			( pin "J4G3.122"
				( objectStatus "@baseboard_fab2_lib.baseboard_fab2(sch_1):page47_i61:dqs15n" )
			)
			( pin "J4G3.121"
				( objectStatus "@baseboard_fab2_lib.baseboard_fab2(sch_1):page47_i61:dqs15p" )
			)
			( pin "J4G3.133"
				( objectStatus "@baseboard_fab2_lib.baseboard_fab2(sch_1):page47_i61:dqs16n" )
			)
			( pin "J4G3.132"
				( objectStatus "@baseboard_fab2_lib.baseboard_fab2(sch_1):page47_i61:dqs16p" )
			)
			( pin "J4G3.52"
				( objectStatus "@baseboard_fab2_lib.baseboard_fab2(sch_1):page47_i61:dqs17n" )
			)
			( pin "J4G3.51"
				( objectStatus "@baseboard_fab2_lib.baseboard_fab2(sch_1):page47_i61:dqs17p" )
			)
			( pin "J4G3.79"
				( objectStatus "@baseboard_fab2_lib.baseboard_fab2(sch_1):page47_i111:a0" )
			)
			( pin "J4G3.72"
				( objectStatus "@baseboard_fab2_lib.baseboard_fab2(sch_1):page47_i111:a1" )
			)
			( pin "J4G3.216"
				( objectStatus "@baseboard_fab2_lib.baseboard_fab2(sch_1):page47_i111:a2" )
			)
			( pin "J4G3.71"
				( objectStatus "@baseboard_fab2_lib.baseboard_fab2(sch_1):page47_i111:a3" )
			)
			( pin "J4G3.214"
				( objectStatus "@baseboard_fab2_lib.baseboard_fab2(sch_1):page47_i111:a4" )
			)
			( pin "J4G3.213"
				( objectStatus "@baseboard_fab2_lib.baseboard_fab2(sch_1):page47_i111:a5" )
			)
			( pin "J4G3.69"
				( objectStatus "@baseboard_fab2_lib.baseboard_fab2(sch_1):page47_i111:a6" )
			)
			( pin "J4G3.211"
				( objectStatus "@baseboard_fab2_lib.baseboard_fab2(sch_1):page47_i111:a7" )
			)
			( pin "J4G3.68"
				( objectStatus "@baseboard_fab2_lib.baseboard_fab2(sch_1):page47_i111:a8" )
			)
			( pin "J4G3.66"
				( objectStatus "@baseboard_fab2_lib.baseboard_fab2(sch_1):page47_i111:a9" )
			)
			( pin "J4G3.225"
				( objectStatus "@baseboard_fab2_lib.baseboard_fab2(sch_1):page47_i111:a10" )
			)
			( pin "J4G3.210"
				( objectStatus "@baseboard_fab2_lib.baseboard_fab2(sch_1):page47_i111:a11" )
			)
			( pin "J4G3.65"
				( objectStatus "@baseboard_fab2_lib.baseboard_fab2(sch_1):page47_i111:a12" )
			)
			( pin "J4G3.232"
				( objectStatus "@baseboard_fab2_lib.baseboard_fab2(sch_1):page47_i111:a13" )
			)
			( pin "J4G3.228"
				( objectStatus "@baseboard_fab2_lib.baseboard_fab2(sch_1):page47_i111:a14_we_n" )
			)
			( pin "J4G3.86"
				( objectStatus "@baseboard_fab2_lib.baseboard_fab2(sch_1):page47_i111:a15_cas_n" )
			)
			( pin "J4G3.82"
				( objectStatus "@baseboard_fab2_lib.baseboard_fab2(sch_1):page47_i111:a16_ras_n" )
			)
			( pin "J4G3.234"
				( objectStatus "@baseboard_fab2_lib.baseboard_fab2(sch_1):page47_i111:a17" )
			)
			( pin "J4G3.62"
				( objectStatus "@baseboard_fab2_lib.baseboard_fab2(sch_1):page47_i111:act_n" )
			)
			( pin "J4G3.208"
				( objectStatus "@baseboard_fab2_lib.baseboard_fab2(sch_1):page47_i111:alert_n" )
			)
			( pin "J4G3.81"
				( objectStatus "@baseboard_fab2_lib.baseboard_fab2(sch_1):page47_i111:ba(0)" )
			)
			( pin "J4G3.224"
				( objectStatus "@baseboard_fab2_lib.baseboard_fab2(sch_1):page47_i111:ba(1)" )
			)
			( pin "J4G3.63"
				( objectStatus "@baseboard_fab2_lib.baseboard_fab2(sch_1):page47_i111:bg(0)" )
			)
			( pin "J4G3.207"
				( objectStatus "@baseboard_fab2_lib.baseboard_fab2(sch_1):page47_i111:bg(1)" )
			)
			( pin "J4G3.235"
				( objectStatus "@baseboard_fab2_lib.baseboard_fab2(sch_1):page47_i111:c(2)" )
			)
			( pin "J4G3.49"
				( objectStatus "@baseboard_fab2_lib.baseboard_fab2(sch_1):page47_i111:cb(0)" )
			)
			( pin "J4G3.194"
				( objectStatus "@baseboard_fab2_lib.baseboard_fab2(sch_1):page47_i111:cb(1)" )
			)
			( pin "J4G3.56"
				( objectStatus "@baseboard_fab2_lib.baseboard_fab2(sch_1):page47_i111:cb(2)" )
			)
			( pin "J4G3.201"
				( objectStatus "@baseboard_fab2_lib.baseboard_fab2(sch_1):page47_i111:cb(3)" )
			)
			( pin "J4G3.47"
				( objectStatus "@baseboard_fab2_lib.baseboard_fab2(sch_1):page47_i111:cb(4)" )
			)
			( pin "J4G3.192"
				( objectStatus "@baseboard_fab2_lib.baseboard_fab2(sch_1):page47_i111:cb(5)" )
			)
			( pin "J4G3.54"
				( objectStatus "@baseboard_fab2_lib.baseboard_fab2(sch_1):page47_i111:cb(6)" )
			)
			( pin "J4G3.199"
				( objectStatus "@baseboard_fab2_lib.baseboard_fab2(sch_1):page47_i111:cb(7)" )
			)
			( pin "J4G3.75"
				( objectStatus "@baseboard_fab2_lib.baseboard_fab2(sch_1):page47_i111:ck0n" )
			)
			( pin "J4G3.74"
				( objectStatus "@baseboard_fab2_lib.baseboard_fab2(sch_1):page47_i111:ck0p" )
			)
			( pin "J4G3.219"
				( objectStatus "@baseboard_fab2_lib.baseboard_fab2(sch_1):page47_i111:ck1n" )
			)
			( pin "J4G3.218"
				( objectStatus "@baseboard_fab2_lib.baseboard_fab2(sch_1):page47_i111:ck1p" )
			)
			( pin "J4G3.60"
				( objectStatus "@baseboard_fab2_lib.baseboard_fab2(sch_1):page47_i111:cke(0)" )
			)
			( pin "J4G3.203"
				( objectStatus "@baseboard_fab2_lib.baseboard_fab2(sch_1):page47_i111:cke(1)" )
			)
			( pin "J4G3.5"
				( objectStatus "@baseboard_fab2_lib.baseboard_fab2(sch_1):page47_i111:dq(0)" )
			)
			( pin "J4G3.150"
				( objectStatus "@baseboard_fab2_lib.baseboard_fab2(sch_1):page47_i111:dq(1)" )
			)
			( pin "J4G3.12"
				( objectStatus "@baseboard_fab2_lib.baseboard_fab2(sch_1):page47_i111:dq(2)" )
			)
			( pin "J4G3.157"
				( objectStatus "@baseboard_fab2_lib.baseboard_fab2(sch_1):page47_i111:dq(3)" )
			)
			( pin "J4G3.3"
				( objectStatus "@baseboard_fab2_lib.baseboard_fab2(sch_1):page47_i111:dq(4)" )
			)
			( pin "J4G3.148"
				( objectStatus "@baseboard_fab2_lib.baseboard_fab2(sch_1):page47_i111:dq(5)" )
			)
			( pin "J4G3.10"
				( objectStatus "@baseboard_fab2_lib.baseboard_fab2(sch_1):page47_i111:dq(6)" )
			)
			( pin "J4G3.155"
				( objectStatus "@baseboard_fab2_lib.baseboard_fab2(sch_1):page47_i111:dq(7)" )
			)
			( pin "J4G3.16"
				( objectStatus "@baseboard_fab2_lib.baseboard_fab2(sch_1):page47_i111:dq(8)" )
			)
			( pin "J4G3.161"
				( objectStatus "@baseboard_fab2_lib.baseboard_fab2(sch_1):page47_i111:dq(9)" )
			)
			( pin "J4G3.23"
				( objectStatus "@baseboard_fab2_lib.baseboard_fab2(sch_1):page47_i111:dq(10)" )
			)
			( pin "J4G3.168"
				( objectStatus "@baseboard_fab2_lib.baseboard_fab2(sch_1):page47_i111:dq(11)" )
			)
			( pin "J4G3.14"
				( objectStatus "@baseboard_fab2_lib.baseboard_fab2(sch_1):page47_i111:dq(12)" )
			)
			( pin "J4G3.159"
				( objectStatus "@baseboard_fab2_lib.baseboard_fab2(sch_1):page47_i111:dq(13)" )
			)
			( pin "J4G3.21"
				( objectStatus "@baseboard_fab2_lib.baseboard_fab2(sch_1):page47_i111:dq(14)" )
			)
			( pin "J4G3.166"
				( objectStatus "@baseboard_fab2_lib.baseboard_fab2(sch_1):page47_i111:dq(15)" )
			)
			( pin "J4G3.27"
				( objectStatus "@baseboard_fab2_lib.baseboard_fab2(sch_1):page47_i111:dq(16)" )
			)
			( pin "J4G3.172"
				( objectStatus "@baseboard_fab2_lib.baseboard_fab2(sch_1):page47_i111:dq(17)" )
			)
			( pin "J4G3.34"
				( objectStatus "@baseboard_fab2_lib.baseboard_fab2(sch_1):page47_i111:dq(18)" )
			)
			( pin "J4G3.179"
				( objectStatus "@baseboard_fab2_lib.baseboard_fab2(sch_1):page47_i111:dq(19)" )
			)
			( pin "J4G3.25"
				( objectStatus "@baseboard_fab2_lib.baseboard_fab2(sch_1):page47_i111:dq(20)" )
			)
			( pin "J4G3.170"
				( objectStatus "@baseboard_fab2_lib.baseboard_fab2(sch_1):page47_i111:dq(21)" )
			)
			( pin "J4G3.32"
				( objectStatus "@baseboard_fab2_lib.baseboard_fab2(sch_1):page47_i111:dq(22)" )
			)
			( pin "J4G3.177"
				( objectStatus "@baseboard_fab2_lib.baseboard_fab2(sch_1):page47_i111:dq(23)" )
			)
			( pin "J4G3.38"
				( objectStatus "@baseboard_fab2_lib.baseboard_fab2(sch_1):page47_i111:dq(24)" )
			)
			( pin "J4G3.183"
				( objectStatus "@baseboard_fab2_lib.baseboard_fab2(sch_1):page47_i111:dq(25)" )
			)
			( pin "J4G3.45"
				( objectStatus "@baseboard_fab2_lib.baseboard_fab2(sch_1):page47_i111:dq(26)" )
			)
			( pin "J4G3.190"
				( objectStatus "@baseboard_fab2_lib.baseboard_fab2(sch_1):page47_i111:dq(27)" )
			)
			( pin "J4G3.36"
				( objectStatus "@baseboard_fab2_lib.baseboard_fab2(sch_1):page47_i111:dq(28)" )
			)
			( pin "J4G3.181"
				( objectStatus "@baseboard_fab2_lib.baseboard_fab2(sch_1):page47_i111:dq(29)" )
			)
			( pin "J4G3.43"
				( objectStatus "@baseboard_fab2_lib.baseboard_fab2(sch_1):page47_i111:dq(30)" )
			)
			( pin "J4G3.188"
				( objectStatus "@baseboard_fab2_lib.baseboard_fab2(sch_1):page47_i111:dq(31)" )
			)
			( pin "J4G3.97"
				( objectStatus "@baseboard_fab2_lib.baseboard_fab2(sch_1):page47_i111:dq(32)" )
			)
			( pin "J4G3.242"
				( objectStatus "@baseboard_fab2_lib.baseboard_fab2(sch_1):page47_i111:dq(33)" )
			)
			( pin "J4G3.104"
				( objectStatus "@baseboard_fab2_lib.baseboard_fab2(sch_1):page47_i111:dq(34)" )
			)
			( pin "J4G3.249"
				( objectStatus "@baseboard_fab2_lib.baseboard_fab2(sch_1):page47_i111:dq(35)" )
			)
			( pin "J4G3.95"
				( objectStatus "@baseboard_fab2_lib.baseboard_fab2(sch_1):page47_i111:dq(36)" )
			)
			( pin "J4G3.240"
				( objectStatus "@baseboard_fab2_lib.baseboard_fab2(sch_1):page47_i111:dq(37)" )
			)
			( pin "J4G3.102"
				( objectStatus "@baseboard_fab2_lib.baseboard_fab2(sch_1):page47_i111:dq(38)" )
			)
			( pin "J4G3.247"
				( objectStatus "@baseboard_fab2_lib.baseboard_fab2(sch_1):page47_i111:dq(39)" )
			)
			( pin "J4G3.108"
				( objectStatus "@baseboard_fab2_lib.baseboard_fab2(sch_1):page47_i111:dq(40)" )
			)
			( pin "J4G3.253"
				( objectStatus "@baseboard_fab2_lib.baseboard_fab2(sch_1):page47_i111:dq(41)" )
			)
			( pin "J4G3.115"
				( objectStatus "@baseboard_fab2_lib.baseboard_fab2(sch_1):page47_i111:dq(42)" )
			)
			( pin "J4G3.260"
				( objectStatus "@baseboard_fab2_lib.baseboard_fab2(sch_1):page47_i111:dq(43)" )
			)
			( pin "J4G3.106"
				( objectStatus "@baseboard_fab2_lib.baseboard_fab2(sch_1):page47_i111:dq(44)" )
			)
			( pin "J4G3.251"
				( objectStatus "@baseboard_fab2_lib.baseboard_fab2(sch_1):page47_i111:dq(45)" )
			)
			( pin "J4G3.113"
				( objectStatus "@baseboard_fab2_lib.baseboard_fab2(sch_1):page47_i111:dq(46)" )
			)
			( pin "J4G3.258"
				( objectStatus "@baseboard_fab2_lib.baseboard_fab2(sch_1):page47_i111:dq(47)" )
			)
			( pin "J4G3.119"
				( objectStatus "@baseboard_fab2_lib.baseboard_fab2(sch_1):page47_i111:dq(48)" )
			)
			( pin "J4G3.264"
				( objectStatus "@baseboard_fab2_lib.baseboard_fab2(sch_1):page47_i111:dq(49)" )
			)
			( pin "J4G3.126"
				( objectStatus "@baseboard_fab2_lib.baseboard_fab2(sch_1):page47_i111:dq(50)" )
			)
			( pin "J4G3.271"
				( objectStatus "@baseboard_fab2_lib.baseboard_fab2(sch_1):page47_i111:dq(51)" )
			)
			( pin "J4G3.117"
				( objectStatus "@baseboard_fab2_lib.baseboard_fab2(sch_1):page47_i111:dq(52)" )
			)
			( pin "J4G3.262"
				( objectStatus "@baseboard_fab2_lib.baseboard_fab2(sch_1):page47_i111:dq(53)" )
			)
			( pin "J4G3.124"
				( objectStatus "@baseboard_fab2_lib.baseboard_fab2(sch_1):page47_i111:dq(54)" )
			)
			( pin "J4G3.269"
				( objectStatus "@baseboard_fab2_lib.baseboard_fab2(sch_1):page47_i111:dq(55)" )
			)
			( pin "J4G3.130"
				( objectStatus "@baseboard_fab2_lib.baseboard_fab2(sch_1):page47_i111:dq(56)" )
			)
			( pin "J4G3.275"
				( objectStatus "@baseboard_fab2_lib.baseboard_fab2(sch_1):page47_i111:dq(57)" )
			)
			( pin "J4G3.137"
				( objectStatus "@baseboard_fab2_lib.baseboard_fab2(sch_1):page47_i111:dq(58)" )
			)
			( pin "J4G3.282"
				( objectStatus "@baseboard_fab2_lib.baseboard_fab2(sch_1):page47_i111:dq(59)" )
			)
			( pin "J4G3.128"
				( objectStatus "@baseboard_fab2_lib.baseboard_fab2(sch_1):page47_i111:dq(60)" )
			)
			( pin "J4G3.273"
				( objectStatus "@baseboard_fab2_lib.baseboard_fab2(sch_1):page47_i111:dq(61)" )
			)
			( pin "J4G3.135"
				( objectStatus "@baseboard_fab2_lib.baseboard_fab2(sch_1):page47_i111:dq(62)" )
			)
			( pin "J4G3.280"
				( objectStatus "@baseboard_fab2_lib.baseboard_fab2(sch_1):page47_i111:dq(63)" )
			)
			( pin "J4G3.78"
				( objectStatus "@baseboard_fab2_lib.baseboard_fab2(sch_1):page47_i111:event_n" )
			)
			( pin "J4G3.87"
				( objectStatus "@baseboard_fab2_lib.baseboard_fab2(sch_1):page47_i111:odt(0)" )
			)
			( pin "J4G3.91"
				( objectStatus "@baseboard_fab2_lib.baseboard_fab2(sch_1):page47_i111:odt(1)" )
			)
			( pin "J4G3.222"
				( objectStatus "@baseboard_fab2_lib.baseboard_fab2(sch_1):page47_i111:par" )
			)
			( pin "J4G3.58"
				( objectStatus "@baseboard_fab2_lib.baseboard_fab2(sch_1):page47_i111:reset_n" )
			)
			( pin "J4G3.205"
				( objectStatus "@baseboard_fab2_lib.baseboard_fab2(sch_1):page47_i111:rfu(0)" )
			)
			( pin "J4G3.227"
				( objectStatus "@baseboard_fab2_lib.baseboard_fab2(sch_1):page47_i111:rfu(1)" )
			)
			( pin "J4G3.144"
				( objectStatus "@baseboard_fab2_lib.baseboard_fab2(sch_1):page47_i111:rfu(2)" )
			)
			( pin "J4G3.84"
				( objectStatus "@baseboard_fab2_lib.baseboard_fab2(sch_1):page47_i111:s0_n" )
			)
			( pin "J4G3.89"
				( objectStatus "@baseboard_fab2_lib.baseboard_fab2(sch_1):page47_i111:s1_n" )
			)
			( pin "J4G3.93"
				( objectStatus "@baseboard_fab2_lib.baseboard_fab2(sch_1):page47_i111:s2_n_c(0)" )
			)
			( pin "J4G3.237"
				( objectStatus "@baseboard_fab2_lib.baseboard_fab2(sch_1):page47_i111:s3_n_c(1)" )
			)
			( pin "J4G3.139"
				( objectStatus "@baseboard_fab2_lib.baseboard_fab2(sch_1):page47_i111:sa(0)" )
			)
			( pin "J4G3.140"
				( objectStatus "@baseboard_fab2_lib.baseboard_fab2(sch_1):page47_i111:sa(1)" )
			)
			( pin "J4G3.238"
				( objectStatus "@baseboard_fab2_lib.baseboard_fab2(sch_1):page47_i111:sa(2)" )
			)
			( pin "J4G3.230"
				( objectStatus "@baseboard_fab2_lib.baseboard_fab2(sch_1):page47_i111:save_n_nc" )
			)
			( pin "J4G3.141"
				( objectStatus "@baseboard_fab2_lib.baseboard_fab2(sch_1):page47_i111:scl" )
			)
			( pin "J4G3.285"
				( objectStatus "@baseboard_fab2_lib.baseboard_fab2(sch_1):page47_i111:sda" )
			)
			( pin "J4G3.284"
				( objectStatus "@baseboard_fab2_lib.baseboard_fab2(sch_1):page47_i111:vddspd" )
			)
			( pin "J4G3.146"
				( objectStatus "@baseboard_fab2_lib.baseboard_fab2(sch_1):page47_i111:vrefca" )
			)
			( pin "J4G3.145"
				( objectStatus "@baseboard_fab2_lib.baseboard_fab2(sch_1):page47_i179:\12v\(0)" )
			)
			( pin "J4G3.1"
				( objectStatus "@baseboard_fab2_lib.baseboard_fab2(sch_1):page47_i179:\12v\(1)" )
			)
			( pin "J4G3.236"
				( objectStatus "@baseboard_fab2_lib.baseboard_fab2(sch_1):page47_i179:vdd(0)" )
			)
			( pin "J4G3.233"
				( objectStatus "@baseboard_fab2_lib.baseboard_fab2(sch_1):page47_i179:vdd(1)" )
			)
			( pin "J4G3.231"
				( objectStatus "@baseboard_fab2_lib.baseboard_fab2(sch_1):page47_i179:vdd(2)" )
			)
			( pin "J4G3.229"
				( objectStatus "@baseboard_fab2_lib.baseboard_fab2(sch_1):page47_i179:vdd(3)" )
			)
			( pin "J4G3.226"
				( objectStatus "@baseboard_fab2_lib.baseboard_fab2(sch_1):page47_i179:vdd(4)" )
			)
			( pin "J4G3.223"
				( objectStatus "@baseboard_fab2_lib.baseboard_fab2(sch_1):page47_i179:vdd(5)" )
			)
			( pin "J4G3.220"
				( objectStatus "@baseboard_fab2_lib.baseboard_fab2(sch_1):page47_i179:vdd(6)" )
			)
			( pin "J4G3.217"
				( objectStatus "@baseboard_fab2_lib.baseboard_fab2(sch_1):page47_i179:vdd(7)" )
			)
			( pin "J4G3.215"
				( objectStatus "@baseboard_fab2_lib.baseboard_fab2(sch_1):page47_i179:vdd(8)" )
			)
			( pin "J4G3.212"
				( objectStatus "@baseboard_fab2_lib.baseboard_fab2(sch_1):page47_i179:vdd(9)" )
			)
			( pin "J4G3.209"
				( objectStatus "@baseboard_fab2_lib.baseboard_fab2(sch_1):page47_i179:vdd(10)" )
			)
			( pin "J4G3.206"
				( objectStatus "@baseboard_fab2_lib.baseboard_fab2(sch_1):page47_i179:vdd(11)" )
			)
			( pin "J4G3.204"
				( objectStatus "@baseboard_fab2_lib.baseboard_fab2(sch_1):page47_i179:vdd(12)" )
			)
			( pin "J4G3.92"
				( objectStatus "@baseboard_fab2_lib.baseboard_fab2(sch_1):page47_i179:vdd(13)" )
			)
			( pin "J4G3.90"
				( objectStatus "@baseboard_fab2_lib.baseboard_fab2(sch_1):page47_i179:vdd(14)" )
			)
			( pin "J4G3.88"
				( objectStatus "@baseboard_fab2_lib.baseboard_fab2(sch_1):page47_i179:vdd(15)" )
			)
			( pin "J4G3.85"
				( objectStatus "@baseboard_fab2_lib.baseboard_fab2(sch_1):page47_i179:vdd(16)" )
			)
			( pin "J4G3.83"
				( objectStatus "@baseboard_fab2_lib.baseboard_fab2(sch_1):page47_i179:vdd(17)" )
			)
			( pin "J4G3.80"
				( objectStatus "@baseboard_fab2_lib.baseboard_fab2(sch_1):page47_i179:vdd(18)" )
			)
			( pin "J4G3.76"
				( objectStatus "@baseboard_fab2_lib.baseboard_fab2(sch_1):page47_i179:vdd(19)" )
			)
			( pin "J4G3.73"
				( objectStatus "@baseboard_fab2_lib.baseboard_fab2(sch_1):page47_i179:vdd(20)" )
			)
			( pin "J4G3.70"
				( objectStatus "@baseboard_fab2_lib.baseboard_fab2(sch_1):page47_i179:vdd(21)" )
			)
			( pin "J4G3.67"
				( objectStatus "@baseboard_fab2_lib.baseboard_fab2(sch_1):page47_i179:vdd(22)" )
			)
			( pin "J4G3.64"
				( objectStatus "@baseboard_fab2_lib.baseboard_fab2(sch_1):page47_i179:vdd(23)" )
			)
			( pin "J4G3.61"
				( objectStatus "@baseboard_fab2_lib.baseboard_fab2(sch_1):page47_i179:vdd(24)" )
			)
			( pin "J4G3.59"
				( objectStatus "@baseboard_fab2_lib.baseboard_fab2(sch_1):page47_i179:vdd(25)" )
			)
			( pin "J4G3.287"
				( objectStatus "@baseboard_fab2_lib.baseboard_fab2(sch_1):page47_i179:vpp(0)" )
			)
			( pin "J4G3.286"
				( objectStatus "@baseboard_fab2_lib.baseboard_fab2(sch_1):page47_i179:vpp(1)" )
			)
			( pin "J4G3.288"
				( objectStatus "@baseboard_fab2_lib.baseboard_fab2(sch_1):page47_i179:vpp(2)" )
			)
			( pin "J4G3.143"
				( objectStatus "@baseboard_fab2_lib.baseboard_fab2(sch_1):page47_i179:vpp(3)" )
			)
			( pin "J4G3.142"
				( objectStatus "@baseboard_fab2_lib.baseboard_fab2(sch_1):page47_i179:vpp(4)" )
			)
			( pin "J4G3.221"
				( objectStatus "@baseboard_fab2_lib.baseboard_fab2(sch_1):page47_i179:vtt(0)" )
			)
			( pin "J4G3.77"
				( objectStatus "@baseboard_fab2_lib.baseboard_fab2(sch_1):page47_i179:vtt(1)" )
			)
			( pin "C4G19.1"
				( objectStatus "@baseboard_fab2_lib.baseboard_fab2(sch_1):page47_i188:a" )
			)
			( pin "C4G19.2"
				( objectStatus "@baseboard_fab2_lib.baseboard_fab2(sch_1):page47_i188:b" )
			)
			( pin "J6U2.283"
				( objectStatus "@baseboard_fab2_lib.baseboard_fab2(sch_1):page48_i43:vss(0)" )
			)
			( pin "J6U2.281"
				( objectStatus "@baseboard_fab2_lib.baseboard_fab2(sch_1):page48_i43:vss(1)" )
			)
			( pin "J6U2.279"
				( objectStatus "@baseboard_fab2_lib.baseboard_fab2(sch_1):page48_i43:vss(2)" )
			)
			( pin "J6U2.276"
				( objectStatus "@baseboard_fab2_lib.baseboard_fab2(sch_1):page48_i43:vss(3)" )
			)
			( pin "J6U2.274"
				( objectStatus "@baseboard_fab2_lib.baseboard_fab2(sch_1):page48_i43:vss(4)" )
			)
			( pin "J6U2.272"
				( objectStatus "@baseboard_fab2_lib.baseboard_fab2(sch_1):page48_i43:vss(5)" )
			)
			( pin "J6U2.270"
				( objectStatus "@baseboard_fab2_lib.baseboard_fab2(sch_1):page48_i43:vss(6)" )
			)
			( pin "J6U2.268"
				( objectStatus "@baseboard_fab2_lib.baseboard_fab2(sch_1):page48_i43:vss(7)" )
			)
			( pin "J6U2.265"
				( objectStatus "@baseboard_fab2_lib.baseboard_fab2(sch_1):page48_i43:vss(8)" )
			)
			( pin "J6U2.263"
				( objectStatus "@baseboard_fab2_lib.baseboard_fab2(sch_1):page48_i43:vss(9)" )
			)
			( pin "J6U2.261"
				( objectStatus "@baseboard_fab2_lib.baseboard_fab2(sch_1):page48_i43:vss(10)" )
			)
			( pin "J6U2.259"
				( objectStatus "@baseboard_fab2_lib.baseboard_fab2(sch_1):page48_i43:vss(11)" )
			)
			( pin "J6U2.257"
				( objectStatus "@baseboard_fab2_lib.baseboard_fab2(sch_1):page48_i43:vss(12)" )
			)
			( pin "J6U2.254"
				( objectStatus "@baseboard_fab2_lib.baseboard_fab2(sch_1):page48_i43:vss(13)" )
			)
			( pin "J6U2.252"
				( objectStatus "@baseboard_fab2_lib.baseboard_fab2(sch_1):page48_i43:vss(14)" )
			)
			( pin "J6U2.250"
				( objectStatus "@baseboard_fab2_lib.baseboard_fab2(sch_1):page48_i43:vss(15)" )
			)
			( pin "J6U2.248"
				( objectStatus "@baseboard_fab2_lib.baseboard_fab2(sch_1):page48_i43:vss(16)" )
			)
			( pin "J6U2.246"
				( objectStatus "@baseboard_fab2_lib.baseboard_fab2(sch_1):page48_i43:vss(17)" )
			)
			( pin "J6U2.243"
				( objectStatus "@baseboard_fab2_lib.baseboard_fab2(sch_1):page48_i43:vss(18)" )
			)
			( pin "J6U2.241"
				( objectStatus "@baseboard_fab2_lib.baseboard_fab2(sch_1):page48_i43:vss(19)" )
			)
			( pin "J6U2.239"
				( objectStatus "@baseboard_fab2_lib.baseboard_fab2(sch_1):page48_i43:vss(20)" )
			)
			( pin "J6U2.202"
				( objectStatus "@baseboard_fab2_lib.baseboard_fab2(sch_1):page48_i43:vss(21)" )
			)
			( pin "J6U2.200"
				( objectStatus "@baseboard_fab2_lib.baseboard_fab2(sch_1):page48_i43:vss(22)" )
			)
			( pin "J6U2.198"
				( objectStatus "@baseboard_fab2_lib.baseboard_fab2(sch_1):page48_i43:vss(23)" )
			)
			( pin "J6U2.195"
				( objectStatus "@baseboard_fab2_lib.baseboard_fab2(sch_1):page48_i43:vss(24)" )
			)
			( pin "J6U2.193"
				( objectStatus "@baseboard_fab2_lib.baseboard_fab2(sch_1):page48_i43:vss(25)" )
			)
			( pin "J6U2.191"
				( objectStatus "@baseboard_fab2_lib.baseboard_fab2(sch_1):page48_i43:vss(26)" )
			)
			( pin "J6U2.189"
				( objectStatus "@baseboard_fab2_lib.baseboard_fab2(sch_1):page48_i43:vss(27)" )
			)
			( pin "J6U2.187"
				( objectStatus "@baseboard_fab2_lib.baseboard_fab2(sch_1):page48_i43:vss(28)" )
			)
			( pin "J6U2.184"
				( objectStatus "@baseboard_fab2_lib.baseboard_fab2(sch_1):page48_i43:vss(29)" )
			)
			( pin "J6U2.182"
				( objectStatus "@baseboard_fab2_lib.baseboard_fab2(sch_1):page48_i43:vss(30)" )
			)
			( pin "J6U2.180"
				( objectStatus "@baseboard_fab2_lib.baseboard_fab2(sch_1):page48_i43:vss(31)" )
			)
			( pin "J6U2.178"
				( objectStatus "@baseboard_fab2_lib.baseboard_fab2(sch_1):page48_i43:vss(32)" )
			)
			( pin "J6U2.176"
				( objectStatus "@baseboard_fab2_lib.baseboard_fab2(sch_1):page48_i43:vss(33)" )
			)
			( pin "J6U2.173"
				( objectStatus "@baseboard_fab2_lib.baseboard_fab2(sch_1):page48_i43:vss(34)" )
			)
			( pin "J6U2.171"
				( objectStatus "@baseboard_fab2_lib.baseboard_fab2(sch_1):page48_i43:vss(35)" )
			)
			( pin "J6U2.169"
				( objectStatus "@baseboard_fab2_lib.baseboard_fab2(sch_1):page48_i43:vss(36)" )
			)
			( pin "J6U2.167"
				( objectStatus "@baseboard_fab2_lib.baseboard_fab2(sch_1):page48_i43:vss(37)" )
			)
			( pin "J6U2.165"
				( objectStatus "@baseboard_fab2_lib.baseboard_fab2(sch_1):page48_i43:vss(38)" )
			)
			( pin "J6U2.162"
				( objectStatus "@baseboard_fab2_lib.baseboard_fab2(sch_1):page48_i43:vss(39)" )
			)
			( pin "J6U2.160"
				( objectStatus "@baseboard_fab2_lib.baseboard_fab2(sch_1):page48_i43:vss(40)" )
			)
			( pin "J6U2.158"
				( objectStatus "@baseboard_fab2_lib.baseboard_fab2(sch_1):page48_i43:vss(41)" )
			)
			( pin "J6U2.156"
				( objectStatus "@baseboard_fab2_lib.baseboard_fab2(sch_1):page48_i43:vss(42)" )
			)
			( pin "J6U2.154"
				( objectStatus "@baseboard_fab2_lib.baseboard_fab2(sch_1):page48_i43:vss(43)" )
			)
			( pin "J6U2.151"
				( objectStatus "@baseboard_fab2_lib.baseboard_fab2(sch_1):page48_i43:vss(44)" )
			)
			( pin "J6U2.149"
				( objectStatus "@baseboard_fab2_lib.baseboard_fab2(sch_1):page48_i43:vss(45)" )
			)
			( pin "J6U2.147"
				( objectStatus "@baseboard_fab2_lib.baseboard_fab2(sch_1):page48_i43:vss(46)" )
			)
			( pin "J6U2.138"
				( objectStatus "@baseboard_fab2_lib.baseboard_fab2(sch_1):page48_i43:vss(47)" )
			)
			( pin "J6U2.136"
				( objectStatus "@baseboard_fab2_lib.baseboard_fab2(sch_1):page48_i43:vss(48)" )
			)
			( pin "J6U2.134"
				( objectStatus "@baseboard_fab2_lib.baseboard_fab2(sch_1):page48_i43:vss(49)" )
			)
			( pin "J6U2.131"
				( objectStatus "@baseboard_fab2_lib.baseboard_fab2(sch_1):page48_i43:vss(50)" )
			)
			( pin "J6U2.129"
				( objectStatus "@baseboard_fab2_lib.baseboard_fab2(sch_1):page48_i43:vss(51)" )
			)
			( pin "J6U2.127"
				( objectStatus "@baseboard_fab2_lib.baseboard_fab2(sch_1):page48_i43:vss(52)" )
			)
			( pin "J6U2.125"
				( objectStatus "@baseboard_fab2_lib.baseboard_fab2(sch_1):page48_i43:vss(53)" )
			)
			( pin "J6U2.123"
				( objectStatus "@baseboard_fab2_lib.baseboard_fab2(sch_1):page48_i43:vss(54)" )
			)
			( pin "J6U2.120"
				( objectStatus "@baseboard_fab2_lib.baseboard_fab2(sch_1):page48_i43:vss(55)" )
			)
			( pin "J6U2.118"
				( objectStatus "@baseboard_fab2_lib.baseboard_fab2(sch_1):page48_i43:vss(56)" )
			)
			( pin "J6U2.116"
				( objectStatus "@baseboard_fab2_lib.baseboard_fab2(sch_1):page48_i43:vss(57)" )
			)
			( pin "J6U2.114"
				( objectStatus "@baseboard_fab2_lib.baseboard_fab2(sch_1):page48_i43:vss(58)" )
			)
			( pin "J6U2.112"
				( objectStatus "@baseboard_fab2_lib.baseboard_fab2(sch_1):page48_i43:vss(59)" )
			)
			( pin "J6U2.109"
				( objectStatus "@baseboard_fab2_lib.baseboard_fab2(sch_1):page48_i43:vss(60)" )
			)
			( pin "J6U2.107"
				( objectStatus "@baseboard_fab2_lib.baseboard_fab2(sch_1):page48_i43:vss(61)" )
			)
			( pin "J6U2.105"
				( objectStatus "@baseboard_fab2_lib.baseboard_fab2(sch_1):page48_i43:vss(62)" )
			)
			( pin "J6U2.103"
				( objectStatus "@baseboard_fab2_lib.baseboard_fab2(sch_1):page48_i43:vss(63)" )
			)
			( pin "J6U2.101"
				( objectStatus "@baseboard_fab2_lib.baseboard_fab2(sch_1):page48_i43:vss(64)" )
			)
			( pin "J6U2.98"
				( objectStatus "@baseboard_fab2_lib.baseboard_fab2(sch_1):page48_i43:vss(65)" )
			)
			( pin "J6U2.96"
				( objectStatus "@baseboard_fab2_lib.baseboard_fab2(sch_1):page48_i43:vss(66)" )
			)
			( pin "J6U2.94"
				( objectStatus "@baseboard_fab2_lib.baseboard_fab2(sch_1):page48_i43:vss(67)" )
			)
			( pin "J6U2.57"
				( objectStatus "@baseboard_fab2_lib.baseboard_fab2(sch_1):page48_i43:vss(68)" )
			)
			( pin "J6U2.55"
				( objectStatus "@baseboard_fab2_lib.baseboard_fab2(sch_1):page48_i43:vss(69)" )
			)
			( pin "J6U2.53"
				( objectStatus "@baseboard_fab2_lib.baseboard_fab2(sch_1):page48_i43:vss(70)" )
			)
			( pin "J6U2.50"
				( objectStatus "@baseboard_fab2_lib.baseboard_fab2(sch_1):page48_i43:vss(71)" )
			)
			( pin "J6U2.48"
				( objectStatus "@baseboard_fab2_lib.baseboard_fab2(sch_1):page48_i43:vss(72)" )
			)
			( pin "J6U2.46"
				( objectStatus "@baseboard_fab2_lib.baseboard_fab2(sch_1):page48_i43:vss(73)" )
			)
			( pin "J6U2.44"
				( objectStatus "@baseboard_fab2_lib.baseboard_fab2(sch_1):page48_i43:vss(74)" )
			)
			( pin "J6U2.42"
				( objectStatus "@baseboard_fab2_lib.baseboard_fab2(sch_1):page48_i43:vss(75)" )
			)
			( pin "J6U2.39"
				( objectStatus "@baseboard_fab2_lib.baseboard_fab2(sch_1):page48_i43:vss(76)" )
			)
			( pin "J6U2.37"
				( objectStatus "@baseboard_fab2_lib.baseboard_fab2(sch_1):page48_i43:vss(77)" )
			)
			( pin "J6U2.35"
				( objectStatus "@baseboard_fab2_lib.baseboard_fab2(sch_1):page48_i43:vss(78)" )
			)
			( pin "J6U2.33"
				( objectStatus "@baseboard_fab2_lib.baseboard_fab2(sch_1):page48_i43:vss(79)" )
			)
			( pin "J6U2.31"
				( objectStatus "@baseboard_fab2_lib.baseboard_fab2(sch_1):page48_i43:vss(80)" )
			)
			( pin "J6U2.28"
				( objectStatus "@baseboard_fab2_lib.baseboard_fab2(sch_1):page48_i43:vss(81)" )
			)
			( pin "J6U2.26"
				( objectStatus "@baseboard_fab2_lib.baseboard_fab2(sch_1):page48_i43:vss(82)" )
			)
			( pin "J6U2.24"
				( objectStatus "@baseboard_fab2_lib.baseboard_fab2(sch_1):page48_i43:vss(83)" )
			)
			( pin "J6U2.22"
				( objectStatus "@baseboard_fab2_lib.baseboard_fab2(sch_1):page48_i43:vss(84)" )
			)
			( pin "J6U2.20"
				( objectStatus "@baseboard_fab2_lib.baseboard_fab2(sch_1):page48_i43:vss(85)" )
			)
			( pin "J6U2.17"
				( objectStatus "@baseboard_fab2_lib.baseboard_fab2(sch_1):page48_i43:vss(86)" )
			)
			( pin "J6U2.15"
				( objectStatus "@baseboard_fab2_lib.baseboard_fab2(sch_1):page48_i43:vss(87)" )
			)
			( pin "J6U2.13"
				( objectStatus "@baseboard_fab2_lib.baseboard_fab2(sch_1):page48_i43:vss(88)" )
			)
			( pin "J6U2.11"
				( objectStatus "@baseboard_fab2_lib.baseboard_fab2(sch_1):page48_i43:vss(89)" )
			)
			( pin "J6U2.9"
				( objectStatus "@baseboard_fab2_lib.baseboard_fab2(sch_1):page48_i43:vss(90)" )
			)
			( pin "J6U2.6"
				( objectStatus "@baseboard_fab2_lib.baseboard_fab2(sch_1):page48_i43:vss(91)" )
			)
			( pin "J6U2.4"
				( objectStatus "@baseboard_fab2_lib.baseboard_fab2(sch_1):page48_i43:vss(92)" )
			)
			( pin "J6U2.2"
				( objectStatus "@baseboard_fab2_lib.baseboard_fab2(sch_1):page48_i43:vss(93)" )
			)
			( pin "J6U2.152"
				( objectStatus "@baseboard_fab2_lib.baseboard_fab2(sch_1):page48_i61:dqs0n" )
			)
			( pin "J6U2.153"
				( objectStatus "@baseboard_fab2_lib.baseboard_fab2(sch_1):page48_i61:dqs0p" )
			)
			( pin "J6U2.163"
				( objectStatus "@baseboard_fab2_lib.baseboard_fab2(sch_1):page48_i61:dqs1n" )
			)
			( pin "J6U2.164"
				( objectStatus "@baseboard_fab2_lib.baseboard_fab2(sch_1):page48_i61:dqs1p" )
			)
			( pin "J6U2.174"
				( objectStatus "@baseboard_fab2_lib.baseboard_fab2(sch_1):page48_i61:dqs2n" )
			)
			( pin "J6U2.175"
				( objectStatus "@baseboard_fab2_lib.baseboard_fab2(sch_1):page48_i61:dqs2p" )
			)
			( pin "J6U2.185"
				( objectStatus "@baseboard_fab2_lib.baseboard_fab2(sch_1):page48_i61:dqs3n" )
			)
			( pin "J6U2.186"
				( objectStatus "@baseboard_fab2_lib.baseboard_fab2(sch_1):page48_i61:dqs3p" )
			)
			( pin "J6U2.244"
				( objectStatus "@baseboard_fab2_lib.baseboard_fab2(sch_1):page48_i61:dqs4n" )
			)
			( pin "J6U2.245"
				( objectStatus "@baseboard_fab2_lib.baseboard_fab2(sch_1):page48_i61:dqs4p" )
			)
			( pin "J6U2.255"
				( objectStatus "@baseboard_fab2_lib.baseboard_fab2(sch_1):page48_i61:dqs5n" )
			)
			( pin "J6U2.256"
				( objectStatus "@baseboard_fab2_lib.baseboard_fab2(sch_1):page48_i61:dqs5p" )
			)
			( pin "J6U2.266"
				( objectStatus "@baseboard_fab2_lib.baseboard_fab2(sch_1):page48_i61:dqs6n" )
			)
			( pin "J6U2.267"
				( objectStatus "@baseboard_fab2_lib.baseboard_fab2(sch_1):page48_i61:dqs6p" )
			)
			( pin "J6U2.277"
				( objectStatus "@baseboard_fab2_lib.baseboard_fab2(sch_1):page48_i61:dqs7n" )
			)
			( pin "J6U2.278"
				( objectStatus "@baseboard_fab2_lib.baseboard_fab2(sch_1):page48_i61:dqs7p" )
			)
			( pin "J6U2.196"
				( objectStatus "@baseboard_fab2_lib.baseboard_fab2(sch_1):page48_i61:dqs8n" )
			)
			( pin "J6U2.197"
				( objectStatus "@baseboard_fab2_lib.baseboard_fab2(sch_1):page48_i61:dqs8p" )
			)
			( pin "J6U2.8"
				( objectStatus "@baseboard_fab2_lib.baseboard_fab2(sch_1):page48_i61:dqs9n" )
			)
			( pin "J6U2.7"
				( objectStatus "@baseboard_fab2_lib.baseboard_fab2(sch_1):page48_i61:dqs9p" )
			)
			( pin "J6U2.19"
				( objectStatus "@baseboard_fab2_lib.baseboard_fab2(sch_1):page48_i61:dqs10n" )
			)
			( pin "J6U2.18"
				( objectStatus "@baseboard_fab2_lib.baseboard_fab2(sch_1):page48_i61:dqs10p" )
			)
			( pin "J6U2.30"
				( objectStatus "@baseboard_fab2_lib.baseboard_fab2(sch_1):page48_i61:dqs11n" )
			)
			( pin "J6U2.29"
				( objectStatus "@baseboard_fab2_lib.baseboard_fab2(sch_1):page48_i61:dqs11p" )
			)
			( pin "J6U2.41"
				( objectStatus "@baseboard_fab2_lib.baseboard_fab2(sch_1):page48_i61:dqs12n" )
			)
			( pin "J6U2.40"
				( objectStatus "@baseboard_fab2_lib.baseboard_fab2(sch_1):page48_i61:dqs12p" )
			)
			( pin "J6U2.100"
				( objectStatus "@baseboard_fab2_lib.baseboard_fab2(sch_1):page48_i61:dqs13n" )
			)
			( pin "J6U2.99"
				( objectStatus "@baseboard_fab2_lib.baseboard_fab2(sch_1):page48_i61:dqs13p" )
			)
			( pin "J6U2.111"
				( objectStatus "@baseboard_fab2_lib.baseboard_fab2(sch_1):page48_i61:dqs14n" )
			)
			( pin "J6U2.110"
				( objectStatus "@baseboard_fab2_lib.baseboard_fab2(sch_1):page48_i61:dqs14p" )
			)
			( pin "J6U2.122"
				( objectStatus "@baseboard_fab2_lib.baseboard_fab2(sch_1):page48_i61:dqs15n" )
			)
			( pin "J6U2.121"
				( objectStatus "@baseboard_fab2_lib.baseboard_fab2(sch_1):page48_i61:dqs15p" )
			)
			( pin "J6U2.133"
				( objectStatus "@baseboard_fab2_lib.baseboard_fab2(sch_1):page48_i61:dqs16n" )
			)
			( pin "J6U2.132"
				( objectStatus "@baseboard_fab2_lib.baseboard_fab2(sch_1):page48_i61:dqs16p" )
			)
			( pin "J6U2.52"
				( objectStatus "@baseboard_fab2_lib.baseboard_fab2(sch_1):page48_i61:dqs17n" )
			)
			( pin "J6U2.51"
				( objectStatus "@baseboard_fab2_lib.baseboard_fab2(sch_1):page48_i61:dqs17p" )
			)
			( pin "J6U2.79"
				( objectStatus "@baseboard_fab2_lib.baseboard_fab2(sch_1):page48_i111:a0" )
			)
			( pin "J6U2.72"
				( objectStatus "@baseboard_fab2_lib.baseboard_fab2(sch_1):page48_i111:a1" )
			)
			( pin "J6U2.216"
				( objectStatus "@baseboard_fab2_lib.baseboard_fab2(sch_1):page48_i111:a2" )
			)
			( pin "J6U2.71"
				( objectStatus "@baseboard_fab2_lib.baseboard_fab2(sch_1):page48_i111:a3" )
			)
			( pin "J6U2.214"
				( objectStatus "@baseboard_fab2_lib.baseboard_fab2(sch_1):page48_i111:a4" )
			)
			( pin "J6U2.213"
				( objectStatus "@baseboard_fab2_lib.baseboard_fab2(sch_1):page48_i111:a5" )
			)
			( pin "J6U2.69"
				( objectStatus "@baseboard_fab2_lib.baseboard_fab2(sch_1):page48_i111:a6" )
			)
			( pin "J6U2.211"
				( objectStatus "@baseboard_fab2_lib.baseboard_fab2(sch_1):page48_i111:a7" )
			)
			( pin "J6U2.68"
				( objectStatus "@baseboard_fab2_lib.baseboard_fab2(sch_1):page48_i111:a8" )
			)
			( pin "J6U2.66"
				( objectStatus "@baseboard_fab2_lib.baseboard_fab2(sch_1):page48_i111:a9" )
			)
			( pin "J6U2.225"
				( objectStatus "@baseboard_fab2_lib.baseboard_fab2(sch_1):page48_i111:a10" )
			)
			( pin "J6U2.210"
				( objectStatus "@baseboard_fab2_lib.baseboard_fab2(sch_1):page48_i111:a11" )
			)
			( pin "J6U2.65"
				( objectStatus "@baseboard_fab2_lib.baseboard_fab2(sch_1):page48_i111:a12" )
			)
			( pin "J6U2.232"
				( objectStatus "@baseboard_fab2_lib.baseboard_fab2(sch_1):page48_i111:a13" )
			)
			( pin "J6U2.228"
				( objectStatus "@baseboard_fab2_lib.baseboard_fab2(sch_1):page48_i111:a14_we_n" )
			)
			( pin "J6U2.86"
				( objectStatus "@baseboard_fab2_lib.baseboard_fab2(sch_1):page48_i111:a15_cas_n" )
			)
			( pin "J6U2.82"
				( objectStatus "@baseboard_fab2_lib.baseboard_fab2(sch_1):page48_i111:a16_ras_n" )
			)
			( pin "J6U2.234"
				( objectStatus "@baseboard_fab2_lib.baseboard_fab2(sch_1):page48_i111:a17" )
			)
			( pin "J6U2.62"
				( objectStatus "@baseboard_fab2_lib.baseboard_fab2(sch_1):page48_i111:act_n" )
			)
			( pin "J6U2.208"
				( objectStatus "@baseboard_fab2_lib.baseboard_fab2(sch_1):page48_i111:alert_n" )
			)
			( pin "J6U2.81"
				( objectStatus "@baseboard_fab2_lib.baseboard_fab2(sch_1):page48_i111:ba(0)" )
			)
			( pin "J6U2.224"
				( objectStatus "@baseboard_fab2_lib.baseboard_fab2(sch_1):page48_i111:ba(1)" )
			)
			( pin "J6U2.63"
				( objectStatus "@baseboard_fab2_lib.baseboard_fab2(sch_1):page48_i111:bg(0)" )
			)
			( pin "J6U2.207"
				( objectStatus "@baseboard_fab2_lib.baseboard_fab2(sch_1):page48_i111:bg(1)" )
			)
			( pin "J6U2.235"
				( objectStatus "@baseboard_fab2_lib.baseboard_fab2(sch_1):page48_i111:c(2)" )
			)
			( pin "J6U2.49"
				( objectStatus "@baseboard_fab2_lib.baseboard_fab2(sch_1):page48_i111:cb(0)" )
			)
			( pin "J6U2.194"
				( objectStatus "@baseboard_fab2_lib.baseboard_fab2(sch_1):page48_i111:cb(1)" )
			)
			( pin "J6U2.56"
				( objectStatus "@baseboard_fab2_lib.baseboard_fab2(sch_1):page48_i111:cb(2)" )
			)
			( pin "J6U2.201"
				( objectStatus "@baseboard_fab2_lib.baseboard_fab2(sch_1):page48_i111:cb(3)" )
			)
			( pin "J6U2.47"
				( objectStatus "@baseboard_fab2_lib.baseboard_fab2(sch_1):page48_i111:cb(4)" )
			)
			( pin "J6U2.192"
				( objectStatus "@baseboard_fab2_lib.baseboard_fab2(sch_1):page48_i111:cb(5)" )
			)
			( pin "J6U2.54"
				( objectStatus "@baseboard_fab2_lib.baseboard_fab2(sch_1):page48_i111:cb(6)" )
			)
			( pin "J6U2.199"
				( objectStatus "@baseboard_fab2_lib.baseboard_fab2(sch_1):page48_i111:cb(7)" )
			)
			( pin "J6U2.75"
				( objectStatus "@baseboard_fab2_lib.baseboard_fab2(sch_1):page48_i111:ck0n" )
			)
			( pin "J6U2.74"
				( objectStatus "@baseboard_fab2_lib.baseboard_fab2(sch_1):page48_i111:ck0p" )
			)
			( pin "J6U2.219"
				( objectStatus "@baseboard_fab2_lib.baseboard_fab2(sch_1):page48_i111:ck1n" )
			)
			( pin "J6U2.218"
				( objectStatus "@baseboard_fab2_lib.baseboard_fab2(sch_1):page48_i111:ck1p" )
			)
			( pin "J6U2.60"
				( objectStatus "@baseboard_fab2_lib.baseboard_fab2(sch_1):page48_i111:cke(0)" )
			)
			( pin "J6U2.203"
				( objectStatus "@baseboard_fab2_lib.baseboard_fab2(sch_1):page48_i111:cke(1)" )
			)
			( pin "J6U2.5"
				( objectStatus "@baseboard_fab2_lib.baseboard_fab2(sch_1):page48_i111:dq(0)" )
			)
			( pin "J6U2.150"
				( objectStatus "@baseboard_fab2_lib.baseboard_fab2(sch_1):page48_i111:dq(1)" )
			)
			( pin "J6U2.12"
				( objectStatus "@baseboard_fab2_lib.baseboard_fab2(sch_1):page48_i111:dq(2)" )
			)
			( pin "J6U2.157"
				( objectStatus "@baseboard_fab2_lib.baseboard_fab2(sch_1):page48_i111:dq(3)" )
			)
			( pin "J6U2.3"
				( objectStatus "@baseboard_fab2_lib.baseboard_fab2(sch_1):page48_i111:dq(4)" )
			)
			( pin "J6U2.148"
				( objectStatus "@baseboard_fab2_lib.baseboard_fab2(sch_1):page48_i111:dq(5)" )
			)
			( pin "J6U2.10"
				( objectStatus "@baseboard_fab2_lib.baseboard_fab2(sch_1):page48_i111:dq(6)" )
			)
			( pin "J6U2.155"
				( objectStatus "@baseboard_fab2_lib.baseboard_fab2(sch_1):page48_i111:dq(7)" )
			)
			( pin "J6U2.16"
				( objectStatus "@baseboard_fab2_lib.baseboard_fab2(sch_1):page48_i111:dq(8)" )
			)
			( pin "J6U2.161"
				( objectStatus "@baseboard_fab2_lib.baseboard_fab2(sch_1):page48_i111:dq(9)" )
			)
			( pin "J6U2.23"
				( objectStatus "@baseboard_fab2_lib.baseboard_fab2(sch_1):page48_i111:dq(10)" )
			)
			( pin "J6U2.168"
				( objectStatus "@baseboard_fab2_lib.baseboard_fab2(sch_1):page48_i111:dq(11)" )
			)
			( pin "J6U2.14"
				( objectStatus "@baseboard_fab2_lib.baseboard_fab2(sch_1):page48_i111:dq(12)" )
			)
			( pin "J6U2.159"
				( objectStatus "@baseboard_fab2_lib.baseboard_fab2(sch_1):page48_i111:dq(13)" )
			)
			( pin "J6U2.21"
				( objectStatus "@baseboard_fab2_lib.baseboard_fab2(sch_1):page48_i111:dq(14)" )
			)
			( pin "J6U2.166"
				( objectStatus "@baseboard_fab2_lib.baseboard_fab2(sch_1):page48_i111:dq(15)" )
			)
			( pin "J6U2.27"
				( objectStatus "@baseboard_fab2_lib.baseboard_fab2(sch_1):page48_i111:dq(16)" )
			)
			( pin "J6U2.172"
				( objectStatus "@baseboard_fab2_lib.baseboard_fab2(sch_1):page48_i111:dq(17)" )
			)
			( pin "J6U2.34"
				( objectStatus "@baseboard_fab2_lib.baseboard_fab2(sch_1):page48_i111:dq(18)" )
			)
			( pin "J6U2.179"
				( objectStatus "@baseboard_fab2_lib.baseboard_fab2(sch_1):page48_i111:dq(19)" )
			)
			( pin "J6U2.25"
				( objectStatus "@baseboard_fab2_lib.baseboard_fab2(sch_1):page48_i111:dq(20)" )
			)
			( pin "J6U2.170"
				( objectStatus "@baseboard_fab2_lib.baseboard_fab2(sch_1):page48_i111:dq(21)" )
			)
			( pin "J6U2.32"
				( objectStatus "@baseboard_fab2_lib.baseboard_fab2(sch_1):page48_i111:dq(22)" )
			)
			( pin "J6U2.177"
				( objectStatus "@baseboard_fab2_lib.baseboard_fab2(sch_1):page48_i111:dq(23)" )
			)
			( pin "J6U2.38"
				( objectStatus "@baseboard_fab2_lib.baseboard_fab2(sch_1):page48_i111:dq(24)" )
			)
			( pin "J6U2.183"
				( objectStatus "@baseboard_fab2_lib.baseboard_fab2(sch_1):page48_i111:dq(25)" )
			)
			( pin "J6U2.45"
				( objectStatus "@baseboard_fab2_lib.baseboard_fab2(sch_1):page48_i111:dq(26)" )
			)
			( pin "J6U2.190"
				( objectStatus "@baseboard_fab2_lib.baseboard_fab2(sch_1):page48_i111:dq(27)" )
			)
			( pin "J6U2.36"
				( objectStatus "@baseboard_fab2_lib.baseboard_fab2(sch_1):page48_i111:dq(28)" )
			)
			( pin "J6U2.181"
				( objectStatus "@baseboard_fab2_lib.baseboard_fab2(sch_1):page48_i111:dq(29)" )
			)
			( pin "J6U2.43"
				( objectStatus "@baseboard_fab2_lib.baseboard_fab2(sch_1):page48_i111:dq(30)" )
			)
			( pin "J6U2.188"
				( objectStatus "@baseboard_fab2_lib.baseboard_fab2(sch_1):page48_i111:dq(31)" )
			)
			( pin "J6U2.97"
				( objectStatus "@baseboard_fab2_lib.baseboard_fab2(sch_1):page48_i111:dq(32)" )
			)
			( pin "J6U2.242"
				( objectStatus "@baseboard_fab2_lib.baseboard_fab2(sch_1):page48_i111:dq(33)" )
			)
			( pin "J6U2.104"
				( objectStatus "@baseboard_fab2_lib.baseboard_fab2(sch_1):page48_i111:dq(34)" )
			)
			( pin "J6U2.249"
				( objectStatus "@baseboard_fab2_lib.baseboard_fab2(sch_1):page48_i111:dq(35)" )
			)
			( pin "J6U2.95"
				( objectStatus "@baseboard_fab2_lib.baseboard_fab2(sch_1):page48_i111:dq(36)" )
			)
			( pin "J6U2.240"
				( objectStatus "@baseboard_fab2_lib.baseboard_fab2(sch_1):page48_i111:dq(37)" )
			)
			( pin "J6U2.102"
				( objectStatus "@baseboard_fab2_lib.baseboard_fab2(sch_1):page48_i111:dq(38)" )
			)
			( pin "J6U2.247"
				( objectStatus "@baseboard_fab2_lib.baseboard_fab2(sch_1):page48_i111:dq(39)" )
			)
			( pin "J6U2.108"
				( objectStatus "@baseboard_fab2_lib.baseboard_fab2(sch_1):page48_i111:dq(40)" )
			)
			( pin "J6U2.253"
				( objectStatus "@baseboard_fab2_lib.baseboard_fab2(sch_1):page48_i111:dq(41)" )
			)
			( pin "J6U2.115"
				( objectStatus "@baseboard_fab2_lib.baseboard_fab2(sch_1):page48_i111:dq(42)" )
			)
			( pin "J6U2.260"
				( objectStatus "@baseboard_fab2_lib.baseboard_fab2(sch_1):page48_i111:dq(43)" )
			)
			( pin "J6U2.106"
				( objectStatus "@baseboard_fab2_lib.baseboard_fab2(sch_1):page48_i111:dq(44)" )
			)
			( pin "J6U2.251"
				( objectStatus "@baseboard_fab2_lib.baseboard_fab2(sch_1):page48_i111:dq(45)" )
			)
			( pin "J6U2.113"
				( objectStatus "@baseboard_fab2_lib.baseboard_fab2(sch_1):page48_i111:dq(46)" )
			)
			( pin "J6U2.258"
				( objectStatus "@baseboard_fab2_lib.baseboard_fab2(sch_1):page48_i111:dq(47)" )
			)
			( pin "J6U2.119"
				( objectStatus "@baseboard_fab2_lib.baseboard_fab2(sch_1):page48_i111:dq(48)" )
			)
			( pin "J6U2.264"
				( objectStatus "@baseboard_fab2_lib.baseboard_fab2(sch_1):page48_i111:dq(49)" )
			)
			( pin "J6U2.126"
				( objectStatus "@baseboard_fab2_lib.baseboard_fab2(sch_1):page48_i111:dq(50)" )
			)
			( pin "J6U2.271"
				( objectStatus "@baseboard_fab2_lib.baseboard_fab2(sch_1):page48_i111:dq(51)" )
			)
			( pin "J6U2.117"
				( objectStatus "@baseboard_fab2_lib.baseboard_fab2(sch_1):page48_i111:dq(52)" )
			)
			( pin "J6U2.262"
				( objectStatus "@baseboard_fab2_lib.baseboard_fab2(sch_1):page48_i111:dq(53)" )
			)
			( pin "J6U2.124"
				( objectStatus "@baseboard_fab2_lib.baseboard_fab2(sch_1):page48_i111:dq(54)" )
			)
			( pin "J6U2.269"
				( objectStatus "@baseboard_fab2_lib.baseboard_fab2(sch_1):page48_i111:dq(55)" )
			)
			( pin "J6U2.130"
				( objectStatus "@baseboard_fab2_lib.baseboard_fab2(sch_1):page48_i111:dq(56)" )
			)
			( pin "J6U2.275"
				( objectStatus "@baseboard_fab2_lib.baseboard_fab2(sch_1):page48_i111:dq(57)" )
			)
			( pin "J6U2.137"
				( objectStatus "@baseboard_fab2_lib.baseboard_fab2(sch_1):page48_i111:dq(58)" )
			)
			( pin "J6U2.282"
				( objectStatus "@baseboard_fab2_lib.baseboard_fab2(sch_1):page48_i111:dq(59)" )
			)
			( pin "J6U2.128"
				( objectStatus "@baseboard_fab2_lib.baseboard_fab2(sch_1):page48_i111:dq(60)" )
			)
			( pin "J6U2.273"
				( objectStatus "@baseboard_fab2_lib.baseboard_fab2(sch_1):page48_i111:dq(61)" )
			)
			( pin "J6U2.135"
				( objectStatus "@baseboard_fab2_lib.baseboard_fab2(sch_1):page48_i111:dq(62)" )
			)
			( pin "J6U2.280"
				( objectStatus "@baseboard_fab2_lib.baseboard_fab2(sch_1):page48_i111:dq(63)" )
			)
			( pin "J6U2.78"
				( objectStatus "@baseboard_fab2_lib.baseboard_fab2(sch_1):page48_i111:event_n" )
			)
			( pin "J6U2.87"
				( objectStatus "@baseboard_fab2_lib.baseboard_fab2(sch_1):page48_i111:odt(0)" )
			)
			( pin "J6U2.91"
				( objectStatus "@baseboard_fab2_lib.baseboard_fab2(sch_1):page48_i111:odt(1)" )
			)
			( pin "J6U2.222"
				( objectStatus "@baseboard_fab2_lib.baseboard_fab2(sch_1):page48_i111:par" )
			)
			( pin "J6U2.58"
				( objectStatus "@baseboard_fab2_lib.baseboard_fab2(sch_1):page48_i111:reset_n" )
			)
			( pin "J6U2.205"
				( objectStatus "@baseboard_fab2_lib.baseboard_fab2(sch_1):page48_i111:rfu(0)" )
			)
			( pin "J6U2.227"
				( objectStatus "@baseboard_fab2_lib.baseboard_fab2(sch_1):page48_i111:rfu(1)" )
			)
			( pin "J6U2.144"
				( objectStatus "@baseboard_fab2_lib.baseboard_fab2(sch_1):page48_i111:rfu(2)" )
			)
			( pin "J6U2.84"
				( objectStatus "@baseboard_fab2_lib.baseboard_fab2(sch_1):page48_i111:s0_n" )
			)
			( pin "J6U2.89"
				( objectStatus "@baseboard_fab2_lib.baseboard_fab2(sch_1):page48_i111:s1_n" )
			)
			( pin "J6U2.93"
				( objectStatus "@baseboard_fab2_lib.baseboard_fab2(sch_1):page48_i111:s2_n_c(0)" )
			)
			( pin "J6U2.237"
				( objectStatus "@baseboard_fab2_lib.baseboard_fab2(sch_1):page48_i111:s3_n_c(1)" )
			)
			( pin "J6U2.139"
				( objectStatus "@baseboard_fab2_lib.baseboard_fab2(sch_1):page48_i111:sa(0)" )
			)
			( pin "J6U2.140"
				( objectStatus "@baseboard_fab2_lib.baseboard_fab2(sch_1):page48_i111:sa(1)" )
			)
			( pin "J6U2.238"
				( objectStatus "@baseboard_fab2_lib.baseboard_fab2(sch_1):page48_i111:sa(2)" )
			)
			( pin "J6U2.230"
				( objectStatus "@baseboard_fab2_lib.baseboard_fab2(sch_1):page48_i111:save_n_nc" )
			)
			( pin "J6U2.141"
				( objectStatus "@baseboard_fab2_lib.baseboard_fab2(sch_1):page48_i111:scl" )
			)
			( pin "J6U2.285"
				( objectStatus "@baseboard_fab2_lib.baseboard_fab2(sch_1):page48_i111:sda" )
			)
			( pin "J6U2.284"
				( objectStatus "@baseboard_fab2_lib.baseboard_fab2(sch_1):page48_i111:vddspd" )
			)
			( pin "J6U2.146"
				( objectStatus "@baseboard_fab2_lib.baseboard_fab2(sch_1):page48_i111:vrefca" )
			)
			( pin "J6U2.145"
				( objectStatus "@baseboard_fab2_lib.baseboard_fab2(sch_1):page48_i171:\12v\(0)" )
			)
			( pin "J6U2.1"
				( objectStatus "@baseboard_fab2_lib.baseboard_fab2(sch_1):page48_i171:\12v\(1)" )
			)
			( pin "J6U2.236"
				( objectStatus "@baseboard_fab2_lib.baseboard_fab2(sch_1):page48_i171:vdd(0)" )
			)
			( pin "J6U2.233"
				( objectStatus "@baseboard_fab2_lib.baseboard_fab2(sch_1):page48_i171:vdd(1)" )
			)
			( pin "J6U2.231"
				( objectStatus "@baseboard_fab2_lib.baseboard_fab2(sch_1):page48_i171:vdd(2)" )
			)
			( pin "J6U2.229"
				( objectStatus "@baseboard_fab2_lib.baseboard_fab2(sch_1):page48_i171:vdd(3)" )
			)
			( pin "J6U2.226"
				( objectStatus "@baseboard_fab2_lib.baseboard_fab2(sch_1):page48_i171:vdd(4)" )
			)
			( pin "J6U2.223"
				( objectStatus "@baseboard_fab2_lib.baseboard_fab2(sch_1):page48_i171:vdd(5)" )
			)
			( pin "J6U2.220"
				( objectStatus "@baseboard_fab2_lib.baseboard_fab2(sch_1):page48_i171:vdd(6)" )
			)
			( pin "J6U2.217"
				( objectStatus "@baseboard_fab2_lib.baseboard_fab2(sch_1):page48_i171:vdd(7)" )
			)
			( pin "J6U2.215"
				( objectStatus "@baseboard_fab2_lib.baseboard_fab2(sch_1):page48_i171:vdd(8)" )
			)
			( pin "J6U2.212"
				( objectStatus "@baseboard_fab2_lib.baseboard_fab2(sch_1):page48_i171:vdd(9)" )
			)
			( pin "J6U2.209"
				( objectStatus "@baseboard_fab2_lib.baseboard_fab2(sch_1):page48_i171:vdd(10)" )
			)
			( pin "J6U2.206"
				( objectStatus "@baseboard_fab2_lib.baseboard_fab2(sch_1):page48_i171:vdd(11)" )
			)
			( pin "J6U2.204"
				( objectStatus "@baseboard_fab2_lib.baseboard_fab2(sch_1):page48_i171:vdd(12)" )
			)
			( pin "J6U2.92"
				( objectStatus "@baseboard_fab2_lib.baseboard_fab2(sch_1):page48_i171:vdd(13)" )
			)
			( pin "J6U2.90"
				( objectStatus "@baseboard_fab2_lib.baseboard_fab2(sch_1):page48_i171:vdd(14)" )
			)
			( pin "J6U2.88"
				( objectStatus "@baseboard_fab2_lib.baseboard_fab2(sch_1):page48_i171:vdd(15)" )
			)
			( pin "J6U2.85"
				( objectStatus "@baseboard_fab2_lib.baseboard_fab2(sch_1):page48_i171:vdd(16)" )
			)
			( pin "J6U2.83"
				( objectStatus "@baseboard_fab2_lib.baseboard_fab2(sch_1):page48_i171:vdd(17)" )
			)
			( pin "J6U2.80"
				( objectStatus "@baseboard_fab2_lib.baseboard_fab2(sch_1):page48_i171:vdd(18)" )
			)
			( pin "J6U2.76"
				( objectStatus "@baseboard_fab2_lib.baseboard_fab2(sch_1):page48_i171:vdd(19)" )
			)
			( pin "J6U2.73"
				( objectStatus "@baseboard_fab2_lib.baseboard_fab2(sch_1):page48_i171:vdd(20)" )
			)
			( pin "J6U2.70"
				( objectStatus "@baseboard_fab2_lib.baseboard_fab2(sch_1):page48_i171:vdd(21)" )
			)
			( pin "J6U2.67"
				( objectStatus "@baseboard_fab2_lib.baseboard_fab2(sch_1):page48_i171:vdd(22)" )
			)
			( pin "J6U2.64"
				( objectStatus "@baseboard_fab2_lib.baseboard_fab2(sch_1):page48_i171:vdd(23)" )
			)
			( pin "J6U2.61"
				( objectStatus "@baseboard_fab2_lib.baseboard_fab2(sch_1):page48_i171:vdd(24)" )
			)
			( pin "J6U2.59"
				( objectStatus "@baseboard_fab2_lib.baseboard_fab2(sch_1):page48_i171:vdd(25)" )
			)
			( pin "J6U2.287"
				( objectStatus "@baseboard_fab2_lib.baseboard_fab2(sch_1):page48_i171:vpp(0)" )
			)
			( pin "J6U2.286"
				( objectStatus "@baseboard_fab2_lib.baseboard_fab2(sch_1):page48_i171:vpp(1)" )
			)
			( pin "J6U2.288"
				( objectStatus "@baseboard_fab2_lib.baseboard_fab2(sch_1):page48_i171:vpp(2)" )
			)
			( pin "J6U2.143"
				( objectStatus "@baseboard_fab2_lib.baseboard_fab2(sch_1):page48_i171:vpp(3)" )
			)
			( pin "J6U2.142"
				( objectStatus "@baseboard_fab2_lib.baseboard_fab2(sch_1):page48_i171:vpp(4)" )
			)
			( pin "J6U2.221"
				( objectStatus "@baseboard_fab2_lib.baseboard_fab2(sch_1):page48_i171:vtt(0)" )
			)
			( pin "J6U2.77"
				( objectStatus "@baseboard_fab2_lib.baseboard_fab2(sch_1):page48_i171:vtt(1)" )
			)
			( pin "C6U17.1"
				( objectStatus "@baseboard_fab2_lib.baseboard_fab2(sch_1):page48_i176:a" )
			)
			( pin "C6U17.2"
				( objectStatus "@baseboard_fab2_lib.baseboard_fab2(sch_1):page48_i176:b" )
			)
			( pin "J4B1.283"
				( objectStatus "@baseboard_fab2_lib.baseboard_fab2(sch_1):page49_i43:vss(0)" )
			)
			( pin "J4B1.281"
				( objectStatus "@baseboard_fab2_lib.baseboard_fab2(sch_1):page49_i43:vss(1)" )
			)
			( pin "J4B1.279"
				( objectStatus "@baseboard_fab2_lib.baseboard_fab2(sch_1):page49_i43:vss(2)" )
			)
			( pin "J4B1.276"
				( objectStatus "@baseboard_fab2_lib.baseboard_fab2(sch_1):page49_i43:vss(3)" )
			)
			( pin "J4B1.274"
				( objectStatus "@baseboard_fab2_lib.baseboard_fab2(sch_1):page49_i43:vss(4)" )
			)
			( pin "J4B1.272"
				( objectStatus "@baseboard_fab2_lib.baseboard_fab2(sch_1):page49_i43:vss(5)" )
			)
			( pin "J4B1.270"
				( objectStatus "@baseboard_fab2_lib.baseboard_fab2(sch_1):page49_i43:vss(6)" )
			)
			( pin "J4B1.268"
				( objectStatus "@baseboard_fab2_lib.baseboard_fab2(sch_1):page49_i43:vss(7)" )
			)
			( pin "J4B1.265"
				( objectStatus "@baseboard_fab2_lib.baseboard_fab2(sch_1):page49_i43:vss(8)" )
			)
			( pin "J4B1.263"
				( objectStatus "@baseboard_fab2_lib.baseboard_fab2(sch_1):page49_i43:vss(9)" )
			)
			( pin "J4B1.261"
				( objectStatus "@baseboard_fab2_lib.baseboard_fab2(sch_1):page49_i43:vss(10)" )
			)
			( pin "J4B1.259"
				( objectStatus "@baseboard_fab2_lib.baseboard_fab2(sch_1):page49_i43:vss(11)" )
			)
			( pin "J4B1.257"
				( objectStatus "@baseboard_fab2_lib.baseboard_fab2(sch_1):page49_i43:vss(12)" )
			)
			( pin "J4B1.254"
				( objectStatus "@baseboard_fab2_lib.baseboard_fab2(sch_1):page49_i43:vss(13)" )
			)
			( pin "J4B1.252"
				( objectStatus "@baseboard_fab2_lib.baseboard_fab2(sch_1):page49_i43:vss(14)" )
			)
			( pin "J4B1.250"
				( objectStatus "@baseboard_fab2_lib.baseboard_fab2(sch_1):page49_i43:vss(15)" )
			)
			( pin "J4B1.248"
				( objectStatus "@baseboard_fab2_lib.baseboard_fab2(sch_1):page49_i43:vss(16)" )
			)
			( pin "J4B1.246"
				( objectStatus "@baseboard_fab2_lib.baseboard_fab2(sch_1):page49_i43:vss(17)" )
			)
			( pin "J4B1.243"
				( objectStatus "@baseboard_fab2_lib.baseboard_fab2(sch_1):page49_i43:vss(18)" )
			)
			( pin "J4B1.241"
				( objectStatus "@baseboard_fab2_lib.baseboard_fab2(sch_1):page49_i43:vss(19)" )
			)
			( pin "J4B1.239"
				( objectStatus "@baseboard_fab2_lib.baseboard_fab2(sch_1):page49_i43:vss(20)" )
			)
			( pin "J4B1.202"
				( objectStatus "@baseboard_fab2_lib.baseboard_fab2(sch_1):page49_i43:vss(21)" )
			)
			( pin "J4B1.200"
				( objectStatus "@baseboard_fab2_lib.baseboard_fab2(sch_1):page49_i43:vss(22)" )
			)
			( pin "J4B1.198"
				( objectStatus "@baseboard_fab2_lib.baseboard_fab2(sch_1):page49_i43:vss(23)" )
			)
			( pin "J4B1.195"
				( objectStatus "@baseboard_fab2_lib.baseboard_fab2(sch_1):page49_i43:vss(24)" )
			)
			( pin "J4B1.193"
				( objectStatus "@baseboard_fab2_lib.baseboard_fab2(sch_1):page49_i43:vss(25)" )
			)
			( pin "J4B1.191"
				( objectStatus "@baseboard_fab2_lib.baseboard_fab2(sch_1):page49_i43:vss(26)" )
			)
			( pin "J4B1.189"
				( objectStatus "@baseboard_fab2_lib.baseboard_fab2(sch_1):page49_i43:vss(27)" )
			)
			( pin "J4B1.187"
				( objectStatus "@baseboard_fab2_lib.baseboard_fab2(sch_1):page49_i43:vss(28)" )
			)
			( pin "J4B1.184"
				( objectStatus "@baseboard_fab2_lib.baseboard_fab2(sch_1):page49_i43:vss(29)" )
			)
			( pin "J4B1.182"
				( objectStatus "@baseboard_fab2_lib.baseboard_fab2(sch_1):page49_i43:vss(30)" )
			)
			( pin "J4B1.180"
				( objectStatus "@baseboard_fab2_lib.baseboard_fab2(sch_1):page49_i43:vss(31)" )
			)
			( pin "J4B1.178"
				( objectStatus "@baseboard_fab2_lib.baseboard_fab2(sch_1):page49_i43:vss(32)" )
			)
			( pin "J4B1.176"
				( objectStatus "@baseboard_fab2_lib.baseboard_fab2(sch_1):page49_i43:vss(33)" )
			)
			( pin "J4B1.173"
				( objectStatus "@baseboard_fab2_lib.baseboard_fab2(sch_1):page49_i43:vss(34)" )
			)
			( pin "J4B1.171"
				( objectStatus "@baseboard_fab2_lib.baseboard_fab2(sch_1):page49_i43:vss(35)" )
			)
			( pin "J4B1.169"
				( objectStatus "@baseboard_fab2_lib.baseboard_fab2(sch_1):page49_i43:vss(36)" )
			)
			( pin "J4B1.167"
				( objectStatus "@baseboard_fab2_lib.baseboard_fab2(sch_1):page49_i43:vss(37)" )
			)
			( pin "J4B1.165"
				( objectStatus "@baseboard_fab2_lib.baseboard_fab2(sch_1):page49_i43:vss(38)" )
			)
			( pin "J4B1.162"
				( objectStatus "@baseboard_fab2_lib.baseboard_fab2(sch_1):page49_i43:vss(39)" )
			)
			( pin "J4B1.160"
				( objectStatus "@baseboard_fab2_lib.baseboard_fab2(sch_1):page49_i43:vss(40)" )
			)
			( pin "J4B1.158"
				( objectStatus "@baseboard_fab2_lib.baseboard_fab2(sch_1):page49_i43:vss(41)" )
			)
			( pin "J4B1.156"
				( objectStatus "@baseboard_fab2_lib.baseboard_fab2(sch_1):page49_i43:vss(42)" )
			)
			( pin "J4B1.154"
				( objectStatus "@baseboard_fab2_lib.baseboard_fab2(sch_1):page49_i43:vss(43)" )
			)
			( pin "J4B1.151"
				( objectStatus "@baseboard_fab2_lib.baseboard_fab2(sch_1):page49_i43:vss(44)" )
			)
			( pin "J4B1.149"
				( objectStatus "@baseboard_fab2_lib.baseboard_fab2(sch_1):page49_i43:vss(45)" )
			)
			( pin "J4B1.147"
				( objectStatus "@baseboard_fab2_lib.baseboard_fab2(sch_1):page49_i43:vss(46)" )
			)
			( pin "J4B1.138"
				( objectStatus "@baseboard_fab2_lib.baseboard_fab2(sch_1):page49_i43:vss(47)" )
			)
			( pin "J4B1.136"
				( objectStatus "@baseboard_fab2_lib.baseboard_fab2(sch_1):page49_i43:vss(48)" )
			)
			( pin "J4B1.134"
				( objectStatus "@baseboard_fab2_lib.baseboard_fab2(sch_1):page49_i43:vss(49)" )
			)
			( pin "J4B1.131"
				( objectStatus "@baseboard_fab2_lib.baseboard_fab2(sch_1):page49_i43:vss(50)" )
			)
			( pin "J4B1.129"
				( objectStatus "@baseboard_fab2_lib.baseboard_fab2(sch_1):page49_i43:vss(51)" )
			)
			( pin "J4B1.127"
				( objectStatus "@baseboard_fab2_lib.baseboard_fab2(sch_1):page49_i43:vss(52)" )
			)
			( pin "J4B1.125"
				( objectStatus "@baseboard_fab2_lib.baseboard_fab2(sch_1):page49_i43:vss(53)" )
			)
			( pin "J4B1.123"
				( objectStatus "@baseboard_fab2_lib.baseboard_fab2(sch_1):page49_i43:vss(54)" )
			)
			( pin "J4B1.120"
				( objectStatus "@baseboard_fab2_lib.baseboard_fab2(sch_1):page49_i43:vss(55)" )
			)
			( pin "J4B1.118"
				( objectStatus "@baseboard_fab2_lib.baseboard_fab2(sch_1):page49_i43:vss(56)" )
			)
			( pin "J4B1.116"
				( objectStatus "@baseboard_fab2_lib.baseboard_fab2(sch_1):page49_i43:vss(57)" )
			)
			( pin "J4B1.114"
				( objectStatus "@baseboard_fab2_lib.baseboard_fab2(sch_1):page49_i43:vss(58)" )
			)
			( pin "J4B1.112"
				( objectStatus "@baseboard_fab2_lib.baseboard_fab2(sch_1):page49_i43:vss(59)" )
			)
			( pin "J4B1.109"
				( objectStatus "@baseboard_fab2_lib.baseboard_fab2(sch_1):page49_i43:vss(60)" )
			)
			( pin "J4B1.107"
				( objectStatus "@baseboard_fab2_lib.baseboard_fab2(sch_1):page49_i43:vss(61)" )
			)
			( pin "J4B1.105"
				( objectStatus "@baseboard_fab2_lib.baseboard_fab2(sch_1):page49_i43:vss(62)" )
			)
			( pin "J4B1.103"
				( objectStatus "@baseboard_fab2_lib.baseboard_fab2(sch_1):page49_i43:vss(63)" )
			)
			( pin "J4B1.101"
				( objectStatus "@baseboard_fab2_lib.baseboard_fab2(sch_1):page49_i43:vss(64)" )
			)
			( pin "J4B1.98"
				( objectStatus "@baseboard_fab2_lib.baseboard_fab2(sch_1):page49_i43:vss(65)" )
			)
			( pin "J4B1.96"
				( objectStatus "@baseboard_fab2_lib.baseboard_fab2(sch_1):page49_i43:vss(66)" )
			)
			( pin "J4B1.94"
				( objectStatus "@baseboard_fab2_lib.baseboard_fab2(sch_1):page49_i43:vss(67)" )
			)
			( pin "J4B1.57"
				( objectStatus "@baseboard_fab2_lib.baseboard_fab2(sch_1):page49_i43:vss(68)" )
			)
			( pin "J4B1.55"
				( objectStatus "@baseboard_fab2_lib.baseboard_fab2(sch_1):page49_i43:vss(69)" )
			)
			( pin "J4B1.53"
				( objectStatus "@baseboard_fab2_lib.baseboard_fab2(sch_1):page49_i43:vss(70)" )
			)
			( pin "J4B1.50"
				( objectStatus "@baseboard_fab2_lib.baseboard_fab2(sch_1):page49_i43:vss(71)" )
			)
			( pin "J4B1.48"
				( objectStatus "@baseboard_fab2_lib.baseboard_fab2(sch_1):page49_i43:vss(72)" )
			)
			( pin "J4B1.46"
				( objectStatus "@baseboard_fab2_lib.baseboard_fab2(sch_1):page49_i43:vss(73)" )
			)
			( pin "J4B1.44"
				( objectStatus "@baseboard_fab2_lib.baseboard_fab2(sch_1):page49_i43:vss(74)" )
			)
			( pin "J4B1.42"
				( objectStatus "@baseboard_fab2_lib.baseboard_fab2(sch_1):page49_i43:vss(75)" )
			)
			( pin "J4B1.39"
				( objectStatus "@baseboard_fab2_lib.baseboard_fab2(sch_1):page49_i43:vss(76)" )
			)
			( pin "J4B1.37"
				( objectStatus "@baseboard_fab2_lib.baseboard_fab2(sch_1):page49_i43:vss(77)" )
			)
			( pin "J4B1.35"
				( objectStatus "@baseboard_fab2_lib.baseboard_fab2(sch_1):page49_i43:vss(78)" )
			)
			( pin "J4B1.33"
				( objectStatus "@baseboard_fab2_lib.baseboard_fab2(sch_1):page49_i43:vss(79)" )
			)
			( pin "J4B1.31"
				( objectStatus "@baseboard_fab2_lib.baseboard_fab2(sch_1):page49_i43:vss(80)" )
			)
			( pin "J4B1.28"
				( objectStatus "@baseboard_fab2_lib.baseboard_fab2(sch_1):page49_i43:vss(81)" )
			)
			( pin "J4B1.26"
				( objectStatus "@baseboard_fab2_lib.baseboard_fab2(sch_1):page49_i43:vss(82)" )
			)
			( pin "J4B1.24"
				( objectStatus "@baseboard_fab2_lib.baseboard_fab2(sch_1):page49_i43:vss(83)" )
			)
			( pin "J4B1.22"
				( objectStatus "@baseboard_fab2_lib.baseboard_fab2(sch_1):page49_i43:vss(84)" )
			)
			( pin "J4B1.20"
				( objectStatus "@baseboard_fab2_lib.baseboard_fab2(sch_1):page49_i43:vss(85)" )
			)
			( pin "J4B1.17"
				( objectStatus "@baseboard_fab2_lib.baseboard_fab2(sch_1):page49_i43:vss(86)" )
			)
			( pin "J4B1.15"
				( objectStatus "@baseboard_fab2_lib.baseboard_fab2(sch_1):page49_i43:vss(87)" )
			)
			( pin "J4B1.13"
				( objectStatus "@baseboard_fab2_lib.baseboard_fab2(sch_1):page49_i43:vss(88)" )
			)
			( pin "J4B1.11"
				( objectStatus "@baseboard_fab2_lib.baseboard_fab2(sch_1):page49_i43:vss(89)" )
			)
			( pin "J4B1.9"
				( objectStatus "@baseboard_fab2_lib.baseboard_fab2(sch_1):page49_i43:vss(90)" )
			)
			( pin "J4B1.6"
				( objectStatus "@baseboard_fab2_lib.baseboard_fab2(sch_1):page49_i43:vss(91)" )
			)
			( pin "J4B1.4"
				( objectStatus "@baseboard_fab2_lib.baseboard_fab2(sch_1):page49_i43:vss(92)" )
			)
			( pin "J4B1.2"
				( objectStatus "@baseboard_fab2_lib.baseboard_fab2(sch_1):page49_i43:vss(93)" )
			)
			( pin "J4B1.152"
				( objectStatus "@baseboard_fab2_lib.baseboard_fab2(sch_1):page49_i66:dqs0n" )
			)
			( pin "J4B1.153"
				( objectStatus "@baseboard_fab2_lib.baseboard_fab2(sch_1):page49_i66:dqs0p" )
			)
			( pin "J4B1.163"
				( objectStatus "@baseboard_fab2_lib.baseboard_fab2(sch_1):page49_i66:dqs1n" )
			)
			( pin "J4B1.164"
				( objectStatus "@baseboard_fab2_lib.baseboard_fab2(sch_1):page49_i66:dqs1p" )
			)
			( pin "J4B1.174"
				( objectStatus "@baseboard_fab2_lib.baseboard_fab2(sch_1):page49_i66:dqs2n" )
			)
			( pin "J4B1.175"
				( objectStatus "@baseboard_fab2_lib.baseboard_fab2(sch_1):page49_i66:dqs2p" )
			)
			( pin "J4B1.185"
				( objectStatus "@baseboard_fab2_lib.baseboard_fab2(sch_1):page49_i66:dqs3n" )
			)
			( pin "J4B1.186"
				( objectStatus "@baseboard_fab2_lib.baseboard_fab2(sch_1):page49_i66:dqs3p" )
			)
			( pin "J4B1.244"
				( objectStatus "@baseboard_fab2_lib.baseboard_fab2(sch_1):page49_i66:dqs4n" )
			)
			( pin "J4B1.245"
				( objectStatus "@baseboard_fab2_lib.baseboard_fab2(sch_1):page49_i66:dqs4p" )
			)
			( pin "J4B1.255"
				( objectStatus "@baseboard_fab2_lib.baseboard_fab2(sch_1):page49_i66:dqs5n" )
			)
			( pin "J4B1.256"
				( objectStatus "@baseboard_fab2_lib.baseboard_fab2(sch_1):page49_i66:dqs5p" )
			)
			( pin "J4B1.266"
				( objectStatus "@baseboard_fab2_lib.baseboard_fab2(sch_1):page49_i66:dqs6n" )
			)
			( pin "J4B1.267"
				( objectStatus "@baseboard_fab2_lib.baseboard_fab2(sch_1):page49_i66:dqs6p" )
			)
			( pin "J4B1.277"
				( objectStatus "@baseboard_fab2_lib.baseboard_fab2(sch_1):page49_i66:dqs7n" )
			)
			( pin "J4B1.278"
				( objectStatus "@baseboard_fab2_lib.baseboard_fab2(sch_1):page49_i66:dqs7p" )
			)
			( pin "J4B1.196"
				( objectStatus "@baseboard_fab2_lib.baseboard_fab2(sch_1):page49_i66:dqs8n" )
			)
			( pin "J4B1.197"
				( objectStatus "@baseboard_fab2_lib.baseboard_fab2(sch_1):page49_i66:dqs8p" )
			)
			( pin "J4B1.8"
				( objectStatus "@baseboard_fab2_lib.baseboard_fab2(sch_1):page49_i66:dqs9n" )
			)
			( pin "J4B1.7"
				( objectStatus "@baseboard_fab2_lib.baseboard_fab2(sch_1):page49_i66:dqs9p" )
			)
			( pin "J4B1.19"
				( objectStatus "@baseboard_fab2_lib.baseboard_fab2(sch_1):page49_i66:dqs10n" )
			)
			( pin "J4B1.18"
				( objectStatus "@baseboard_fab2_lib.baseboard_fab2(sch_1):page49_i66:dqs10p" )
			)
			( pin "J4B1.30"
				( objectStatus "@baseboard_fab2_lib.baseboard_fab2(sch_1):page49_i66:dqs11n" )
			)
			( pin "J4B1.29"
				( objectStatus "@baseboard_fab2_lib.baseboard_fab2(sch_1):page49_i66:dqs11p" )
			)
			( pin "J4B1.41"
				( objectStatus "@baseboard_fab2_lib.baseboard_fab2(sch_1):page49_i66:dqs12n" )
			)
			( pin "J4B1.40"
				( objectStatus "@baseboard_fab2_lib.baseboard_fab2(sch_1):page49_i66:dqs12p" )
			)
			( pin "J4B1.100"
				( objectStatus "@baseboard_fab2_lib.baseboard_fab2(sch_1):page49_i66:dqs13n" )
			)
			( pin "J4B1.99"
				( objectStatus "@baseboard_fab2_lib.baseboard_fab2(sch_1):page49_i66:dqs13p" )
			)
			( pin "J4B1.111"
				( objectStatus "@baseboard_fab2_lib.baseboard_fab2(sch_1):page49_i66:dqs14n" )
			)
			( pin "J4B1.110"
				( objectStatus "@baseboard_fab2_lib.baseboard_fab2(sch_1):page49_i66:dqs14p" )
			)
			( pin "J4B1.122"
				( objectStatus "@baseboard_fab2_lib.baseboard_fab2(sch_1):page49_i66:dqs15n" )
			)
			( pin "J4B1.121"
				( objectStatus "@baseboard_fab2_lib.baseboard_fab2(sch_1):page49_i66:dqs15p" )
			)
			( pin "J4B1.133"
				( objectStatus "@baseboard_fab2_lib.baseboard_fab2(sch_1):page49_i66:dqs16n" )
			)
			( pin "J4B1.132"
				( objectStatus "@baseboard_fab2_lib.baseboard_fab2(sch_1):page49_i66:dqs16p" )
			)
			( pin "J4B1.52"
				( objectStatus "@baseboard_fab2_lib.baseboard_fab2(sch_1):page49_i66:dqs17n" )
			)
			( pin "J4B1.51"
				( objectStatus "@baseboard_fab2_lib.baseboard_fab2(sch_1):page49_i66:dqs17p" )
			)
			( pin "J4B1.79"
				( objectStatus "@baseboard_fab2_lib.baseboard_fab2(sch_1):page49_i111:a0" )
			)
			( pin "J4B1.72"
				( objectStatus "@baseboard_fab2_lib.baseboard_fab2(sch_1):page49_i111:a1" )
			)
			( pin "J4B1.216"
				( objectStatus "@baseboard_fab2_lib.baseboard_fab2(sch_1):page49_i111:a2" )
			)
			( pin "J4B1.71"
				( objectStatus "@baseboard_fab2_lib.baseboard_fab2(sch_1):page49_i111:a3" )
			)
			( pin "J4B1.214"
				( objectStatus "@baseboard_fab2_lib.baseboard_fab2(sch_1):page49_i111:a4" )
			)
			( pin "J4B1.213"
				( objectStatus "@baseboard_fab2_lib.baseboard_fab2(sch_1):page49_i111:a5" )
			)
			( pin "J4B1.69"
				( objectStatus "@baseboard_fab2_lib.baseboard_fab2(sch_1):page49_i111:a6" )
			)
			( pin "J4B1.211"
				( objectStatus "@baseboard_fab2_lib.baseboard_fab2(sch_1):page49_i111:a7" )
			)
			( pin "J4B1.68"
				( objectStatus "@baseboard_fab2_lib.baseboard_fab2(sch_1):page49_i111:a8" )
			)
			( pin "J4B1.66"
				( objectStatus "@baseboard_fab2_lib.baseboard_fab2(sch_1):page49_i111:a9" )
			)
			( pin "J4B1.225"
				( objectStatus "@baseboard_fab2_lib.baseboard_fab2(sch_1):page49_i111:a10" )
			)
			( pin "J4B1.210"
				( objectStatus "@baseboard_fab2_lib.baseboard_fab2(sch_1):page49_i111:a11" )
			)
			( pin "J4B1.65"
				( objectStatus "@baseboard_fab2_lib.baseboard_fab2(sch_1):page49_i111:a12" )
			)
			( pin "J4B1.232"
				( objectStatus "@baseboard_fab2_lib.baseboard_fab2(sch_1):page49_i111:a13" )
			)
			( pin "J4B1.228"
				( objectStatus "@baseboard_fab2_lib.baseboard_fab2(sch_1):page49_i111:a14_we_n" )
			)
			( pin "J4B1.86"
				( objectStatus "@baseboard_fab2_lib.baseboard_fab2(sch_1):page49_i111:a15_cas_n" )
			)
			( pin "J4B1.82"
				( objectStatus "@baseboard_fab2_lib.baseboard_fab2(sch_1):page49_i111:a16_ras_n" )
			)
			( pin "J4B1.234"
				( objectStatus "@baseboard_fab2_lib.baseboard_fab2(sch_1):page49_i111:a17" )
			)
			( pin "J4B1.62"
				( objectStatus "@baseboard_fab2_lib.baseboard_fab2(sch_1):page49_i111:act_n" )
			)
			( pin "J4B1.208"
				( objectStatus "@baseboard_fab2_lib.baseboard_fab2(sch_1):page49_i111:alert_n" )
			)
			( pin "J4B1.81"
				( objectStatus "@baseboard_fab2_lib.baseboard_fab2(sch_1):page49_i111:ba(0)" )
			)
			( pin "J4B1.224"
				( objectStatus "@baseboard_fab2_lib.baseboard_fab2(sch_1):page49_i111:ba(1)" )
			)
			( pin "J4B1.63"
				( objectStatus "@baseboard_fab2_lib.baseboard_fab2(sch_1):page49_i111:bg(0)" )
			)
			( pin "J4B1.207"
				( objectStatus "@baseboard_fab2_lib.baseboard_fab2(sch_1):page49_i111:bg(1)" )
			)
			( pin "J4B1.235"
				( objectStatus "@baseboard_fab2_lib.baseboard_fab2(sch_1):page49_i111:c(2)" )
			)
			( pin "J4B1.49"
				( objectStatus "@baseboard_fab2_lib.baseboard_fab2(sch_1):page49_i111:cb(0)" )
			)
			( pin "J4B1.194"
				( objectStatus "@baseboard_fab2_lib.baseboard_fab2(sch_1):page49_i111:cb(1)" )
			)
			( pin "J4B1.56"
				( objectStatus "@baseboard_fab2_lib.baseboard_fab2(sch_1):page49_i111:cb(2)" )
			)
			( pin "J4B1.201"
				( objectStatus "@baseboard_fab2_lib.baseboard_fab2(sch_1):page49_i111:cb(3)" )
			)
			( pin "J4B1.47"
				( objectStatus "@baseboard_fab2_lib.baseboard_fab2(sch_1):page49_i111:cb(4)" )
			)
			( pin "J4B1.192"
				( objectStatus "@baseboard_fab2_lib.baseboard_fab2(sch_1):page49_i111:cb(5)" )
			)
			( pin "J4B1.54"
				( objectStatus "@baseboard_fab2_lib.baseboard_fab2(sch_1):page49_i111:cb(6)" )
			)
			( pin "J4B1.199"
				( objectStatus "@baseboard_fab2_lib.baseboard_fab2(sch_1):page49_i111:cb(7)" )
			)
			( pin "J4B1.75"
				( objectStatus "@baseboard_fab2_lib.baseboard_fab2(sch_1):page49_i111:ck0n" )
			)
			( pin "J4B1.74"
				( objectStatus "@baseboard_fab2_lib.baseboard_fab2(sch_1):page49_i111:ck0p" )
			)
			( pin "J4B1.219"
				( objectStatus "@baseboard_fab2_lib.baseboard_fab2(sch_1):page49_i111:ck1n" )
			)
			( pin "J4B1.218"
				( objectStatus "@baseboard_fab2_lib.baseboard_fab2(sch_1):page49_i111:ck1p" )
			)
			( pin "J4B1.60"
				( objectStatus "@baseboard_fab2_lib.baseboard_fab2(sch_1):page49_i111:cke(0)" )
			)
			( pin "J4B1.203"
				( objectStatus "@baseboard_fab2_lib.baseboard_fab2(sch_1):page49_i111:cke(1)" )
			)
			( pin "J4B1.5"
				( objectStatus "@baseboard_fab2_lib.baseboard_fab2(sch_1):page49_i111:dq(0)" )
			)
			( pin "J4B1.150"
				( objectStatus "@baseboard_fab2_lib.baseboard_fab2(sch_1):page49_i111:dq(1)" )
			)
			( pin "J4B1.12"
				( objectStatus "@baseboard_fab2_lib.baseboard_fab2(sch_1):page49_i111:dq(2)" )
			)
			( pin "J4B1.157"
				( objectStatus "@baseboard_fab2_lib.baseboard_fab2(sch_1):page49_i111:dq(3)" )
			)
			( pin "J4B1.3"
				( objectStatus "@baseboard_fab2_lib.baseboard_fab2(sch_1):page49_i111:dq(4)" )
			)
			( pin "J4B1.148"
				( objectStatus "@baseboard_fab2_lib.baseboard_fab2(sch_1):page49_i111:dq(5)" )
			)
			( pin "J4B1.10"
				( objectStatus "@baseboard_fab2_lib.baseboard_fab2(sch_1):page49_i111:dq(6)" )
			)
			( pin "J4B1.155"
				( objectStatus "@baseboard_fab2_lib.baseboard_fab2(sch_1):page49_i111:dq(7)" )
			)
			( pin "J4B1.16"
				( objectStatus "@baseboard_fab2_lib.baseboard_fab2(sch_1):page49_i111:dq(8)" )
			)
			( pin "J4B1.161"
				( objectStatus "@baseboard_fab2_lib.baseboard_fab2(sch_1):page49_i111:dq(9)" )
			)
			( pin "J4B1.23"
				( objectStatus "@baseboard_fab2_lib.baseboard_fab2(sch_1):page49_i111:dq(10)" )
			)
			( pin "J4B1.168"
				( objectStatus "@baseboard_fab2_lib.baseboard_fab2(sch_1):page49_i111:dq(11)" )
			)
			( pin "J4B1.14"
				( objectStatus "@baseboard_fab2_lib.baseboard_fab2(sch_1):page49_i111:dq(12)" )
			)
			( pin "J4B1.159"
				( objectStatus "@baseboard_fab2_lib.baseboard_fab2(sch_1):page49_i111:dq(13)" )
			)
			( pin "J4B1.21"
				( objectStatus "@baseboard_fab2_lib.baseboard_fab2(sch_1):page49_i111:dq(14)" )
			)
			( pin "J4B1.166"
				( objectStatus "@baseboard_fab2_lib.baseboard_fab2(sch_1):page49_i111:dq(15)" )
			)
			( pin "J4B1.27"
				( objectStatus "@baseboard_fab2_lib.baseboard_fab2(sch_1):page49_i111:dq(16)" )
			)
			( pin "J4B1.172"
				( objectStatus "@baseboard_fab2_lib.baseboard_fab2(sch_1):page49_i111:dq(17)" )
			)
			( pin "J4B1.34"
				( objectStatus "@baseboard_fab2_lib.baseboard_fab2(sch_1):page49_i111:dq(18)" )
			)
			( pin "J4B1.179"
				( objectStatus "@baseboard_fab2_lib.baseboard_fab2(sch_1):page49_i111:dq(19)" )
			)
			( pin "J4B1.25"
				( objectStatus "@baseboard_fab2_lib.baseboard_fab2(sch_1):page49_i111:dq(20)" )
			)
			( pin "J4B1.170"
				( objectStatus "@baseboard_fab2_lib.baseboard_fab2(sch_1):page49_i111:dq(21)" )
			)
			( pin "J4B1.32"
				( objectStatus "@baseboard_fab2_lib.baseboard_fab2(sch_1):page49_i111:dq(22)" )
			)
			( pin "J4B1.177"
				( objectStatus "@baseboard_fab2_lib.baseboard_fab2(sch_1):page49_i111:dq(23)" )
			)
			( pin "J4B1.38"
				( objectStatus "@baseboard_fab2_lib.baseboard_fab2(sch_1):page49_i111:dq(24)" )
			)
			( pin "J4B1.183"
				( objectStatus "@baseboard_fab2_lib.baseboard_fab2(sch_1):page49_i111:dq(25)" )
			)
			( pin "J4B1.45"
				( objectStatus "@baseboard_fab2_lib.baseboard_fab2(sch_1):page49_i111:dq(26)" )
			)
			( pin "J4B1.190"
				( objectStatus "@baseboard_fab2_lib.baseboard_fab2(sch_1):page49_i111:dq(27)" )
			)
			( pin "J4B1.36"
				( objectStatus "@baseboard_fab2_lib.baseboard_fab2(sch_1):page49_i111:dq(28)" )
			)
			( pin "J4B1.181"
				( objectStatus "@baseboard_fab2_lib.baseboard_fab2(sch_1):page49_i111:dq(29)" )
			)
			( pin "J4B1.43"
				( objectStatus "@baseboard_fab2_lib.baseboard_fab2(sch_1):page49_i111:dq(30)" )
			)
			( pin "J4B1.188"
				( objectStatus "@baseboard_fab2_lib.baseboard_fab2(sch_1):page49_i111:dq(31)" )
			)
			( pin "J4B1.97"
				( objectStatus "@baseboard_fab2_lib.baseboard_fab2(sch_1):page49_i111:dq(32)" )
			)
			( pin "J4B1.242"
				( objectStatus "@baseboard_fab2_lib.baseboard_fab2(sch_1):page49_i111:dq(33)" )
			)
			( pin "J4B1.104"
				( objectStatus "@baseboard_fab2_lib.baseboard_fab2(sch_1):page49_i111:dq(34)" )
			)
			( pin "J4B1.249"
				( objectStatus "@baseboard_fab2_lib.baseboard_fab2(sch_1):page49_i111:dq(35)" )
			)
			( pin "J4B1.95"
				( objectStatus "@baseboard_fab2_lib.baseboard_fab2(sch_1):page49_i111:dq(36)" )
			)
			( pin "J4B1.240"
				( objectStatus "@baseboard_fab2_lib.baseboard_fab2(sch_1):page49_i111:dq(37)" )
			)
			( pin "J4B1.102"
				( objectStatus "@baseboard_fab2_lib.baseboard_fab2(sch_1):page49_i111:dq(38)" )
			)
			( pin "J4B1.247"
				( objectStatus "@baseboard_fab2_lib.baseboard_fab2(sch_1):page49_i111:dq(39)" )
			)
			( pin "J4B1.108"
				( objectStatus "@baseboard_fab2_lib.baseboard_fab2(sch_1):page49_i111:dq(40)" )
			)
			( pin "J4B1.253"
				( objectStatus "@baseboard_fab2_lib.baseboard_fab2(sch_1):page49_i111:dq(41)" )
			)
			( pin "J4B1.115"
				( objectStatus "@baseboard_fab2_lib.baseboard_fab2(sch_1):page49_i111:dq(42)" )
			)
			( pin "J4B1.260"
				( objectStatus "@baseboard_fab2_lib.baseboard_fab2(sch_1):page49_i111:dq(43)" )
			)
			( pin "J4B1.106"
				( objectStatus "@baseboard_fab2_lib.baseboard_fab2(sch_1):page49_i111:dq(44)" )
			)
			( pin "J4B1.251"
				( objectStatus "@baseboard_fab2_lib.baseboard_fab2(sch_1):page49_i111:dq(45)" )
			)
			( pin "J4B1.113"
				( objectStatus "@baseboard_fab2_lib.baseboard_fab2(sch_1):page49_i111:dq(46)" )
			)
			( pin "J4B1.258"
				( objectStatus "@baseboard_fab2_lib.baseboard_fab2(sch_1):page49_i111:dq(47)" )
			)
			( pin "J4B1.119"
				( objectStatus "@baseboard_fab2_lib.baseboard_fab2(sch_1):page49_i111:dq(48)" )
			)
			( pin "J4B1.264"
				( objectStatus "@baseboard_fab2_lib.baseboard_fab2(sch_1):page49_i111:dq(49)" )
			)
			( pin "J4B1.126"
				( objectStatus "@baseboard_fab2_lib.baseboard_fab2(sch_1):page49_i111:dq(50)" )
			)
			( pin "J4B1.271"
				( objectStatus "@baseboard_fab2_lib.baseboard_fab2(sch_1):page49_i111:dq(51)" )
			)
			( pin "J4B1.117"
				( objectStatus "@baseboard_fab2_lib.baseboard_fab2(sch_1):page49_i111:dq(52)" )
			)
			( pin "J4B1.262"
				( objectStatus "@baseboard_fab2_lib.baseboard_fab2(sch_1):page49_i111:dq(53)" )
			)
			( pin "J4B1.124"
				( objectStatus "@baseboard_fab2_lib.baseboard_fab2(sch_1):page49_i111:dq(54)" )
			)
			( pin "J4B1.269"
				( objectStatus "@baseboard_fab2_lib.baseboard_fab2(sch_1):page49_i111:dq(55)" )
			)
			( pin "J4B1.130"
				( objectStatus "@baseboard_fab2_lib.baseboard_fab2(sch_1):page49_i111:dq(56)" )
			)
			( pin "J4B1.275"
				( objectStatus "@baseboard_fab2_lib.baseboard_fab2(sch_1):page49_i111:dq(57)" )
			)
			( pin "J4B1.137"
				( objectStatus "@baseboard_fab2_lib.baseboard_fab2(sch_1):page49_i111:dq(58)" )
			)
			( pin "J4B1.282"
				( objectStatus "@baseboard_fab2_lib.baseboard_fab2(sch_1):page49_i111:dq(59)" )
			)
			( pin "J4B1.128"
				( objectStatus "@baseboard_fab2_lib.baseboard_fab2(sch_1):page49_i111:dq(60)" )
			)
			( pin "J4B1.273"
				( objectStatus "@baseboard_fab2_lib.baseboard_fab2(sch_1):page49_i111:dq(61)" )
			)
			( pin "J4B1.135"
				( objectStatus "@baseboard_fab2_lib.baseboard_fab2(sch_1):page49_i111:dq(62)" )
			)
			( pin "J4B1.280"
				( objectStatus "@baseboard_fab2_lib.baseboard_fab2(sch_1):page49_i111:dq(63)" )
			)
			( pin "J4B1.78"
				( objectStatus "@baseboard_fab2_lib.baseboard_fab2(sch_1):page49_i111:event_n" )
			)
			( pin "J4B1.87"
				( objectStatus "@baseboard_fab2_lib.baseboard_fab2(sch_1):page49_i111:odt(0)" )
			)
			( pin "J4B1.91"
				( objectStatus "@baseboard_fab2_lib.baseboard_fab2(sch_1):page49_i111:odt(1)" )
			)
			( pin "J4B1.222"
				( objectStatus "@baseboard_fab2_lib.baseboard_fab2(sch_1):page49_i111:par" )
			)
			( pin "J4B1.58"
				( objectStatus "@baseboard_fab2_lib.baseboard_fab2(sch_1):page49_i111:reset_n" )
			)
			( pin "J4B1.205"
				( objectStatus "@baseboard_fab2_lib.baseboard_fab2(sch_1):page49_i111:rfu(0)" )
			)
			( pin "J4B1.227"
				( objectStatus "@baseboard_fab2_lib.baseboard_fab2(sch_1):page49_i111:rfu(1)" )
			)
			( pin "J4B1.144"
				( objectStatus "@baseboard_fab2_lib.baseboard_fab2(sch_1):page49_i111:rfu(2)" )
			)
			( pin "J4B1.84"
				( objectStatus "@baseboard_fab2_lib.baseboard_fab2(sch_1):page49_i111:s0_n" )
			)
			( pin "J4B1.89"
				( objectStatus "@baseboard_fab2_lib.baseboard_fab2(sch_1):page49_i111:s1_n" )
			)
			( pin "J4B1.93"
				( objectStatus "@baseboard_fab2_lib.baseboard_fab2(sch_1):page49_i111:s2_n_c(0)" )
			)
			( pin "J4B1.237"
				( objectStatus "@baseboard_fab2_lib.baseboard_fab2(sch_1):page49_i111:s3_n_c(1)" )
			)
			( pin "J4B1.139"
				( objectStatus "@baseboard_fab2_lib.baseboard_fab2(sch_1):page49_i111:sa(0)" )
			)
			( pin "J4B1.140"
				( objectStatus "@baseboard_fab2_lib.baseboard_fab2(sch_1):page49_i111:sa(1)" )
			)
			( pin "J4B1.238"
				( objectStatus "@baseboard_fab2_lib.baseboard_fab2(sch_1):page49_i111:sa(2)" )
			)
			( pin "J4B1.230"
				( objectStatus "@baseboard_fab2_lib.baseboard_fab2(sch_1):page49_i111:save_n_nc" )
			)
			( pin "J4B1.141"
				( objectStatus "@baseboard_fab2_lib.baseboard_fab2(sch_1):page49_i111:scl" )
			)
			( pin "J4B1.285"
				( objectStatus "@baseboard_fab2_lib.baseboard_fab2(sch_1):page49_i111:sda" )
			)
			( pin "J4B1.284"
				( objectStatus "@baseboard_fab2_lib.baseboard_fab2(sch_1):page49_i111:vddspd" )
			)
			( pin "J4B1.146"
				( objectStatus "@baseboard_fab2_lib.baseboard_fab2(sch_1):page49_i111:vrefca" )
			)
			( pin "J4B1.145"
				( objectStatus "@baseboard_fab2_lib.baseboard_fab2(sch_1):page49_i169:\12v\(0)" )
			)
			( pin "J4B1.1"
				( objectStatus "@baseboard_fab2_lib.baseboard_fab2(sch_1):page49_i169:\12v\(1)" )
			)
			( pin "J4B1.236"
				( objectStatus "@baseboard_fab2_lib.baseboard_fab2(sch_1):page49_i169:vdd(0)" )
			)
			( pin "J4B1.233"
				( objectStatus "@baseboard_fab2_lib.baseboard_fab2(sch_1):page49_i169:vdd(1)" )
			)
			( pin "J4B1.231"
				( objectStatus "@baseboard_fab2_lib.baseboard_fab2(sch_1):page49_i169:vdd(2)" )
			)
			( pin "J4B1.229"
				( objectStatus "@baseboard_fab2_lib.baseboard_fab2(sch_1):page49_i169:vdd(3)" )
			)
			( pin "J4B1.226"
				( objectStatus "@baseboard_fab2_lib.baseboard_fab2(sch_1):page49_i169:vdd(4)" )
			)
			( pin "J4B1.223"
				( objectStatus "@baseboard_fab2_lib.baseboard_fab2(sch_1):page49_i169:vdd(5)" )
			)
			( pin "J4B1.220"
				( objectStatus "@baseboard_fab2_lib.baseboard_fab2(sch_1):page49_i169:vdd(6)" )
			)
			( pin "J4B1.217"
				( objectStatus "@baseboard_fab2_lib.baseboard_fab2(sch_1):page49_i169:vdd(7)" )
			)
			( pin "J4B1.215"
				( objectStatus "@baseboard_fab2_lib.baseboard_fab2(sch_1):page49_i169:vdd(8)" )
			)
			( pin "J4B1.212"
				( objectStatus "@baseboard_fab2_lib.baseboard_fab2(sch_1):page49_i169:vdd(9)" )
			)
			( pin "J4B1.209"
				( objectStatus "@baseboard_fab2_lib.baseboard_fab2(sch_1):page49_i169:vdd(10)" )
			)
			( pin "J4B1.206"
				( objectStatus "@baseboard_fab2_lib.baseboard_fab2(sch_1):page49_i169:vdd(11)" )
			)
			( pin "J4B1.204"
				( objectStatus "@baseboard_fab2_lib.baseboard_fab2(sch_1):page49_i169:vdd(12)" )
			)
			( pin "J4B1.92"
				( objectStatus "@baseboard_fab2_lib.baseboard_fab2(sch_1):page49_i169:vdd(13)" )
			)
			( pin "J4B1.90"
				( objectStatus "@baseboard_fab2_lib.baseboard_fab2(sch_1):page49_i169:vdd(14)" )
			)
			( pin "J4B1.88"
				( objectStatus "@baseboard_fab2_lib.baseboard_fab2(sch_1):page49_i169:vdd(15)" )
			)
			( pin "J4B1.85"
				( objectStatus "@baseboard_fab2_lib.baseboard_fab2(sch_1):page49_i169:vdd(16)" )
			)
			( pin "J4B1.83"
				( objectStatus "@baseboard_fab2_lib.baseboard_fab2(sch_1):page49_i169:vdd(17)" )
			)
			( pin "J4B1.80"
				( objectStatus "@baseboard_fab2_lib.baseboard_fab2(sch_1):page49_i169:vdd(18)" )
			)
			( pin "J4B1.76"
				( objectStatus "@baseboard_fab2_lib.baseboard_fab2(sch_1):page49_i169:vdd(19)" )
			)
			( pin "J4B1.73"
				( objectStatus "@baseboard_fab2_lib.baseboard_fab2(sch_1):page49_i169:vdd(20)" )
			)
			( pin "J4B1.70"
				( objectStatus "@baseboard_fab2_lib.baseboard_fab2(sch_1):page49_i169:vdd(21)" )
			)
			( pin "J4B1.67"
				( objectStatus "@baseboard_fab2_lib.baseboard_fab2(sch_1):page49_i169:vdd(22)" )
			)
			( pin "J4B1.64"
				( objectStatus "@baseboard_fab2_lib.baseboard_fab2(sch_1):page49_i169:vdd(23)" )
			)
			( pin "J4B1.61"
				( objectStatus "@baseboard_fab2_lib.baseboard_fab2(sch_1):page49_i169:vdd(24)" )
			)
			( pin "J4B1.59"
				( objectStatus "@baseboard_fab2_lib.baseboard_fab2(sch_1):page49_i169:vdd(25)" )
			)
			( pin "J4B1.287"
				( objectStatus "@baseboard_fab2_lib.baseboard_fab2(sch_1):page49_i169:vpp(0)" )
			)
			( pin "J4B1.286"
				( objectStatus "@baseboard_fab2_lib.baseboard_fab2(sch_1):page49_i169:vpp(1)" )
			)
			( pin "J4B1.288"
				( objectStatus "@baseboard_fab2_lib.baseboard_fab2(sch_1):page49_i169:vpp(2)" )
			)
			( pin "J4B1.143"
				( objectStatus "@baseboard_fab2_lib.baseboard_fab2(sch_1):page49_i169:vpp(3)" )
			)
			( pin "J4B1.142"
				( objectStatus "@baseboard_fab2_lib.baseboard_fab2(sch_1):page49_i169:vpp(4)" )
			)
			( pin "J4B1.221"
				( objectStatus "@baseboard_fab2_lib.baseboard_fab2(sch_1):page49_i169:vtt(0)" )
			)
			( pin "J4B1.77"
				( objectStatus "@baseboard_fab2_lib.baseboard_fab2(sch_1):page49_i169:vtt(1)" )
			)
			( pin "C4B12.1"
				( objectStatus "@baseboard_fab2_lib.baseboard_fab2(sch_1):page49_i179:a" )
			)
			( pin "C4B12.2"
				( objectStatus "@baseboard_fab2_lib.baseboard_fab2(sch_1):page49_i179:b" )
			)
			( pin "J6M1.283"
				( objectStatus "@baseboard_fab2_lib.baseboard_fab2(sch_1):page50_i44:vss(0)" )
			)
			( pin "J6M1.281"
				( objectStatus "@baseboard_fab2_lib.baseboard_fab2(sch_1):page50_i44:vss(1)" )
			)
			( pin "J6M1.279"
				( objectStatus "@baseboard_fab2_lib.baseboard_fab2(sch_1):page50_i44:vss(2)" )
			)
			( pin "J6M1.276"
				( objectStatus "@baseboard_fab2_lib.baseboard_fab2(sch_1):page50_i44:vss(3)" )
			)
			( pin "J6M1.274"
				( objectStatus "@baseboard_fab2_lib.baseboard_fab2(sch_1):page50_i44:vss(4)" )
			)
			( pin "J6M1.272"
				( objectStatus "@baseboard_fab2_lib.baseboard_fab2(sch_1):page50_i44:vss(5)" )
			)
			( pin "J6M1.270"
				( objectStatus "@baseboard_fab2_lib.baseboard_fab2(sch_1):page50_i44:vss(6)" )
			)
			( pin "J6M1.268"
				( objectStatus "@baseboard_fab2_lib.baseboard_fab2(sch_1):page50_i44:vss(7)" )
			)
			( pin "J6M1.265"
				( objectStatus "@baseboard_fab2_lib.baseboard_fab2(sch_1):page50_i44:vss(8)" )
			)
			( pin "J6M1.263"
				( objectStatus "@baseboard_fab2_lib.baseboard_fab2(sch_1):page50_i44:vss(9)" )
			)
			( pin "J6M1.261"
				( objectStatus "@baseboard_fab2_lib.baseboard_fab2(sch_1):page50_i44:vss(10)" )
			)
			( pin "J6M1.259"
				( objectStatus "@baseboard_fab2_lib.baseboard_fab2(sch_1):page50_i44:vss(11)" )
			)
			( pin "J6M1.257"
				( objectStatus "@baseboard_fab2_lib.baseboard_fab2(sch_1):page50_i44:vss(12)" )
			)
			( pin "J6M1.254"
				( objectStatus "@baseboard_fab2_lib.baseboard_fab2(sch_1):page50_i44:vss(13)" )
			)
			( pin "J6M1.252"
				( objectStatus "@baseboard_fab2_lib.baseboard_fab2(sch_1):page50_i44:vss(14)" )
			)
			( pin "J6M1.250"
				( objectStatus "@baseboard_fab2_lib.baseboard_fab2(sch_1):page50_i44:vss(15)" )
			)
			( pin "J6M1.248"
				( objectStatus "@baseboard_fab2_lib.baseboard_fab2(sch_1):page50_i44:vss(16)" )
			)
			( pin "J6M1.246"
				( objectStatus "@baseboard_fab2_lib.baseboard_fab2(sch_1):page50_i44:vss(17)" )
			)
			( pin "J6M1.243"
				( objectStatus "@baseboard_fab2_lib.baseboard_fab2(sch_1):page50_i44:vss(18)" )
			)
			( pin "J6M1.241"
				( objectStatus "@baseboard_fab2_lib.baseboard_fab2(sch_1):page50_i44:vss(19)" )
			)
			( pin "J6M1.239"
				( objectStatus "@baseboard_fab2_lib.baseboard_fab2(sch_1):page50_i44:vss(20)" )
			)
			( pin "J6M1.202"
				( objectStatus "@baseboard_fab2_lib.baseboard_fab2(sch_1):page50_i44:vss(21)" )
			)
			( pin "J6M1.200"
				( objectStatus "@baseboard_fab2_lib.baseboard_fab2(sch_1):page50_i44:vss(22)" )
			)
			( pin "J6M1.198"
				( objectStatus "@baseboard_fab2_lib.baseboard_fab2(sch_1):page50_i44:vss(23)" )
			)
			( pin "J6M1.195"
				( objectStatus "@baseboard_fab2_lib.baseboard_fab2(sch_1):page50_i44:vss(24)" )
			)
			( pin "J6M1.193"
				( objectStatus "@baseboard_fab2_lib.baseboard_fab2(sch_1):page50_i44:vss(25)" )
			)
			( pin "J6M1.191"
				( objectStatus "@baseboard_fab2_lib.baseboard_fab2(sch_1):page50_i44:vss(26)" )
			)
			( pin "J6M1.189"
				( objectStatus "@baseboard_fab2_lib.baseboard_fab2(sch_1):page50_i44:vss(27)" )
			)
			( pin "J6M1.187"
				( objectStatus "@baseboard_fab2_lib.baseboard_fab2(sch_1):page50_i44:vss(28)" )
			)
			( pin "J6M1.184"
				( objectStatus "@baseboard_fab2_lib.baseboard_fab2(sch_1):page50_i44:vss(29)" )
			)
			( pin "J6M1.182"
				( objectStatus "@baseboard_fab2_lib.baseboard_fab2(sch_1):page50_i44:vss(30)" )
			)
			( pin "J6M1.180"
				( objectStatus "@baseboard_fab2_lib.baseboard_fab2(sch_1):page50_i44:vss(31)" )
			)
			( pin "J6M1.178"
				( objectStatus "@baseboard_fab2_lib.baseboard_fab2(sch_1):page50_i44:vss(32)" )
			)
			( pin "J6M1.176"
				( objectStatus "@baseboard_fab2_lib.baseboard_fab2(sch_1):page50_i44:vss(33)" )
			)
			( pin "J6M1.173"
				( objectStatus "@baseboard_fab2_lib.baseboard_fab2(sch_1):page50_i44:vss(34)" )
			)
			( pin "J6M1.171"
				( objectStatus "@baseboard_fab2_lib.baseboard_fab2(sch_1):page50_i44:vss(35)" )
			)
			( pin "J6M1.169"
				( objectStatus "@baseboard_fab2_lib.baseboard_fab2(sch_1):page50_i44:vss(36)" )
			)
			( pin "J6M1.167"
				( objectStatus "@baseboard_fab2_lib.baseboard_fab2(sch_1):page50_i44:vss(37)" )
			)
			( pin "J6M1.165"
				( objectStatus "@baseboard_fab2_lib.baseboard_fab2(sch_1):page50_i44:vss(38)" )
			)
			( pin "J6M1.162"
				( objectStatus "@baseboard_fab2_lib.baseboard_fab2(sch_1):page50_i44:vss(39)" )
			)
			( pin "J6M1.160"
				( objectStatus "@baseboard_fab2_lib.baseboard_fab2(sch_1):page50_i44:vss(40)" )
			)
			( pin "J6M1.158"
				( objectStatus "@baseboard_fab2_lib.baseboard_fab2(sch_1):page50_i44:vss(41)" )
			)
			( pin "J6M1.156"
				( objectStatus "@baseboard_fab2_lib.baseboard_fab2(sch_1):page50_i44:vss(42)" )
			)
			( pin "J6M1.154"
				( objectStatus "@baseboard_fab2_lib.baseboard_fab2(sch_1):page50_i44:vss(43)" )
			)
			( pin "J6M1.151"
				( objectStatus "@baseboard_fab2_lib.baseboard_fab2(sch_1):page50_i44:vss(44)" )
			)
			( pin "J6M1.149"
				( objectStatus "@baseboard_fab2_lib.baseboard_fab2(sch_1):page50_i44:vss(45)" )
			)
			( pin "J6M1.147"
				( objectStatus "@baseboard_fab2_lib.baseboard_fab2(sch_1):page50_i44:vss(46)" )
			)
			( pin "J6M1.138"
				( objectStatus "@baseboard_fab2_lib.baseboard_fab2(sch_1):page50_i44:vss(47)" )
			)
			( pin "J6M1.136"
				( objectStatus "@baseboard_fab2_lib.baseboard_fab2(sch_1):page50_i44:vss(48)" )
			)
			( pin "J6M1.134"
				( objectStatus "@baseboard_fab2_lib.baseboard_fab2(sch_1):page50_i44:vss(49)" )
			)
			( pin "J6M1.131"
				( objectStatus "@baseboard_fab2_lib.baseboard_fab2(sch_1):page50_i44:vss(50)" )
			)
			( pin "J6M1.129"
				( objectStatus "@baseboard_fab2_lib.baseboard_fab2(sch_1):page50_i44:vss(51)" )
			)
			( pin "J6M1.127"
				( objectStatus "@baseboard_fab2_lib.baseboard_fab2(sch_1):page50_i44:vss(52)" )
			)
			( pin "J6M1.125"
				( objectStatus "@baseboard_fab2_lib.baseboard_fab2(sch_1):page50_i44:vss(53)" )
			)
			( pin "J6M1.123"
				( objectStatus "@baseboard_fab2_lib.baseboard_fab2(sch_1):page50_i44:vss(54)" )
			)
			( pin "J6M1.120"
				( objectStatus "@baseboard_fab2_lib.baseboard_fab2(sch_1):page50_i44:vss(55)" )
			)
			( pin "J6M1.118"
				( objectStatus "@baseboard_fab2_lib.baseboard_fab2(sch_1):page50_i44:vss(56)" )
			)
			( pin "J6M1.116"
				( objectStatus "@baseboard_fab2_lib.baseboard_fab2(sch_1):page50_i44:vss(57)" )
			)
			( pin "J6M1.114"
				( objectStatus "@baseboard_fab2_lib.baseboard_fab2(sch_1):page50_i44:vss(58)" )
			)
			( pin "J6M1.112"
				( objectStatus "@baseboard_fab2_lib.baseboard_fab2(sch_1):page50_i44:vss(59)" )
			)
			( pin "J6M1.109"
				( objectStatus "@baseboard_fab2_lib.baseboard_fab2(sch_1):page50_i44:vss(60)" )
			)
			( pin "J6M1.107"
				( objectStatus "@baseboard_fab2_lib.baseboard_fab2(sch_1):page50_i44:vss(61)" )
			)
			( pin "J6M1.105"
				( objectStatus "@baseboard_fab2_lib.baseboard_fab2(sch_1):page50_i44:vss(62)" )
			)
			( pin "J6M1.103"
				( objectStatus "@baseboard_fab2_lib.baseboard_fab2(sch_1):page50_i44:vss(63)" )
			)
			( pin "J6M1.101"
				( objectStatus "@baseboard_fab2_lib.baseboard_fab2(sch_1):page50_i44:vss(64)" )
			)
			( pin "J6M1.98"
				( objectStatus "@baseboard_fab2_lib.baseboard_fab2(sch_1):page50_i44:vss(65)" )
			)
			( pin "J6M1.96"
				( objectStatus "@baseboard_fab2_lib.baseboard_fab2(sch_1):page50_i44:vss(66)" )
			)
			( pin "J6M1.94"
				( objectStatus "@baseboard_fab2_lib.baseboard_fab2(sch_1):page50_i44:vss(67)" )
			)
			( pin "J6M1.57"
				( objectStatus "@baseboard_fab2_lib.baseboard_fab2(sch_1):page50_i44:vss(68)" )
			)
			( pin "J6M1.55"
				( objectStatus "@baseboard_fab2_lib.baseboard_fab2(sch_1):page50_i44:vss(69)" )
			)
			( pin "J6M1.53"
				( objectStatus "@baseboard_fab2_lib.baseboard_fab2(sch_1):page50_i44:vss(70)" )
			)
			( pin "J6M1.50"
				( objectStatus "@baseboard_fab2_lib.baseboard_fab2(sch_1):page50_i44:vss(71)" )
			)
			( pin "J6M1.48"
				( objectStatus "@baseboard_fab2_lib.baseboard_fab2(sch_1):page50_i44:vss(72)" )
			)
			( pin "J6M1.46"
				( objectStatus "@baseboard_fab2_lib.baseboard_fab2(sch_1):page50_i44:vss(73)" )
			)
			( pin "J6M1.44"
				( objectStatus "@baseboard_fab2_lib.baseboard_fab2(sch_1):page50_i44:vss(74)" )
			)
			( pin "J6M1.42"
				( objectStatus "@baseboard_fab2_lib.baseboard_fab2(sch_1):page50_i44:vss(75)" )
			)
			( pin "J6M1.39"
				( objectStatus "@baseboard_fab2_lib.baseboard_fab2(sch_1):page50_i44:vss(76)" )
			)
			( pin "J6M1.37"
				( objectStatus "@baseboard_fab2_lib.baseboard_fab2(sch_1):page50_i44:vss(77)" )
			)
			( pin "J6M1.35"
				( objectStatus "@baseboard_fab2_lib.baseboard_fab2(sch_1):page50_i44:vss(78)" )
			)
			( pin "J6M1.33"
				( objectStatus "@baseboard_fab2_lib.baseboard_fab2(sch_1):page50_i44:vss(79)" )
			)
			( pin "J6M1.31"
				( objectStatus "@baseboard_fab2_lib.baseboard_fab2(sch_1):page50_i44:vss(80)" )
			)
			( pin "J6M1.28"
				( objectStatus "@baseboard_fab2_lib.baseboard_fab2(sch_1):page50_i44:vss(81)" )
			)
			( pin "J6M1.26"
				( objectStatus "@baseboard_fab2_lib.baseboard_fab2(sch_1):page50_i44:vss(82)" )
			)
			( pin "J6M1.24"
				( objectStatus "@baseboard_fab2_lib.baseboard_fab2(sch_1):page50_i44:vss(83)" )
			)
			( pin "J6M1.22"
				( objectStatus "@baseboard_fab2_lib.baseboard_fab2(sch_1):page50_i44:vss(84)" )
			)
			( pin "J6M1.20"
				( objectStatus "@baseboard_fab2_lib.baseboard_fab2(sch_1):page50_i44:vss(85)" )
			)
			( pin "J6M1.17"
				( objectStatus "@baseboard_fab2_lib.baseboard_fab2(sch_1):page50_i44:vss(86)" )
			)
			( pin "J6M1.15"
				( objectStatus "@baseboard_fab2_lib.baseboard_fab2(sch_1):page50_i44:vss(87)" )
			)
			( pin "J6M1.13"
				( objectStatus "@baseboard_fab2_lib.baseboard_fab2(sch_1):page50_i44:vss(88)" )
			)
			( pin "J6M1.11"
				( objectStatus "@baseboard_fab2_lib.baseboard_fab2(sch_1):page50_i44:vss(89)" )
			)
			( pin "J6M1.9"
				( objectStatus "@baseboard_fab2_lib.baseboard_fab2(sch_1):page50_i44:vss(90)" )
			)
			( pin "J6M1.6"
				( objectStatus "@baseboard_fab2_lib.baseboard_fab2(sch_1):page50_i44:vss(91)" )
			)
			( pin "J6M1.4"
				( objectStatus "@baseboard_fab2_lib.baseboard_fab2(sch_1):page50_i44:vss(92)" )
			)
			( pin "J6M1.2"
				( objectStatus "@baseboard_fab2_lib.baseboard_fab2(sch_1):page50_i44:vss(93)" )
			)
			( pin "J6M1.152"
				( objectStatus "@baseboard_fab2_lib.baseboard_fab2(sch_1):page50_i46:dqs0n" )
			)
			( pin "J6M1.153"
				( objectStatus "@baseboard_fab2_lib.baseboard_fab2(sch_1):page50_i46:dqs0p" )
			)
			( pin "J6M1.163"
				( objectStatus "@baseboard_fab2_lib.baseboard_fab2(sch_1):page50_i46:dqs1n" )
			)
			( pin "J6M1.164"
				( objectStatus "@baseboard_fab2_lib.baseboard_fab2(sch_1):page50_i46:dqs1p" )
			)
			( pin "J6M1.174"
				( objectStatus "@baseboard_fab2_lib.baseboard_fab2(sch_1):page50_i46:dqs2n" )
			)
			( pin "J6M1.175"
				( objectStatus "@baseboard_fab2_lib.baseboard_fab2(sch_1):page50_i46:dqs2p" )
			)
			( pin "J6M1.185"
				( objectStatus "@baseboard_fab2_lib.baseboard_fab2(sch_1):page50_i46:dqs3n" )
			)
			( pin "J6M1.186"
				( objectStatus "@baseboard_fab2_lib.baseboard_fab2(sch_1):page50_i46:dqs3p" )
			)
			( pin "J6M1.244"
				( objectStatus "@baseboard_fab2_lib.baseboard_fab2(sch_1):page50_i46:dqs4n" )
			)
			( pin "J6M1.245"
				( objectStatus "@baseboard_fab2_lib.baseboard_fab2(sch_1):page50_i46:dqs4p" )
			)
			( pin "J6M1.255"
				( objectStatus "@baseboard_fab2_lib.baseboard_fab2(sch_1):page50_i46:dqs5n" )
			)
			( pin "J6M1.256"
				( objectStatus "@baseboard_fab2_lib.baseboard_fab2(sch_1):page50_i46:dqs5p" )
			)
			( pin "J6M1.266"
				( objectStatus "@baseboard_fab2_lib.baseboard_fab2(sch_1):page50_i46:dqs6n" )
			)
			( pin "J6M1.267"
				( objectStatus "@baseboard_fab2_lib.baseboard_fab2(sch_1):page50_i46:dqs6p" )
			)
			( pin "J6M1.277"
				( objectStatus "@baseboard_fab2_lib.baseboard_fab2(sch_1):page50_i46:dqs7n" )
			)
			( pin "J6M1.278"
				( objectStatus "@baseboard_fab2_lib.baseboard_fab2(sch_1):page50_i46:dqs7p" )
			)
			( pin "J6M1.196"
				( objectStatus "@baseboard_fab2_lib.baseboard_fab2(sch_1):page50_i46:dqs8n" )
			)
			( pin "J6M1.197"
				( objectStatus "@baseboard_fab2_lib.baseboard_fab2(sch_1):page50_i46:dqs8p" )
			)
			( pin "J6M1.8"
				( objectStatus "@baseboard_fab2_lib.baseboard_fab2(sch_1):page50_i46:dqs9n" )
			)
			( pin "J6M1.7"
				( objectStatus "@baseboard_fab2_lib.baseboard_fab2(sch_1):page50_i46:dqs9p" )
			)
			( pin "J6M1.19"
				( objectStatus "@baseboard_fab2_lib.baseboard_fab2(sch_1):page50_i46:dqs10n" )
			)
			( pin "J6M1.18"
				( objectStatus "@baseboard_fab2_lib.baseboard_fab2(sch_1):page50_i46:dqs10p" )
			)
			( pin "J6M1.30"
				( objectStatus "@baseboard_fab2_lib.baseboard_fab2(sch_1):page50_i46:dqs11n" )
			)
			( pin "J6M1.29"
				( objectStatus "@baseboard_fab2_lib.baseboard_fab2(sch_1):page50_i46:dqs11p" )
			)
			( pin "J6M1.41"
				( objectStatus "@baseboard_fab2_lib.baseboard_fab2(sch_1):page50_i46:dqs12n" )
			)
			( pin "J6M1.40"
				( objectStatus "@baseboard_fab2_lib.baseboard_fab2(sch_1):page50_i46:dqs12p" )
			)
			( pin "J6M1.100"
				( objectStatus "@baseboard_fab2_lib.baseboard_fab2(sch_1):page50_i46:dqs13n" )
			)
			( pin "J6M1.99"
				( objectStatus "@baseboard_fab2_lib.baseboard_fab2(sch_1):page50_i46:dqs13p" )
			)
			( pin "J6M1.111"
				( objectStatus "@baseboard_fab2_lib.baseboard_fab2(sch_1):page50_i46:dqs14n" )
			)
			( pin "J6M1.110"
				( objectStatus "@baseboard_fab2_lib.baseboard_fab2(sch_1):page50_i46:dqs14p" )
			)
			( pin "J6M1.122"
				( objectStatus "@baseboard_fab2_lib.baseboard_fab2(sch_1):page50_i46:dqs15n" )
			)
			( pin "J6M1.121"
				( objectStatus "@baseboard_fab2_lib.baseboard_fab2(sch_1):page50_i46:dqs15p" )
			)
			( pin "J6M1.133"
				( objectStatus "@baseboard_fab2_lib.baseboard_fab2(sch_1):page50_i46:dqs16n" )
			)
			( pin "J6M1.132"
				( objectStatus "@baseboard_fab2_lib.baseboard_fab2(sch_1):page50_i46:dqs16p" )
			)
			( pin "J6M1.52"
				( objectStatus "@baseboard_fab2_lib.baseboard_fab2(sch_1):page50_i46:dqs17n" )
			)
			( pin "J6M1.51"
				( objectStatus "@baseboard_fab2_lib.baseboard_fab2(sch_1):page50_i46:dqs17p" )
			)
			( pin "J6M1.145"
				( objectStatus "@baseboard_fab2_lib.baseboard_fab2(sch_1):page50_i50:\12v\(0)" )
			)
			( pin "J6M1.1"
				( objectStatus "@baseboard_fab2_lib.baseboard_fab2(sch_1):page50_i50:\12v\(1)" )
			)
			( pin "J6M1.236"
				( objectStatus "@baseboard_fab2_lib.baseboard_fab2(sch_1):page50_i50:vdd(0)" )
			)
			( pin "J6M1.233"
				( objectStatus "@baseboard_fab2_lib.baseboard_fab2(sch_1):page50_i50:vdd(1)" )
			)
			( pin "J6M1.231"
				( objectStatus "@baseboard_fab2_lib.baseboard_fab2(sch_1):page50_i50:vdd(2)" )
			)
			( pin "J6M1.229"
				( objectStatus "@baseboard_fab2_lib.baseboard_fab2(sch_1):page50_i50:vdd(3)" )
			)
			( pin "J6M1.226"
				( objectStatus "@baseboard_fab2_lib.baseboard_fab2(sch_1):page50_i50:vdd(4)" )
			)
			( pin "J6M1.223"
				( objectStatus "@baseboard_fab2_lib.baseboard_fab2(sch_1):page50_i50:vdd(5)" )
			)
			( pin "J6M1.220"
				( objectStatus "@baseboard_fab2_lib.baseboard_fab2(sch_1):page50_i50:vdd(6)" )
			)
			( pin "J6M1.217"
				( objectStatus "@baseboard_fab2_lib.baseboard_fab2(sch_1):page50_i50:vdd(7)" )
			)
			( pin "J6M1.215"
				( objectStatus "@baseboard_fab2_lib.baseboard_fab2(sch_1):page50_i50:vdd(8)" )
			)
			( pin "J6M1.212"
				( objectStatus "@baseboard_fab2_lib.baseboard_fab2(sch_1):page50_i50:vdd(9)" )
			)
			( pin "J6M1.209"
				( objectStatus "@baseboard_fab2_lib.baseboard_fab2(sch_1):page50_i50:vdd(10)" )
			)
			( pin "J6M1.206"
				( objectStatus "@baseboard_fab2_lib.baseboard_fab2(sch_1):page50_i50:vdd(11)" )
			)
			( pin "J6M1.204"
				( objectStatus "@baseboard_fab2_lib.baseboard_fab2(sch_1):page50_i50:vdd(12)" )
			)
			( pin "J6M1.92"
				( objectStatus "@baseboard_fab2_lib.baseboard_fab2(sch_1):page50_i50:vdd(13)" )
			)
			( pin "J6M1.90"
				( objectStatus "@baseboard_fab2_lib.baseboard_fab2(sch_1):page50_i50:vdd(14)" )
			)
			( pin "J6M1.88"
				( objectStatus "@baseboard_fab2_lib.baseboard_fab2(sch_1):page50_i50:vdd(15)" )
			)
			( pin "J6M1.85"
				( objectStatus "@baseboard_fab2_lib.baseboard_fab2(sch_1):page50_i50:vdd(16)" )
			)
			( pin "J6M1.83"
				( objectStatus "@baseboard_fab2_lib.baseboard_fab2(sch_1):page50_i50:vdd(17)" )
			)
			( pin "J6M1.80"
				( objectStatus "@baseboard_fab2_lib.baseboard_fab2(sch_1):page50_i50:vdd(18)" )
			)
			( pin "J6M1.76"
				( objectStatus "@baseboard_fab2_lib.baseboard_fab2(sch_1):page50_i50:vdd(19)" )
			)
			( pin "J6M1.73"
				( objectStatus "@baseboard_fab2_lib.baseboard_fab2(sch_1):page50_i50:vdd(20)" )
			)
			( pin "J6M1.70"
				( objectStatus "@baseboard_fab2_lib.baseboard_fab2(sch_1):page50_i50:vdd(21)" )
			)
			( pin "J6M1.67"
				( objectStatus "@baseboard_fab2_lib.baseboard_fab2(sch_1):page50_i50:vdd(22)" )
			)
			( pin "J6M1.64"
				( objectStatus "@baseboard_fab2_lib.baseboard_fab2(sch_1):page50_i50:vdd(23)" )
			)
			( pin "J6M1.61"
				( objectStatus "@baseboard_fab2_lib.baseboard_fab2(sch_1):page50_i50:vdd(24)" )
			)
			( pin "J6M1.59"
				( objectStatus "@baseboard_fab2_lib.baseboard_fab2(sch_1):page50_i50:vdd(25)" )
			)
			( pin "J6M1.287"
				( objectStatus "@baseboard_fab2_lib.baseboard_fab2(sch_1):page50_i50:vpp(0)" )
			)
			( pin "J6M1.286"
				( objectStatus "@baseboard_fab2_lib.baseboard_fab2(sch_1):page50_i50:vpp(1)" )
			)
			( pin "J6M1.288"
				( objectStatus "@baseboard_fab2_lib.baseboard_fab2(sch_1):page50_i50:vpp(2)" )
			)
			( pin "J6M1.143"
				( objectStatus "@baseboard_fab2_lib.baseboard_fab2(sch_1):page50_i50:vpp(3)" )
			)
			( pin "J6M1.142"
				( objectStatus "@baseboard_fab2_lib.baseboard_fab2(sch_1):page50_i50:vpp(4)" )
			)
			( pin "J6M1.221"
				( objectStatus "@baseboard_fab2_lib.baseboard_fab2(sch_1):page50_i50:vtt(0)" )
			)
			( pin "J6M1.77"
				( objectStatus "@baseboard_fab2_lib.baseboard_fab2(sch_1):page50_i50:vtt(1)" )
			)
			( pin "J6M1.79"
				( objectStatus "@baseboard_fab2_lib.baseboard_fab2(sch_1):page50_i158:a0" )
			)
			( pin "J6M1.72"
				( objectStatus "@baseboard_fab2_lib.baseboard_fab2(sch_1):page50_i158:a1" )
			)
			( pin "J6M1.216"
				( objectStatus "@baseboard_fab2_lib.baseboard_fab2(sch_1):page50_i158:a2" )
			)
			( pin "J6M1.71"
				( objectStatus "@baseboard_fab2_lib.baseboard_fab2(sch_1):page50_i158:a3" )
			)
			( pin "J6M1.214"
				( objectStatus "@baseboard_fab2_lib.baseboard_fab2(sch_1):page50_i158:a4" )
			)
			( pin "J6M1.213"
				( objectStatus "@baseboard_fab2_lib.baseboard_fab2(sch_1):page50_i158:a5" )
			)
			( pin "J6M1.69"
				( objectStatus "@baseboard_fab2_lib.baseboard_fab2(sch_1):page50_i158:a6" )
			)
			( pin "J6M1.211"
				( objectStatus "@baseboard_fab2_lib.baseboard_fab2(sch_1):page50_i158:a7" )
			)
			( pin "J6M1.68"
				( objectStatus "@baseboard_fab2_lib.baseboard_fab2(sch_1):page50_i158:a8" )
			)
			( pin "J6M1.66"
				( objectStatus "@baseboard_fab2_lib.baseboard_fab2(sch_1):page50_i158:a9" )
			)
			( pin "J6M1.225"
				( objectStatus "@baseboard_fab2_lib.baseboard_fab2(sch_1):page50_i158:a10" )
			)
			( pin "J6M1.210"
				( objectStatus "@baseboard_fab2_lib.baseboard_fab2(sch_1):page50_i158:a11" )
			)
			( pin "J6M1.65"
				( objectStatus "@baseboard_fab2_lib.baseboard_fab2(sch_1):page50_i158:a12" )
			)
			( pin "J6M1.232"
				( objectStatus "@baseboard_fab2_lib.baseboard_fab2(sch_1):page50_i158:a13" )
			)
			( pin "J6M1.228"
				( objectStatus "@baseboard_fab2_lib.baseboard_fab2(sch_1):page50_i158:a14_we_n" )
			)
			( pin "J6M1.86"
				( objectStatus "@baseboard_fab2_lib.baseboard_fab2(sch_1):page50_i158:a15_cas_n" )
			)
			( pin "J6M1.82"
				( objectStatus "@baseboard_fab2_lib.baseboard_fab2(sch_1):page50_i158:a16_ras_n" )
			)
			( pin "J6M1.234"
				( objectStatus "@baseboard_fab2_lib.baseboard_fab2(sch_1):page50_i158:a17" )
			)
			( pin "J6M1.62"
				( objectStatus "@baseboard_fab2_lib.baseboard_fab2(sch_1):page50_i158:act_n" )
			)
			( pin "J6M1.208"
				( objectStatus "@baseboard_fab2_lib.baseboard_fab2(sch_1):page50_i158:alert_n" )
			)
			( pin "J6M1.81"
				( objectStatus "@baseboard_fab2_lib.baseboard_fab2(sch_1):page50_i158:ba(0)" )
			)
			( pin "J6M1.224"
				( objectStatus "@baseboard_fab2_lib.baseboard_fab2(sch_1):page50_i158:ba(1)" )
			)
			( pin "J6M1.63"
				( objectStatus "@baseboard_fab2_lib.baseboard_fab2(sch_1):page50_i158:bg(0)" )
			)
			( pin "J6M1.207"
				( objectStatus "@baseboard_fab2_lib.baseboard_fab2(sch_1):page50_i158:bg(1)" )
			)
			( pin "J6M1.235"
				( objectStatus "@baseboard_fab2_lib.baseboard_fab2(sch_1):page50_i158:c(2)" )
			)
			( pin "J6M1.49"
				( objectStatus "@baseboard_fab2_lib.baseboard_fab2(sch_1):page50_i158:cb(0)" )
			)
			( pin "J6M1.194"
				( objectStatus "@baseboard_fab2_lib.baseboard_fab2(sch_1):page50_i158:cb(1)" )
			)
			( pin "J6M1.56"
				( objectStatus "@baseboard_fab2_lib.baseboard_fab2(sch_1):page50_i158:cb(2)" )
			)
			( pin "J6M1.201"
				( objectStatus "@baseboard_fab2_lib.baseboard_fab2(sch_1):page50_i158:cb(3)" )
			)
			( pin "J6M1.47"
				( objectStatus "@baseboard_fab2_lib.baseboard_fab2(sch_1):page50_i158:cb(4)" )
			)
			( pin "J6M1.192"
				( objectStatus "@baseboard_fab2_lib.baseboard_fab2(sch_1):page50_i158:cb(5)" )
			)
			( pin "J6M1.54"
				( objectStatus "@baseboard_fab2_lib.baseboard_fab2(sch_1):page50_i158:cb(6)" )
			)
			( pin "J6M1.199"
				( objectStatus "@baseboard_fab2_lib.baseboard_fab2(sch_1):page50_i158:cb(7)" )
			)
			( pin "J6M1.75"
				( objectStatus "@baseboard_fab2_lib.baseboard_fab2(sch_1):page50_i158:ck0n" )
			)
			( pin "J6M1.74"
				( objectStatus "@baseboard_fab2_lib.baseboard_fab2(sch_1):page50_i158:ck0p" )
			)
			( pin "J6M1.219"
				( objectStatus "@baseboard_fab2_lib.baseboard_fab2(sch_1):page50_i158:ck1n" )
			)
			( pin "J6M1.218"
				( objectStatus "@baseboard_fab2_lib.baseboard_fab2(sch_1):page50_i158:ck1p" )
			)
			( pin "J6M1.60"
				( objectStatus "@baseboard_fab2_lib.baseboard_fab2(sch_1):page50_i158:cke(0)" )
			)
			( pin "J6M1.203"
				( objectStatus "@baseboard_fab2_lib.baseboard_fab2(sch_1):page50_i158:cke(1)" )
			)
			( pin "J6M1.5"
				( objectStatus "@baseboard_fab2_lib.baseboard_fab2(sch_1):page50_i158:dq(0)" )
			)
			( pin "J6M1.150"
				( objectStatus "@baseboard_fab2_lib.baseboard_fab2(sch_1):page50_i158:dq(1)" )
			)
			( pin "J6M1.12"
				( objectStatus "@baseboard_fab2_lib.baseboard_fab2(sch_1):page50_i158:dq(2)" )
			)
			( pin "J6M1.157"
				( objectStatus "@baseboard_fab2_lib.baseboard_fab2(sch_1):page50_i158:dq(3)" )
			)
			( pin "J6M1.3"
				( objectStatus "@baseboard_fab2_lib.baseboard_fab2(sch_1):page50_i158:dq(4)" )
			)
			( pin "J6M1.148"
				( objectStatus "@baseboard_fab2_lib.baseboard_fab2(sch_1):page50_i158:dq(5)" )
			)
			( pin "J6M1.10"
				( objectStatus "@baseboard_fab2_lib.baseboard_fab2(sch_1):page50_i158:dq(6)" )
			)
			( pin "J6M1.155"
				( objectStatus "@baseboard_fab2_lib.baseboard_fab2(sch_1):page50_i158:dq(7)" )
			)
			( pin "J6M1.16"
				( objectStatus "@baseboard_fab2_lib.baseboard_fab2(sch_1):page50_i158:dq(8)" )
			)
			( pin "J6M1.161"
				( objectStatus "@baseboard_fab2_lib.baseboard_fab2(sch_1):page50_i158:dq(9)" )
			)
			( pin "J6M1.23"
				( objectStatus "@baseboard_fab2_lib.baseboard_fab2(sch_1):page50_i158:dq(10)" )
			)
			( pin "J6M1.168"
				( objectStatus "@baseboard_fab2_lib.baseboard_fab2(sch_1):page50_i158:dq(11)" )
			)
			( pin "J6M1.14"
				( objectStatus "@baseboard_fab2_lib.baseboard_fab2(sch_1):page50_i158:dq(12)" )
			)
			( pin "J6M1.159"
				( objectStatus "@baseboard_fab2_lib.baseboard_fab2(sch_1):page50_i158:dq(13)" )
			)
			( pin "J6M1.21"
				( objectStatus "@baseboard_fab2_lib.baseboard_fab2(sch_1):page50_i158:dq(14)" )
			)
			( pin "J6M1.166"
				( objectStatus "@baseboard_fab2_lib.baseboard_fab2(sch_1):page50_i158:dq(15)" )
			)
			( pin "J6M1.27"
				( objectStatus "@baseboard_fab2_lib.baseboard_fab2(sch_1):page50_i158:dq(16)" )
			)
			( pin "J6M1.172"
				( objectStatus "@baseboard_fab2_lib.baseboard_fab2(sch_1):page50_i158:dq(17)" )
			)
			( pin "J6M1.34"
				( objectStatus "@baseboard_fab2_lib.baseboard_fab2(sch_1):page50_i158:dq(18)" )
			)
			( pin "J6M1.179"
				( objectStatus "@baseboard_fab2_lib.baseboard_fab2(sch_1):page50_i158:dq(19)" )
			)
			( pin "J6M1.25"
				( objectStatus "@baseboard_fab2_lib.baseboard_fab2(sch_1):page50_i158:dq(20)" )
			)
			( pin "J6M1.170"
				( objectStatus "@baseboard_fab2_lib.baseboard_fab2(sch_1):page50_i158:dq(21)" )
			)
			( pin "J6M1.32"
				( objectStatus "@baseboard_fab2_lib.baseboard_fab2(sch_1):page50_i158:dq(22)" )
			)
			( pin "J6M1.177"
				( objectStatus "@baseboard_fab2_lib.baseboard_fab2(sch_1):page50_i158:dq(23)" )
			)
			( pin "J6M1.38"
				( objectStatus "@baseboard_fab2_lib.baseboard_fab2(sch_1):page50_i158:dq(24)" )
			)
			( pin "J6M1.183"
				( objectStatus "@baseboard_fab2_lib.baseboard_fab2(sch_1):page50_i158:dq(25)" )
			)
			( pin "J6M1.45"
				( objectStatus "@baseboard_fab2_lib.baseboard_fab2(sch_1):page50_i158:dq(26)" )
			)
			( pin "J6M1.190"
				( objectStatus "@baseboard_fab2_lib.baseboard_fab2(sch_1):page50_i158:dq(27)" )
			)
			( pin "J6M1.36"
				( objectStatus "@baseboard_fab2_lib.baseboard_fab2(sch_1):page50_i158:dq(28)" )
			)
			( pin "J6M1.181"
				( objectStatus "@baseboard_fab2_lib.baseboard_fab2(sch_1):page50_i158:dq(29)" )
			)
			( pin "J6M1.43"
				( objectStatus "@baseboard_fab2_lib.baseboard_fab2(sch_1):page50_i158:dq(30)" )
			)
			( pin "J6M1.188"
				( objectStatus "@baseboard_fab2_lib.baseboard_fab2(sch_1):page50_i158:dq(31)" )
			)
			( pin "J6M1.97"
				( objectStatus "@baseboard_fab2_lib.baseboard_fab2(sch_1):page50_i158:dq(32)" )
			)
			( pin "J6M1.242"
				( objectStatus "@baseboard_fab2_lib.baseboard_fab2(sch_1):page50_i158:dq(33)" )
			)
			( pin "J6M1.104"
				( objectStatus "@baseboard_fab2_lib.baseboard_fab2(sch_1):page50_i158:dq(34)" )
			)
			( pin "J6M1.249"
				( objectStatus "@baseboard_fab2_lib.baseboard_fab2(sch_1):page50_i158:dq(35)" )
			)
			( pin "J6M1.95"
				( objectStatus "@baseboard_fab2_lib.baseboard_fab2(sch_1):page50_i158:dq(36)" )
			)
			( pin "J6M1.240"
				( objectStatus "@baseboard_fab2_lib.baseboard_fab2(sch_1):page50_i158:dq(37)" )
			)
			( pin "J6M1.102"
				( objectStatus "@baseboard_fab2_lib.baseboard_fab2(sch_1):page50_i158:dq(38)" )
			)
			( pin "J6M1.247"
				( objectStatus "@baseboard_fab2_lib.baseboard_fab2(sch_1):page50_i158:dq(39)" )
			)
			( pin "J6M1.108"
				( objectStatus "@baseboard_fab2_lib.baseboard_fab2(sch_1):page50_i158:dq(40)" )
			)
			( pin "J6M1.253"
				( objectStatus "@baseboard_fab2_lib.baseboard_fab2(sch_1):page50_i158:dq(41)" )
			)
			( pin "J6M1.115"
				( objectStatus "@baseboard_fab2_lib.baseboard_fab2(sch_1):page50_i158:dq(42)" )
			)
			( pin "J6M1.260"
				( objectStatus "@baseboard_fab2_lib.baseboard_fab2(sch_1):page50_i158:dq(43)" )
			)
			( pin "J6M1.106"
				( objectStatus "@baseboard_fab2_lib.baseboard_fab2(sch_1):page50_i158:dq(44)" )
			)
			( pin "J6M1.251"
				( objectStatus "@baseboard_fab2_lib.baseboard_fab2(sch_1):page50_i158:dq(45)" )
			)
			( pin "J6M1.113"
				( objectStatus "@baseboard_fab2_lib.baseboard_fab2(sch_1):page50_i158:dq(46)" )
			)
			( pin "J6M1.258"
				( objectStatus "@baseboard_fab2_lib.baseboard_fab2(sch_1):page50_i158:dq(47)" )
			)
			( pin "J6M1.119"
				( objectStatus "@baseboard_fab2_lib.baseboard_fab2(sch_1):page50_i158:dq(48)" )
			)
			( pin "J6M1.264"
				( objectStatus "@baseboard_fab2_lib.baseboard_fab2(sch_1):page50_i158:dq(49)" )
			)
			( pin "J6M1.126"
				( objectStatus "@baseboard_fab2_lib.baseboard_fab2(sch_1):page50_i158:dq(50)" )
			)
			( pin "J6M1.271"
				( objectStatus "@baseboard_fab2_lib.baseboard_fab2(sch_1):page50_i158:dq(51)" )
			)
			( pin "J6M1.117"
				( objectStatus "@baseboard_fab2_lib.baseboard_fab2(sch_1):page50_i158:dq(52)" )
			)
			( pin "J6M1.262"
				( objectStatus "@baseboard_fab2_lib.baseboard_fab2(sch_1):page50_i158:dq(53)" )
			)
			( pin "J6M1.124"
				( objectStatus "@baseboard_fab2_lib.baseboard_fab2(sch_1):page50_i158:dq(54)" )
			)
			( pin "J6M1.269"
				( objectStatus "@baseboard_fab2_lib.baseboard_fab2(sch_1):page50_i158:dq(55)" )
			)
			( pin "J6M1.130"
				( objectStatus "@baseboard_fab2_lib.baseboard_fab2(sch_1):page50_i158:dq(56)" )
			)
			( pin "J6M1.275"
				( objectStatus "@baseboard_fab2_lib.baseboard_fab2(sch_1):page50_i158:dq(57)" )
			)
			( pin "J6M1.137"
				( objectStatus "@baseboard_fab2_lib.baseboard_fab2(sch_1):page50_i158:dq(58)" )
			)
			( pin "J6M1.282"
				( objectStatus "@baseboard_fab2_lib.baseboard_fab2(sch_1):page50_i158:dq(59)" )
			)
			( pin "J6M1.128"
				( objectStatus "@baseboard_fab2_lib.baseboard_fab2(sch_1):page50_i158:dq(60)" )
			)
			( pin "J6M1.273"
				( objectStatus "@baseboard_fab2_lib.baseboard_fab2(sch_1):page50_i158:dq(61)" )
			)
			( pin "J6M1.135"
				( objectStatus "@baseboard_fab2_lib.baseboard_fab2(sch_1):page50_i158:dq(62)" )
			)
			( pin "J6M1.280"
				( objectStatus "@baseboard_fab2_lib.baseboard_fab2(sch_1):page50_i158:dq(63)" )
			)
			( pin "J6M1.78"
				( objectStatus "@baseboard_fab2_lib.baseboard_fab2(sch_1):page50_i158:event_n" )
			)
			( pin "J6M1.87"
				( objectStatus "@baseboard_fab2_lib.baseboard_fab2(sch_1):page50_i158:odt(0)" )
			)
			( pin "J6M1.91"
				( objectStatus "@baseboard_fab2_lib.baseboard_fab2(sch_1):page50_i158:odt(1)" )
			)
			( pin "J6M1.222"
				( objectStatus "@baseboard_fab2_lib.baseboard_fab2(sch_1):page50_i158:par" )
			)
			( pin "J6M1.58"
				( objectStatus "@baseboard_fab2_lib.baseboard_fab2(sch_1):page50_i158:reset_n" )
			)
			( pin "J6M1.205"
				( objectStatus "@baseboard_fab2_lib.baseboard_fab2(sch_1):page50_i158:rfu(0)" )
			)
			( pin "J6M1.227"
				( objectStatus "@baseboard_fab2_lib.baseboard_fab2(sch_1):page50_i158:rfu(1)" )
			)
			( pin "J6M1.144"
				( objectStatus "@baseboard_fab2_lib.baseboard_fab2(sch_1):page50_i158:rfu(2)" )
			)
			( pin "J6M1.84"
				( objectStatus "@baseboard_fab2_lib.baseboard_fab2(sch_1):page50_i158:s0_n" )
			)
			( pin "J6M1.89"
				( objectStatus "@baseboard_fab2_lib.baseboard_fab2(sch_1):page50_i158:s1_n" )
			)
			( pin "J6M1.93"
				( objectStatus "@baseboard_fab2_lib.baseboard_fab2(sch_1):page50_i158:s2_n_c(0)" )
			)
			( pin "J6M1.237"
				( objectStatus "@baseboard_fab2_lib.baseboard_fab2(sch_1):page50_i158:s3_n_c(1)" )
			)
			( pin "J6M1.139"
				( objectStatus "@baseboard_fab2_lib.baseboard_fab2(sch_1):page50_i158:sa(0)" )
			)
			( pin "J6M1.140"
				( objectStatus "@baseboard_fab2_lib.baseboard_fab2(sch_1):page50_i158:sa(1)" )
			)
			( pin "J6M1.238"
				( objectStatus "@baseboard_fab2_lib.baseboard_fab2(sch_1):page50_i158:sa(2)" )
			)
			( pin "J6M1.230"
				( objectStatus "@baseboard_fab2_lib.baseboard_fab2(sch_1):page50_i158:save_n_nc" )
			)
			( pin "J6M1.141"
				( objectStatus "@baseboard_fab2_lib.baseboard_fab2(sch_1):page50_i158:scl" )
			)
			( pin "J6M1.285"
				( objectStatus "@baseboard_fab2_lib.baseboard_fab2(sch_1):page50_i158:sda" )
			)
			( pin "J6M1.284"
				( objectStatus "@baseboard_fab2_lib.baseboard_fab2(sch_1):page50_i158:vddspd" )
			)
			( pin "J6M1.146"
				( objectStatus "@baseboard_fab2_lib.baseboard_fab2(sch_1):page50_i158:vrefca" )
			)
			( pin "C6M1.1"
				( objectStatus "@baseboard_fab2_lib.baseboard_fab2(sch_1):page50_i177:a" )
			)
			( pin "C6M1.2"
				( objectStatus "@baseboard_fab2_lib.baseboard_fab2(sch_1):page50_i177:b" )
			)
			( pin "J4A2.283"
				( objectStatus "@baseboard_fab2_lib.baseboard_fab2(sch_1):page51_i43:vss(0)" )
			)
			( pin "J4A2.281"
				( objectStatus "@baseboard_fab2_lib.baseboard_fab2(sch_1):page51_i43:vss(1)" )
			)
			( pin "J4A2.279"
				( objectStatus "@baseboard_fab2_lib.baseboard_fab2(sch_1):page51_i43:vss(2)" )
			)
			( pin "J4A2.276"
				( objectStatus "@baseboard_fab2_lib.baseboard_fab2(sch_1):page51_i43:vss(3)" )
			)
			( pin "J4A2.274"
				( objectStatus "@baseboard_fab2_lib.baseboard_fab2(sch_1):page51_i43:vss(4)" )
			)
			( pin "J4A2.272"
				( objectStatus "@baseboard_fab2_lib.baseboard_fab2(sch_1):page51_i43:vss(5)" )
			)
			( pin "J4A2.270"
				( objectStatus "@baseboard_fab2_lib.baseboard_fab2(sch_1):page51_i43:vss(6)" )
			)
			( pin "J4A2.268"
				( objectStatus "@baseboard_fab2_lib.baseboard_fab2(sch_1):page51_i43:vss(7)" )
			)
			( pin "J4A2.265"
				( objectStatus "@baseboard_fab2_lib.baseboard_fab2(sch_1):page51_i43:vss(8)" )
			)
			( pin "J4A2.263"
				( objectStatus "@baseboard_fab2_lib.baseboard_fab2(sch_1):page51_i43:vss(9)" )
			)
			( pin "J4A2.261"
				( objectStatus "@baseboard_fab2_lib.baseboard_fab2(sch_1):page51_i43:vss(10)" )
			)
			( pin "J4A2.259"
				( objectStatus "@baseboard_fab2_lib.baseboard_fab2(sch_1):page51_i43:vss(11)" )
			)
			( pin "J4A2.257"
				( objectStatus "@baseboard_fab2_lib.baseboard_fab2(sch_1):page51_i43:vss(12)" )
			)
			( pin "J4A2.254"
				( objectStatus "@baseboard_fab2_lib.baseboard_fab2(sch_1):page51_i43:vss(13)" )
			)
			( pin "J4A2.252"
				( objectStatus "@baseboard_fab2_lib.baseboard_fab2(sch_1):page51_i43:vss(14)" )
			)
			( pin "J4A2.250"
				( objectStatus "@baseboard_fab2_lib.baseboard_fab2(sch_1):page51_i43:vss(15)" )
			)
			( pin "J4A2.248"
				( objectStatus "@baseboard_fab2_lib.baseboard_fab2(sch_1):page51_i43:vss(16)" )
			)
			( pin "J4A2.246"
				( objectStatus "@baseboard_fab2_lib.baseboard_fab2(sch_1):page51_i43:vss(17)" )
			)
			( pin "J4A2.243"
				( objectStatus "@baseboard_fab2_lib.baseboard_fab2(sch_1):page51_i43:vss(18)" )
			)
			( pin "J4A2.241"
				( objectStatus "@baseboard_fab2_lib.baseboard_fab2(sch_1):page51_i43:vss(19)" )
			)
			( pin "J4A2.239"
				( objectStatus "@baseboard_fab2_lib.baseboard_fab2(sch_1):page51_i43:vss(20)" )
			)
			( pin "J4A2.202"
				( objectStatus "@baseboard_fab2_lib.baseboard_fab2(sch_1):page51_i43:vss(21)" )
			)
			( pin "J4A2.200"
				( objectStatus "@baseboard_fab2_lib.baseboard_fab2(sch_1):page51_i43:vss(22)" )
			)
			( pin "J4A2.198"
				( objectStatus "@baseboard_fab2_lib.baseboard_fab2(sch_1):page51_i43:vss(23)" )
			)
			( pin "J4A2.195"
				( objectStatus "@baseboard_fab2_lib.baseboard_fab2(sch_1):page51_i43:vss(24)" )
			)
			( pin "J4A2.193"
				( objectStatus "@baseboard_fab2_lib.baseboard_fab2(sch_1):page51_i43:vss(25)" )
			)
			( pin "J4A2.191"
				( objectStatus "@baseboard_fab2_lib.baseboard_fab2(sch_1):page51_i43:vss(26)" )
			)
			( pin "J4A2.189"
				( objectStatus "@baseboard_fab2_lib.baseboard_fab2(sch_1):page51_i43:vss(27)" )
			)
			( pin "J4A2.187"
				( objectStatus "@baseboard_fab2_lib.baseboard_fab2(sch_1):page51_i43:vss(28)" )
			)
			( pin "J4A2.184"
				( objectStatus "@baseboard_fab2_lib.baseboard_fab2(sch_1):page51_i43:vss(29)" )
			)
			( pin "J4A2.182"
				( objectStatus "@baseboard_fab2_lib.baseboard_fab2(sch_1):page51_i43:vss(30)" )
			)
			( pin "J4A2.180"
				( objectStatus "@baseboard_fab2_lib.baseboard_fab2(sch_1):page51_i43:vss(31)" )
			)
			( pin "J4A2.178"
				( objectStatus "@baseboard_fab2_lib.baseboard_fab2(sch_1):page51_i43:vss(32)" )
			)
			( pin "J4A2.176"
				( objectStatus "@baseboard_fab2_lib.baseboard_fab2(sch_1):page51_i43:vss(33)" )
			)
			( pin "J4A2.173"
				( objectStatus "@baseboard_fab2_lib.baseboard_fab2(sch_1):page51_i43:vss(34)" )
			)
			( pin "J4A2.171"
				( objectStatus "@baseboard_fab2_lib.baseboard_fab2(sch_1):page51_i43:vss(35)" )
			)
			( pin "J4A2.169"
				( objectStatus "@baseboard_fab2_lib.baseboard_fab2(sch_1):page51_i43:vss(36)" )
			)
			( pin "J4A2.167"
				( objectStatus "@baseboard_fab2_lib.baseboard_fab2(sch_1):page51_i43:vss(37)" )
			)
			( pin "J4A2.165"
				( objectStatus "@baseboard_fab2_lib.baseboard_fab2(sch_1):page51_i43:vss(38)" )
			)
			( pin "J4A2.162"
				( objectStatus "@baseboard_fab2_lib.baseboard_fab2(sch_1):page51_i43:vss(39)" )
			)
			( pin "J4A2.160"
				( objectStatus "@baseboard_fab2_lib.baseboard_fab2(sch_1):page51_i43:vss(40)" )
			)
			( pin "J4A2.158"
				( objectStatus "@baseboard_fab2_lib.baseboard_fab2(sch_1):page51_i43:vss(41)" )
			)
			( pin "J4A2.156"
				( objectStatus "@baseboard_fab2_lib.baseboard_fab2(sch_1):page51_i43:vss(42)" )
			)
			( pin "J4A2.154"
				( objectStatus "@baseboard_fab2_lib.baseboard_fab2(sch_1):page51_i43:vss(43)" )
			)
			( pin "J4A2.151"
				( objectStatus "@baseboard_fab2_lib.baseboard_fab2(sch_1):page51_i43:vss(44)" )
			)
			( pin "J4A2.149"
				( objectStatus "@baseboard_fab2_lib.baseboard_fab2(sch_1):page51_i43:vss(45)" )
			)
			( pin "J4A2.147"
				( objectStatus "@baseboard_fab2_lib.baseboard_fab2(sch_1):page51_i43:vss(46)" )
			)
			( pin "J4A2.138"
				( objectStatus "@baseboard_fab2_lib.baseboard_fab2(sch_1):page51_i43:vss(47)" )
			)
			( pin "J4A2.136"
				( objectStatus "@baseboard_fab2_lib.baseboard_fab2(sch_1):page51_i43:vss(48)" )
			)
			( pin "J4A2.134"
				( objectStatus "@baseboard_fab2_lib.baseboard_fab2(sch_1):page51_i43:vss(49)" )
			)
			( pin "J4A2.131"
				( objectStatus "@baseboard_fab2_lib.baseboard_fab2(sch_1):page51_i43:vss(50)" )
			)
			( pin "J4A2.129"
				( objectStatus "@baseboard_fab2_lib.baseboard_fab2(sch_1):page51_i43:vss(51)" )
			)
			( pin "J4A2.127"
				( objectStatus "@baseboard_fab2_lib.baseboard_fab2(sch_1):page51_i43:vss(52)" )
			)
			( pin "J4A2.125"
				( objectStatus "@baseboard_fab2_lib.baseboard_fab2(sch_1):page51_i43:vss(53)" )
			)
			( pin "J4A2.123"
				( objectStatus "@baseboard_fab2_lib.baseboard_fab2(sch_1):page51_i43:vss(54)" )
			)
			( pin "J4A2.120"
				( objectStatus "@baseboard_fab2_lib.baseboard_fab2(sch_1):page51_i43:vss(55)" )
			)
			( pin "J4A2.118"
				( objectStatus "@baseboard_fab2_lib.baseboard_fab2(sch_1):page51_i43:vss(56)" )
			)
			( pin "J4A2.116"
				( objectStatus "@baseboard_fab2_lib.baseboard_fab2(sch_1):page51_i43:vss(57)" )
			)
			( pin "J4A2.114"
				( objectStatus "@baseboard_fab2_lib.baseboard_fab2(sch_1):page51_i43:vss(58)" )
			)
			( pin "J4A2.112"
				( objectStatus "@baseboard_fab2_lib.baseboard_fab2(sch_1):page51_i43:vss(59)" )
			)
			( pin "J4A2.109"
				( objectStatus "@baseboard_fab2_lib.baseboard_fab2(sch_1):page51_i43:vss(60)" )
			)
			( pin "J4A2.107"
				( objectStatus "@baseboard_fab2_lib.baseboard_fab2(sch_1):page51_i43:vss(61)" )
			)
			( pin "J4A2.105"
				( objectStatus "@baseboard_fab2_lib.baseboard_fab2(sch_1):page51_i43:vss(62)" )
			)
			( pin "J4A2.103"
				( objectStatus "@baseboard_fab2_lib.baseboard_fab2(sch_1):page51_i43:vss(63)" )
			)
			( pin "J4A2.101"
				( objectStatus "@baseboard_fab2_lib.baseboard_fab2(sch_1):page51_i43:vss(64)" )
			)
			( pin "J4A2.98"
				( objectStatus "@baseboard_fab2_lib.baseboard_fab2(sch_1):page51_i43:vss(65)" )
			)
			( pin "J4A2.96"
				( objectStatus "@baseboard_fab2_lib.baseboard_fab2(sch_1):page51_i43:vss(66)" )
			)
			( pin "J4A2.94"
				( objectStatus "@baseboard_fab2_lib.baseboard_fab2(sch_1):page51_i43:vss(67)" )
			)
			( pin "J4A2.57"
				( objectStatus "@baseboard_fab2_lib.baseboard_fab2(sch_1):page51_i43:vss(68)" )
			)
			( pin "J4A2.55"
				( objectStatus "@baseboard_fab2_lib.baseboard_fab2(sch_1):page51_i43:vss(69)" )
			)
			( pin "J4A2.53"
				( objectStatus "@baseboard_fab2_lib.baseboard_fab2(sch_1):page51_i43:vss(70)" )
			)
			( pin "J4A2.50"
				( objectStatus "@baseboard_fab2_lib.baseboard_fab2(sch_1):page51_i43:vss(71)" )
			)
			( pin "J4A2.48"
				( objectStatus "@baseboard_fab2_lib.baseboard_fab2(sch_1):page51_i43:vss(72)" )
			)
			( pin "J4A2.46"
				( objectStatus "@baseboard_fab2_lib.baseboard_fab2(sch_1):page51_i43:vss(73)" )
			)
			( pin "J4A2.44"
				( objectStatus "@baseboard_fab2_lib.baseboard_fab2(sch_1):page51_i43:vss(74)" )
			)
			( pin "J4A2.42"
				( objectStatus "@baseboard_fab2_lib.baseboard_fab2(sch_1):page51_i43:vss(75)" )
			)
			( pin "J4A2.39"
				( objectStatus "@baseboard_fab2_lib.baseboard_fab2(sch_1):page51_i43:vss(76)" )
			)
			( pin "J4A2.37"
				( objectStatus "@baseboard_fab2_lib.baseboard_fab2(sch_1):page51_i43:vss(77)" )
			)
			( pin "J4A2.35"
				( objectStatus "@baseboard_fab2_lib.baseboard_fab2(sch_1):page51_i43:vss(78)" )
			)
			( pin "J4A2.33"
				( objectStatus "@baseboard_fab2_lib.baseboard_fab2(sch_1):page51_i43:vss(79)" )
			)
			( pin "J4A2.31"
				( objectStatus "@baseboard_fab2_lib.baseboard_fab2(sch_1):page51_i43:vss(80)" )
			)
			( pin "J4A2.28"
				( objectStatus "@baseboard_fab2_lib.baseboard_fab2(sch_1):page51_i43:vss(81)" )
			)
			( pin "J4A2.26"
				( objectStatus "@baseboard_fab2_lib.baseboard_fab2(sch_1):page51_i43:vss(82)" )
			)
			( pin "J4A2.24"
				( objectStatus "@baseboard_fab2_lib.baseboard_fab2(sch_1):page51_i43:vss(83)" )
			)
			( pin "J4A2.22"
				( objectStatus "@baseboard_fab2_lib.baseboard_fab2(sch_1):page51_i43:vss(84)" )
			)
			( pin "J4A2.20"
				( objectStatus "@baseboard_fab2_lib.baseboard_fab2(sch_1):page51_i43:vss(85)" )
			)
			( pin "J4A2.17"
				( objectStatus "@baseboard_fab2_lib.baseboard_fab2(sch_1):page51_i43:vss(86)" )
			)
			( pin "J4A2.15"
				( objectStatus "@baseboard_fab2_lib.baseboard_fab2(sch_1):page51_i43:vss(87)" )
			)
			( pin "J4A2.13"
				( objectStatus "@baseboard_fab2_lib.baseboard_fab2(sch_1):page51_i43:vss(88)" )
			)
			( pin "J4A2.11"
				( objectStatus "@baseboard_fab2_lib.baseboard_fab2(sch_1):page51_i43:vss(89)" )
			)
			( pin "J4A2.9"
				( objectStatus "@baseboard_fab2_lib.baseboard_fab2(sch_1):page51_i43:vss(90)" )
			)
			( pin "J4A2.6"
				( objectStatus "@baseboard_fab2_lib.baseboard_fab2(sch_1):page51_i43:vss(91)" )
			)
			( pin "J4A2.4"
				( objectStatus "@baseboard_fab2_lib.baseboard_fab2(sch_1):page51_i43:vss(92)" )
			)
			( pin "J4A2.2"
				( objectStatus "@baseboard_fab2_lib.baseboard_fab2(sch_1):page51_i43:vss(93)" )
			)
			( pin "J4A2.152"
				( objectStatus "@baseboard_fab2_lib.baseboard_fab2(sch_1):page51_i66:dqs0n" )
			)
			( pin "J4A2.153"
				( objectStatus "@baseboard_fab2_lib.baseboard_fab2(sch_1):page51_i66:dqs0p" )
			)
			( pin "J4A2.163"
				( objectStatus "@baseboard_fab2_lib.baseboard_fab2(sch_1):page51_i66:dqs1n" )
			)
			( pin "J4A2.164"
				( objectStatus "@baseboard_fab2_lib.baseboard_fab2(sch_1):page51_i66:dqs1p" )
			)
			( pin "J4A2.174"
				( objectStatus "@baseboard_fab2_lib.baseboard_fab2(sch_1):page51_i66:dqs2n" )
			)
			( pin "J4A2.175"
				( objectStatus "@baseboard_fab2_lib.baseboard_fab2(sch_1):page51_i66:dqs2p" )
			)
			( pin "J4A2.185"
				( objectStatus "@baseboard_fab2_lib.baseboard_fab2(sch_1):page51_i66:dqs3n" )
			)
			( pin "J4A2.186"
				( objectStatus "@baseboard_fab2_lib.baseboard_fab2(sch_1):page51_i66:dqs3p" )
			)
			( pin "J4A2.244"
				( objectStatus "@baseboard_fab2_lib.baseboard_fab2(sch_1):page51_i66:dqs4n" )
			)
			( pin "J4A2.245"
				( objectStatus "@baseboard_fab2_lib.baseboard_fab2(sch_1):page51_i66:dqs4p" )
			)
			( pin "J4A2.255"
				( objectStatus "@baseboard_fab2_lib.baseboard_fab2(sch_1):page51_i66:dqs5n" )
			)
			( pin "J4A2.256"
				( objectStatus "@baseboard_fab2_lib.baseboard_fab2(sch_1):page51_i66:dqs5p" )
			)
			( pin "J4A2.266"
				( objectStatus "@baseboard_fab2_lib.baseboard_fab2(sch_1):page51_i66:dqs6n" )
			)
			( pin "J4A2.267"
				( objectStatus "@baseboard_fab2_lib.baseboard_fab2(sch_1):page51_i66:dqs6p" )
			)
			( pin "J4A2.277"
				( objectStatus "@baseboard_fab2_lib.baseboard_fab2(sch_1):page51_i66:dqs7n" )
			)
			( pin "J4A2.278"
				( objectStatus "@baseboard_fab2_lib.baseboard_fab2(sch_1):page51_i66:dqs7p" )
			)
			( pin "J4A2.196"
				( objectStatus "@baseboard_fab2_lib.baseboard_fab2(sch_1):page51_i66:dqs8n" )
			)
			( pin "J4A2.197"
				( objectStatus "@baseboard_fab2_lib.baseboard_fab2(sch_1):page51_i66:dqs8p" )
			)
			( pin "J4A2.8"
				( objectStatus "@baseboard_fab2_lib.baseboard_fab2(sch_1):page51_i66:dqs9n" )
			)
			( pin "J4A2.7"
				( objectStatus "@baseboard_fab2_lib.baseboard_fab2(sch_1):page51_i66:dqs9p" )
			)
			( pin "J4A2.19"
				( objectStatus "@baseboard_fab2_lib.baseboard_fab2(sch_1):page51_i66:dqs10n" )
			)
			( pin "J4A2.18"
				( objectStatus "@baseboard_fab2_lib.baseboard_fab2(sch_1):page51_i66:dqs10p" )
			)
			( pin "J4A2.30"
				( objectStatus "@baseboard_fab2_lib.baseboard_fab2(sch_1):page51_i66:dqs11n" )
			)
			( pin "J4A2.29"
				( objectStatus "@baseboard_fab2_lib.baseboard_fab2(sch_1):page51_i66:dqs11p" )
			)
			( pin "J4A2.41"
				( objectStatus "@baseboard_fab2_lib.baseboard_fab2(sch_1):page51_i66:dqs12n" )
			)
			( pin "J4A2.40"
				( objectStatus "@baseboard_fab2_lib.baseboard_fab2(sch_1):page51_i66:dqs12p" )
			)
			( pin "J4A2.100"
				( objectStatus "@baseboard_fab2_lib.baseboard_fab2(sch_1):page51_i66:dqs13n" )
			)
			( pin "J4A2.99"
				( objectStatus "@baseboard_fab2_lib.baseboard_fab2(sch_1):page51_i66:dqs13p" )
			)
			( pin "J4A2.111"
				( objectStatus "@baseboard_fab2_lib.baseboard_fab2(sch_1):page51_i66:dqs14n" )
			)
			( pin "J4A2.110"
				( objectStatus "@baseboard_fab2_lib.baseboard_fab2(sch_1):page51_i66:dqs14p" )
			)
			( pin "J4A2.122"
				( objectStatus "@baseboard_fab2_lib.baseboard_fab2(sch_1):page51_i66:dqs15n" )
			)
			( pin "J4A2.121"
				( objectStatus "@baseboard_fab2_lib.baseboard_fab2(sch_1):page51_i66:dqs15p" )
			)
			( pin "J4A2.133"
				( objectStatus "@baseboard_fab2_lib.baseboard_fab2(sch_1):page51_i66:dqs16n" )
			)
			( pin "J4A2.132"
				( objectStatus "@baseboard_fab2_lib.baseboard_fab2(sch_1):page51_i66:dqs16p" )
			)
			( pin "J4A2.52"
				( objectStatus "@baseboard_fab2_lib.baseboard_fab2(sch_1):page51_i66:dqs17n" )
			)
			( pin "J4A2.51"
				( objectStatus "@baseboard_fab2_lib.baseboard_fab2(sch_1):page51_i66:dqs17p" )
			)
			( pin "J4A2.79"
				( objectStatus "@baseboard_fab2_lib.baseboard_fab2(sch_1):page51_i111:a0" )
			)
			( pin "J4A2.72"
				( objectStatus "@baseboard_fab2_lib.baseboard_fab2(sch_1):page51_i111:a1" )
			)
			( pin "J4A2.216"
				( objectStatus "@baseboard_fab2_lib.baseboard_fab2(sch_1):page51_i111:a2" )
			)
			( pin "J4A2.71"
				( objectStatus "@baseboard_fab2_lib.baseboard_fab2(sch_1):page51_i111:a3" )
			)
			( pin "J4A2.214"
				( objectStatus "@baseboard_fab2_lib.baseboard_fab2(sch_1):page51_i111:a4" )
			)
			( pin "J4A2.213"
				( objectStatus "@baseboard_fab2_lib.baseboard_fab2(sch_1):page51_i111:a5" )
			)
			( pin "J4A2.69"
				( objectStatus "@baseboard_fab2_lib.baseboard_fab2(sch_1):page51_i111:a6" )
			)
			( pin "J4A2.211"
				( objectStatus "@baseboard_fab2_lib.baseboard_fab2(sch_1):page51_i111:a7" )
			)
			( pin "J4A2.68"
				( objectStatus "@baseboard_fab2_lib.baseboard_fab2(sch_1):page51_i111:a8" )
			)
			( pin "J4A2.66"
				( objectStatus "@baseboard_fab2_lib.baseboard_fab2(sch_1):page51_i111:a9" )
			)
			( pin "J4A2.225"
				( objectStatus "@baseboard_fab2_lib.baseboard_fab2(sch_1):page51_i111:a10" )
			)
			( pin "J4A2.210"
				( objectStatus "@baseboard_fab2_lib.baseboard_fab2(sch_1):page51_i111:a11" )
			)
			( pin "J4A2.65"
				( objectStatus "@baseboard_fab2_lib.baseboard_fab2(sch_1):page51_i111:a12" )
			)
			( pin "J4A2.232"
				( objectStatus "@baseboard_fab2_lib.baseboard_fab2(sch_1):page51_i111:a13" )
			)
			( pin "J4A2.228"
				( objectStatus "@baseboard_fab2_lib.baseboard_fab2(sch_1):page51_i111:a14_we_n" )
			)
			( pin "J4A2.86"
				( objectStatus "@baseboard_fab2_lib.baseboard_fab2(sch_1):page51_i111:a15_cas_n" )
			)
			( pin "J4A2.82"
				( objectStatus "@baseboard_fab2_lib.baseboard_fab2(sch_1):page51_i111:a16_ras_n" )
			)
			( pin "J4A2.234"
				( objectStatus "@baseboard_fab2_lib.baseboard_fab2(sch_1):page51_i111:a17" )
			)
			( pin "J4A2.62"
				( objectStatus "@baseboard_fab2_lib.baseboard_fab2(sch_1):page51_i111:act_n" )
			)
			( pin "J4A2.208"
				( objectStatus "@baseboard_fab2_lib.baseboard_fab2(sch_1):page51_i111:alert_n" )
			)
			( pin "J4A2.81"
				( objectStatus "@baseboard_fab2_lib.baseboard_fab2(sch_1):page51_i111:ba(0)" )
			)
			( pin "J4A2.224"
				( objectStatus "@baseboard_fab2_lib.baseboard_fab2(sch_1):page51_i111:ba(1)" )
			)
			( pin "J4A2.63"
				( objectStatus "@baseboard_fab2_lib.baseboard_fab2(sch_1):page51_i111:bg(0)" )
			)
			( pin "J4A2.207"
				( objectStatus "@baseboard_fab2_lib.baseboard_fab2(sch_1):page51_i111:bg(1)" )
			)
			( pin "J4A2.235"
				( objectStatus "@baseboard_fab2_lib.baseboard_fab2(sch_1):page51_i111:c(2)" )
			)
			( pin "J4A2.49"
				( objectStatus "@baseboard_fab2_lib.baseboard_fab2(sch_1):page51_i111:cb(0)" )
			)
			( pin "J4A2.194"
				( objectStatus "@baseboard_fab2_lib.baseboard_fab2(sch_1):page51_i111:cb(1)" )
			)
			( pin "J4A2.56"
				( objectStatus "@baseboard_fab2_lib.baseboard_fab2(sch_1):page51_i111:cb(2)" )
			)
			( pin "J4A2.201"
				( objectStatus "@baseboard_fab2_lib.baseboard_fab2(sch_1):page51_i111:cb(3)" )
			)
			( pin "J4A2.47"
				( objectStatus "@baseboard_fab2_lib.baseboard_fab2(sch_1):page51_i111:cb(4)" )
			)
			( pin "J4A2.192"
				( objectStatus "@baseboard_fab2_lib.baseboard_fab2(sch_1):page51_i111:cb(5)" )
			)
			( pin "J4A2.54"
				( objectStatus "@baseboard_fab2_lib.baseboard_fab2(sch_1):page51_i111:cb(6)" )
			)
			( pin "J4A2.199"
				( objectStatus "@baseboard_fab2_lib.baseboard_fab2(sch_1):page51_i111:cb(7)" )
			)
			( pin "J4A2.75"
				( objectStatus "@baseboard_fab2_lib.baseboard_fab2(sch_1):page51_i111:ck0n" )
			)
			( pin "J4A2.74"
				( objectStatus "@baseboard_fab2_lib.baseboard_fab2(sch_1):page51_i111:ck0p" )
			)
			( pin "J4A2.219"
				( objectStatus "@baseboard_fab2_lib.baseboard_fab2(sch_1):page51_i111:ck1n" )
			)
			( pin "J4A2.218"
				( objectStatus "@baseboard_fab2_lib.baseboard_fab2(sch_1):page51_i111:ck1p" )
			)
			( pin "J4A2.60"
				( objectStatus "@baseboard_fab2_lib.baseboard_fab2(sch_1):page51_i111:cke(0)" )
			)
			( pin "J4A2.203"
				( objectStatus "@baseboard_fab2_lib.baseboard_fab2(sch_1):page51_i111:cke(1)" )
			)
			( pin "J4A2.5"
				( objectStatus "@baseboard_fab2_lib.baseboard_fab2(sch_1):page51_i111:dq(0)" )
			)
			( pin "J4A2.150"
				( objectStatus "@baseboard_fab2_lib.baseboard_fab2(sch_1):page51_i111:dq(1)" )
			)
			( pin "J4A2.12"
				( objectStatus "@baseboard_fab2_lib.baseboard_fab2(sch_1):page51_i111:dq(2)" )
			)
			( pin "J4A2.157"
				( objectStatus "@baseboard_fab2_lib.baseboard_fab2(sch_1):page51_i111:dq(3)" )
			)
			( pin "J4A2.3"
				( objectStatus "@baseboard_fab2_lib.baseboard_fab2(sch_1):page51_i111:dq(4)" )
			)
			( pin "J4A2.148"
				( objectStatus "@baseboard_fab2_lib.baseboard_fab2(sch_1):page51_i111:dq(5)" )
			)
			( pin "J4A2.10"
				( objectStatus "@baseboard_fab2_lib.baseboard_fab2(sch_1):page51_i111:dq(6)" )
			)
			( pin "J4A2.155"
				( objectStatus "@baseboard_fab2_lib.baseboard_fab2(sch_1):page51_i111:dq(7)" )
			)
			( pin "J4A2.16"
				( objectStatus "@baseboard_fab2_lib.baseboard_fab2(sch_1):page51_i111:dq(8)" )
			)
			( pin "J4A2.161"
				( objectStatus "@baseboard_fab2_lib.baseboard_fab2(sch_1):page51_i111:dq(9)" )
			)
			( pin "J4A2.23"
				( objectStatus "@baseboard_fab2_lib.baseboard_fab2(sch_1):page51_i111:dq(10)" )
			)
			( pin "J4A2.168"
				( objectStatus "@baseboard_fab2_lib.baseboard_fab2(sch_1):page51_i111:dq(11)" )
			)
			( pin "J4A2.14"
				( objectStatus "@baseboard_fab2_lib.baseboard_fab2(sch_1):page51_i111:dq(12)" )
			)
			( pin "J4A2.159"
				( objectStatus "@baseboard_fab2_lib.baseboard_fab2(sch_1):page51_i111:dq(13)" )
			)
			( pin "J4A2.21"
				( objectStatus "@baseboard_fab2_lib.baseboard_fab2(sch_1):page51_i111:dq(14)" )
			)
			( pin "J4A2.166"
				( objectStatus "@baseboard_fab2_lib.baseboard_fab2(sch_1):page51_i111:dq(15)" )
			)
			( pin "J4A2.27"
				( objectStatus "@baseboard_fab2_lib.baseboard_fab2(sch_1):page51_i111:dq(16)" )
			)
			( pin "J4A2.172"
				( objectStatus "@baseboard_fab2_lib.baseboard_fab2(sch_1):page51_i111:dq(17)" )
			)
			( pin "J4A2.34"
				( objectStatus "@baseboard_fab2_lib.baseboard_fab2(sch_1):page51_i111:dq(18)" )
			)
			( pin "J4A2.179"
				( objectStatus "@baseboard_fab2_lib.baseboard_fab2(sch_1):page51_i111:dq(19)" )
			)
			( pin "J4A2.25"
				( objectStatus "@baseboard_fab2_lib.baseboard_fab2(sch_1):page51_i111:dq(20)" )
			)
			( pin "J4A2.170"
				( objectStatus "@baseboard_fab2_lib.baseboard_fab2(sch_1):page51_i111:dq(21)" )
			)
			( pin "J4A2.32"
				( objectStatus "@baseboard_fab2_lib.baseboard_fab2(sch_1):page51_i111:dq(22)" )
			)
			( pin "J4A2.177"
				( objectStatus "@baseboard_fab2_lib.baseboard_fab2(sch_1):page51_i111:dq(23)" )
			)
			( pin "J4A2.38"
				( objectStatus "@baseboard_fab2_lib.baseboard_fab2(sch_1):page51_i111:dq(24)" )
			)
			( pin "J4A2.183"
				( objectStatus "@baseboard_fab2_lib.baseboard_fab2(sch_1):page51_i111:dq(25)" )
			)
			( pin "J4A2.45"
				( objectStatus "@baseboard_fab2_lib.baseboard_fab2(sch_1):page51_i111:dq(26)" )
			)
			( pin "J4A2.190"
				( objectStatus "@baseboard_fab2_lib.baseboard_fab2(sch_1):page51_i111:dq(27)" )
			)
			( pin "J4A2.36"
				( objectStatus "@baseboard_fab2_lib.baseboard_fab2(sch_1):page51_i111:dq(28)" )
			)
			( pin "J4A2.181"
				( objectStatus "@baseboard_fab2_lib.baseboard_fab2(sch_1):page51_i111:dq(29)" )
			)
			( pin "J4A2.43"
				( objectStatus "@baseboard_fab2_lib.baseboard_fab2(sch_1):page51_i111:dq(30)" )
			)
			( pin "J4A2.188"
				( objectStatus "@baseboard_fab2_lib.baseboard_fab2(sch_1):page51_i111:dq(31)" )
			)
			( pin "J4A2.97"
				( objectStatus "@baseboard_fab2_lib.baseboard_fab2(sch_1):page51_i111:dq(32)" )
			)
			( pin "J4A2.242"
				( objectStatus "@baseboard_fab2_lib.baseboard_fab2(sch_1):page51_i111:dq(33)" )
			)
			( pin "J4A2.104"
				( objectStatus "@baseboard_fab2_lib.baseboard_fab2(sch_1):page51_i111:dq(34)" )
			)
			( pin "J4A2.249"
				( objectStatus "@baseboard_fab2_lib.baseboard_fab2(sch_1):page51_i111:dq(35)" )
			)
			( pin "J4A2.95"
				( objectStatus "@baseboard_fab2_lib.baseboard_fab2(sch_1):page51_i111:dq(36)" )
			)
			( pin "J4A2.240"
				( objectStatus "@baseboard_fab2_lib.baseboard_fab2(sch_1):page51_i111:dq(37)" )
			)
			( pin "J4A2.102"
				( objectStatus "@baseboard_fab2_lib.baseboard_fab2(sch_1):page51_i111:dq(38)" )
			)
			( pin "J4A2.247"
				( objectStatus "@baseboard_fab2_lib.baseboard_fab2(sch_1):page51_i111:dq(39)" )
			)
			( pin "J4A2.108"
				( objectStatus "@baseboard_fab2_lib.baseboard_fab2(sch_1):page51_i111:dq(40)" )
			)
			( pin "J4A2.253"
				( objectStatus "@baseboard_fab2_lib.baseboard_fab2(sch_1):page51_i111:dq(41)" )
			)
			( pin "J4A2.115"
				( objectStatus "@baseboard_fab2_lib.baseboard_fab2(sch_1):page51_i111:dq(42)" )
			)
			( pin "J4A2.260"
				( objectStatus "@baseboard_fab2_lib.baseboard_fab2(sch_1):page51_i111:dq(43)" )
			)
			( pin "J4A2.106"
				( objectStatus "@baseboard_fab2_lib.baseboard_fab2(sch_1):page51_i111:dq(44)" )
			)
			( pin "J4A2.251"
				( objectStatus "@baseboard_fab2_lib.baseboard_fab2(sch_1):page51_i111:dq(45)" )
			)
			( pin "J4A2.113"
				( objectStatus "@baseboard_fab2_lib.baseboard_fab2(sch_1):page51_i111:dq(46)" )
			)
			( pin "J4A2.258"
				( objectStatus "@baseboard_fab2_lib.baseboard_fab2(sch_1):page51_i111:dq(47)" )
			)
			( pin "J4A2.119"
				( objectStatus "@baseboard_fab2_lib.baseboard_fab2(sch_1):page51_i111:dq(48)" )
			)
			( pin "J4A2.264"
				( objectStatus "@baseboard_fab2_lib.baseboard_fab2(sch_1):page51_i111:dq(49)" )
			)
			( pin "J4A2.126"
				( objectStatus "@baseboard_fab2_lib.baseboard_fab2(sch_1):page51_i111:dq(50)" )
			)
			( pin "J4A2.271"
				( objectStatus "@baseboard_fab2_lib.baseboard_fab2(sch_1):page51_i111:dq(51)" )
			)
			( pin "J4A2.117"
				( objectStatus "@baseboard_fab2_lib.baseboard_fab2(sch_1):page51_i111:dq(52)" )
			)
			( pin "J4A2.262"
				( objectStatus "@baseboard_fab2_lib.baseboard_fab2(sch_1):page51_i111:dq(53)" )
			)
			( pin "J4A2.124"
				( objectStatus "@baseboard_fab2_lib.baseboard_fab2(sch_1):page51_i111:dq(54)" )
			)
			( pin "J4A2.269"
				( objectStatus "@baseboard_fab2_lib.baseboard_fab2(sch_1):page51_i111:dq(55)" )
			)
			( pin "J4A2.130"
				( objectStatus "@baseboard_fab2_lib.baseboard_fab2(sch_1):page51_i111:dq(56)" )
			)
			( pin "J4A2.275"
				( objectStatus "@baseboard_fab2_lib.baseboard_fab2(sch_1):page51_i111:dq(57)" )
			)
			( pin "J4A2.137"
				( objectStatus "@baseboard_fab2_lib.baseboard_fab2(sch_1):page51_i111:dq(58)" )
			)
			( pin "J4A2.282"
				( objectStatus "@baseboard_fab2_lib.baseboard_fab2(sch_1):page51_i111:dq(59)" )
			)
			( pin "J4A2.128"
				( objectStatus "@baseboard_fab2_lib.baseboard_fab2(sch_1):page51_i111:dq(60)" )
			)
			( pin "J4A2.273"
				( objectStatus "@baseboard_fab2_lib.baseboard_fab2(sch_1):page51_i111:dq(61)" )
			)
			( pin "J4A2.135"
				( objectStatus "@baseboard_fab2_lib.baseboard_fab2(sch_1):page51_i111:dq(62)" )
			)
			( pin "J4A2.280"
				( objectStatus "@baseboard_fab2_lib.baseboard_fab2(sch_1):page51_i111:dq(63)" )
			)
			( pin "J4A2.78"
				( objectStatus "@baseboard_fab2_lib.baseboard_fab2(sch_1):page51_i111:event_n" )
			)
			( pin "J4A2.87"
				( objectStatus "@baseboard_fab2_lib.baseboard_fab2(sch_1):page51_i111:odt(0)" )
			)
			( pin "J4A2.91"
				( objectStatus "@baseboard_fab2_lib.baseboard_fab2(sch_1):page51_i111:odt(1)" )
			)
			( pin "J4A2.222"
				( objectStatus "@baseboard_fab2_lib.baseboard_fab2(sch_1):page51_i111:par" )
			)
			( pin "J4A2.58"
				( objectStatus "@baseboard_fab2_lib.baseboard_fab2(sch_1):page51_i111:reset_n" )
			)
			( pin "J4A2.205"
				( objectStatus "@baseboard_fab2_lib.baseboard_fab2(sch_1):page51_i111:rfu(0)" )
			)
			( pin "J4A2.227"
				( objectStatus "@baseboard_fab2_lib.baseboard_fab2(sch_1):page51_i111:rfu(1)" )
			)
			( pin "J4A2.144"
				( objectStatus "@baseboard_fab2_lib.baseboard_fab2(sch_1):page51_i111:rfu(2)" )
			)
			( pin "J4A2.84"
				( objectStatus "@baseboard_fab2_lib.baseboard_fab2(sch_1):page51_i111:s0_n" )
			)
			( pin "J4A2.89"
				( objectStatus "@baseboard_fab2_lib.baseboard_fab2(sch_1):page51_i111:s1_n" )
			)
			( pin "J4A2.93"
				( objectStatus "@baseboard_fab2_lib.baseboard_fab2(sch_1):page51_i111:s2_n_c(0)" )
			)
			( pin "J4A2.237"
				( objectStatus "@baseboard_fab2_lib.baseboard_fab2(sch_1):page51_i111:s3_n_c(1)" )
			)
			( pin "J4A2.139"
				( objectStatus "@baseboard_fab2_lib.baseboard_fab2(sch_1):page51_i111:sa(0)" )
			)
			( pin "J4A2.140"
				( objectStatus "@baseboard_fab2_lib.baseboard_fab2(sch_1):page51_i111:sa(1)" )
			)
			( pin "J4A2.238"
				( objectStatus "@baseboard_fab2_lib.baseboard_fab2(sch_1):page51_i111:sa(2)" )
			)
			( pin "J4A2.230"
				( objectStatus "@baseboard_fab2_lib.baseboard_fab2(sch_1):page51_i111:save_n_nc" )
			)
			( pin "J4A2.141"
				( objectStatus "@baseboard_fab2_lib.baseboard_fab2(sch_1):page51_i111:scl" )
			)
			( pin "J4A2.285"
				( objectStatus "@baseboard_fab2_lib.baseboard_fab2(sch_1):page51_i111:sda" )
			)
			( pin "J4A2.284"
				( objectStatus "@baseboard_fab2_lib.baseboard_fab2(sch_1):page51_i111:vddspd" )
			)
			( pin "J4A2.146"
				( objectStatus "@baseboard_fab2_lib.baseboard_fab2(sch_1):page51_i111:vrefca" )
			)
			( pin "J4A2.145"
				( objectStatus "@baseboard_fab2_lib.baseboard_fab2(sch_1):page51_i167:\12v\(0)" )
			)
			( pin "J4A2.1"
				( objectStatus "@baseboard_fab2_lib.baseboard_fab2(sch_1):page51_i167:\12v\(1)" )
			)
			( pin "J4A2.236"
				( objectStatus "@baseboard_fab2_lib.baseboard_fab2(sch_1):page51_i167:vdd(0)" )
			)
			( pin "J4A2.233"
				( objectStatus "@baseboard_fab2_lib.baseboard_fab2(sch_1):page51_i167:vdd(1)" )
			)
			( pin "J4A2.231"
				( objectStatus "@baseboard_fab2_lib.baseboard_fab2(sch_1):page51_i167:vdd(2)" )
			)
			( pin "J4A2.229"
				( objectStatus "@baseboard_fab2_lib.baseboard_fab2(sch_1):page51_i167:vdd(3)" )
			)
			( pin "J4A2.226"
				( objectStatus "@baseboard_fab2_lib.baseboard_fab2(sch_1):page51_i167:vdd(4)" )
			)
			( pin "J4A2.223"
				( objectStatus "@baseboard_fab2_lib.baseboard_fab2(sch_1):page51_i167:vdd(5)" )
			)
			( pin "J4A2.220"
				( objectStatus "@baseboard_fab2_lib.baseboard_fab2(sch_1):page51_i167:vdd(6)" )
			)
			( pin "J4A2.217"
				( objectStatus "@baseboard_fab2_lib.baseboard_fab2(sch_1):page51_i167:vdd(7)" )
			)
			( pin "J4A2.215"
				( objectStatus "@baseboard_fab2_lib.baseboard_fab2(sch_1):page51_i167:vdd(8)" )
			)
			( pin "J4A2.212"
				( objectStatus "@baseboard_fab2_lib.baseboard_fab2(sch_1):page51_i167:vdd(9)" )
			)
			( pin "J4A2.209"
				( objectStatus "@baseboard_fab2_lib.baseboard_fab2(sch_1):page51_i167:vdd(10)" )
			)
			( pin "J4A2.206"
				( objectStatus "@baseboard_fab2_lib.baseboard_fab2(sch_1):page51_i167:vdd(11)" )
			)
			( pin "J4A2.204"
				( objectStatus "@baseboard_fab2_lib.baseboard_fab2(sch_1):page51_i167:vdd(12)" )
			)
			( pin "J4A2.92"
				( objectStatus "@baseboard_fab2_lib.baseboard_fab2(sch_1):page51_i167:vdd(13)" )
			)
			( pin "J4A2.90"
				( objectStatus "@baseboard_fab2_lib.baseboard_fab2(sch_1):page51_i167:vdd(14)" )
			)
			( pin "J4A2.88"
				( objectStatus "@baseboard_fab2_lib.baseboard_fab2(sch_1):page51_i167:vdd(15)" )
			)
			( pin "J4A2.85"
				( objectStatus "@baseboard_fab2_lib.baseboard_fab2(sch_1):page51_i167:vdd(16)" )
			)
			( pin "J4A2.83"
				( objectStatus "@baseboard_fab2_lib.baseboard_fab2(sch_1):page51_i167:vdd(17)" )
			)
			( pin "J4A2.80"
				( objectStatus "@baseboard_fab2_lib.baseboard_fab2(sch_1):page51_i167:vdd(18)" )
			)
			( pin "J4A2.76"
				( objectStatus "@baseboard_fab2_lib.baseboard_fab2(sch_1):page51_i167:vdd(19)" )
			)
			( pin "J4A2.73"
				( objectStatus "@baseboard_fab2_lib.baseboard_fab2(sch_1):page51_i167:vdd(20)" )
			)
			( pin "J4A2.70"
				( objectStatus "@baseboard_fab2_lib.baseboard_fab2(sch_1):page51_i167:vdd(21)" )
			)
			( pin "J4A2.67"
				( objectStatus "@baseboard_fab2_lib.baseboard_fab2(sch_1):page51_i167:vdd(22)" )
			)
			( pin "J4A2.64"
				( objectStatus "@baseboard_fab2_lib.baseboard_fab2(sch_1):page51_i167:vdd(23)" )
			)
			( pin "J4A2.61"
				( objectStatus "@baseboard_fab2_lib.baseboard_fab2(sch_1):page51_i167:vdd(24)" )
			)
			( pin "J4A2.59"
				( objectStatus "@baseboard_fab2_lib.baseboard_fab2(sch_1):page51_i167:vdd(25)" )
			)
			( pin "J4A2.287"
				( objectStatus "@baseboard_fab2_lib.baseboard_fab2(sch_1):page51_i167:vpp(0)" )
			)
			( pin "J4A2.286"
				( objectStatus "@baseboard_fab2_lib.baseboard_fab2(sch_1):page51_i167:vpp(1)" )
			)
			( pin "J4A2.288"
				( objectStatus "@baseboard_fab2_lib.baseboard_fab2(sch_1):page51_i167:vpp(2)" )
			)
			( pin "J4A2.143"
				( objectStatus "@baseboard_fab2_lib.baseboard_fab2(sch_1):page51_i167:vpp(3)" )
			)
			( pin "J4A2.142"
				( objectStatus "@baseboard_fab2_lib.baseboard_fab2(sch_1):page51_i167:vpp(4)" )
			)
			( pin "J4A2.221"
				( objectStatus "@baseboard_fab2_lib.baseboard_fab2(sch_1):page51_i167:vtt(0)" )
			)
			( pin "J4A2.77"
				( objectStatus "@baseboard_fab2_lib.baseboard_fab2(sch_1):page51_i167:vtt(1)" )
			)
			( pin "C6L6.1"
				( objectStatus "@baseboard_fab2_lib.baseboard_fab2(sch_1):page51_i175:a" )
			)
			( pin "C6L6.2"
				( objectStatus "@baseboard_fab2_lib.baseboard_fab2(sch_1):page51_i175:b" )
			)
			( pin "C4A18.1"
				( objectStatus "@baseboard_fab2_lib.baseboard_fab2(sch_1):page52_i3:a" )
			)
			( pin "C4A18.2"
				( objectStatus "@baseboard_fab2_lib.baseboard_fab2(sch_1):page52_i3:b" )
			)
			( pin "J6L2.79"
				( objectStatus "@baseboard_fab2_lib.baseboard_fab2(sch_1):page52_i12:a0" )
			)
			( pin "J6L2.72"
				( objectStatus "@baseboard_fab2_lib.baseboard_fab2(sch_1):page52_i12:a1" )
			)
			( pin "J6L2.216"
				( objectStatus "@baseboard_fab2_lib.baseboard_fab2(sch_1):page52_i12:a2" )
			)
			( pin "J6L2.71"
				( objectStatus "@baseboard_fab2_lib.baseboard_fab2(sch_1):page52_i12:a3" )
			)
			( pin "J6L2.214"
				( objectStatus "@baseboard_fab2_lib.baseboard_fab2(sch_1):page52_i12:a4" )
			)
			( pin "J6L2.213"
				( objectStatus "@baseboard_fab2_lib.baseboard_fab2(sch_1):page52_i12:a5" )
			)
			( pin "J6L2.69"
				( objectStatus "@baseboard_fab2_lib.baseboard_fab2(sch_1):page52_i12:a6" )
			)
			( pin "J6L2.211"
				( objectStatus "@baseboard_fab2_lib.baseboard_fab2(sch_1):page52_i12:a7" )
			)
			( pin "J6L2.68"
				( objectStatus "@baseboard_fab2_lib.baseboard_fab2(sch_1):page52_i12:a8" )
			)
			( pin "J6L2.66"
				( objectStatus "@baseboard_fab2_lib.baseboard_fab2(sch_1):page52_i12:a9" )
			)
			( pin "J6L2.225"
				( objectStatus "@baseboard_fab2_lib.baseboard_fab2(sch_1):page52_i12:a10" )
			)
			( pin "J6L2.210"
				( objectStatus "@baseboard_fab2_lib.baseboard_fab2(sch_1):page52_i12:a11" )
			)
			( pin "J6L2.65"
				( objectStatus "@baseboard_fab2_lib.baseboard_fab2(sch_1):page52_i12:a12" )
			)
			( pin "J6L2.232"
				( objectStatus "@baseboard_fab2_lib.baseboard_fab2(sch_1):page52_i12:a13" )
			)
			( pin "J6L2.228"
				( objectStatus "@baseboard_fab2_lib.baseboard_fab2(sch_1):page52_i12:a14_we_n" )
			)
			( pin "J6L2.86"
				( objectStatus "@baseboard_fab2_lib.baseboard_fab2(sch_1):page52_i12:a15_cas_n" )
			)
			( pin "J6L2.82"
				( objectStatus "@baseboard_fab2_lib.baseboard_fab2(sch_1):page52_i12:a16_ras_n" )
			)
			( pin "J6L2.234"
				( objectStatus "@baseboard_fab2_lib.baseboard_fab2(sch_1):page52_i12:a17" )
			)
			( pin "J6L2.62"
				( objectStatus "@baseboard_fab2_lib.baseboard_fab2(sch_1):page52_i12:act_n" )
			)
			( pin "J6L2.208"
				( objectStatus "@baseboard_fab2_lib.baseboard_fab2(sch_1):page52_i12:alert_n" )
			)
			( pin "J6L2.81"
				( objectStatus "@baseboard_fab2_lib.baseboard_fab2(sch_1):page52_i12:ba(0)" )
			)
			( pin "J6L2.224"
				( objectStatus "@baseboard_fab2_lib.baseboard_fab2(sch_1):page52_i12:ba(1)" )
			)
			( pin "J6L2.63"
				( objectStatus "@baseboard_fab2_lib.baseboard_fab2(sch_1):page52_i12:bg(0)" )
			)
			( pin "J6L2.207"
				( objectStatus "@baseboard_fab2_lib.baseboard_fab2(sch_1):page52_i12:bg(1)" )
			)
			( pin "J6L2.235"
				( objectStatus "@baseboard_fab2_lib.baseboard_fab2(sch_1):page52_i12:c(2)" )
			)
			( pin "J6L2.49"
				( objectStatus "@baseboard_fab2_lib.baseboard_fab2(sch_1):page52_i12:cb(0)" )
			)
			( pin "J6L2.194"
				( objectStatus "@baseboard_fab2_lib.baseboard_fab2(sch_1):page52_i12:cb(1)" )
			)
			( pin "J6L2.56"
				( objectStatus "@baseboard_fab2_lib.baseboard_fab2(sch_1):page52_i12:cb(2)" )
			)
			( pin "J6L2.201"
				( objectStatus "@baseboard_fab2_lib.baseboard_fab2(sch_1):page52_i12:cb(3)" )
			)
			( pin "J6L2.47"
				( objectStatus "@baseboard_fab2_lib.baseboard_fab2(sch_1):page52_i12:cb(4)" )
			)
			( pin "J6L2.192"
				( objectStatus "@baseboard_fab2_lib.baseboard_fab2(sch_1):page52_i12:cb(5)" )
			)
			( pin "J6L2.54"
				( objectStatus "@baseboard_fab2_lib.baseboard_fab2(sch_1):page52_i12:cb(6)" )
			)
			( pin "J6L2.199"
				( objectStatus "@baseboard_fab2_lib.baseboard_fab2(sch_1):page52_i12:cb(7)" )
			)
			( pin "J6L2.75"
				( objectStatus "@baseboard_fab2_lib.baseboard_fab2(sch_1):page52_i12:ck0n" )
			)
			( pin "J6L2.74"
				( objectStatus "@baseboard_fab2_lib.baseboard_fab2(sch_1):page52_i12:ck0p" )
			)
			( pin "J6L2.219"
				( objectStatus "@baseboard_fab2_lib.baseboard_fab2(sch_1):page52_i12:ck1n" )
			)
			( pin "J6L2.218"
				( objectStatus "@baseboard_fab2_lib.baseboard_fab2(sch_1):page52_i12:ck1p" )
			)
			( pin "J6L2.60"
				( objectStatus "@baseboard_fab2_lib.baseboard_fab2(sch_1):page52_i12:cke(0)" )
			)
			( pin "J6L2.203"
				( objectStatus "@baseboard_fab2_lib.baseboard_fab2(sch_1):page52_i12:cke(1)" )
			)
			( pin "J6L2.5"
				( objectStatus "@baseboard_fab2_lib.baseboard_fab2(sch_1):page52_i12:dq(0)" )
			)
			( pin "J6L2.150"
				( objectStatus "@baseboard_fab2_lib.baseboard_fab2(sch_1):page52_i12:dq(1)" )
			)
			( pin "J6L2.12"
				( objectStatus "@baseboard_fab2_lib.baseboard_fab2(sch_1):page52_i12:dq(2)" )
			)
			( pin "J6L2.157"
				( objectStatus "@baseboard_fab2_lib.baseboard_fab2(sch_1):page52_i12:dq(3)" )
			)
			( pin "J6L2.3"
				( objectStatus "@baseboard_fab2_lib.baseboard_fab2(sch_1):page52_i12:dq(4)" )
			)
			( pin "J6L2.148"
				( objectStatus "@baseboard_fab2_lib.baseboard_fab2(sch_1):page52_i12:dq(5)" )
			)
			( pin "J6L2.10"
				( objectStatus "@baseboard_fab2_lib.baseboard_fab2(sch_1):page52_i12:dq(6)" )
			)
			( pin "J6L2.155"
				( objectStatus "@baseboard_fab2_lib.baseboard_fab2(sch_1):page52_i12:dq(7)" )
			)
			( pin "J6L2.16"
				( objectStatus "@baseboard_fab2_lib.baseboard_fab2(sch_1):page52_i12:dq(8)" )
			)
			( pin "J6L2.161"
				( objectStatus "@baseboard_fab2_lib.baseboard_fab2(sch_1):page52_i12:dq(9)" )
			)
			( pin "J6L2.23"
				( objectStatus "@baseboard_fab2_lib.baseboard_fab2(sch_1):page52_i12:dq(10)" )
			)
			( pin "J6L2.168"
				( objectStatus "@baseboard_fab2_lib.baseboard_fab2(sch_1):page52_i12:dq(11)" )
			)
			( pin "J6L2.14"
				( objectStatus "@baseboard_fab2_lib.baseboard_fab2(sch_1):page52_i12:dq(12)" )
			)
			( pin "J6L2.159"
				( objectStatus "@baseboard_fab2_lib.baseboard_fab2(sch_1):page52_i12:dq(13)" )
			)
			( pin "J6L2.21"
				( objectStatus "@baseboard_fab2_lib.baseboard_fab2(sch_1):page52_i12:dq(14)" )
			)
			( pin "J6L2.166"
				( objectStatus "@baseboard_fab2_lib.baseboard_fab2(sch_1):page52_i12:dq(15)" )
			)
			( pin "J6L2.27"
				( objectStatus "@baseboard_fab2_lib.baseboard_fab2(sch_1):page52_i12:dq(16)" )
			)
			( pin "J6L2.172"
				( objectStatus "@baseboard_fab2_lib.baseboard_fab2(sch_1):page52_i12:dq(17)" )
			)
			( pin "J6L2.34"
				( objectStatus "@baseboard_fab2_lib.baseboard_fab2(sch_1):page52_i12:dq(18)" )
			)
			( pin "J6L2.179"
				( objectStatus "@baseboard_fab2_lib.baseboard_fab2(sch_1):page52_i12:dq(19)" )
			)
			( pin "J6L2.25"
				( objectStatus "@baseboard_fab2_lib.baseboard_fab2(sch_1):page52_i12:dq(20)" )
			)
			( pin "J6L2.170"
				( objectStatus "@baseboard_fab2_lib.baseboard_fab2(sch_1):page52_i12:dq(21)" )
			)
			( pin "J6L2.32"
				( objectStatus "@baseboard_fab2_lib.baseboard_fab2(sch_1):page52_i12:dq(22)" )
			)
			( pin "J6L2.177"
				( objectStatus "@baseboard_fab2_lib.baseboard_fab2(sch_1):page52_i12:dq(23)" )
			)
			( pin "J6L2.38"
				( objectStatus "@baseboard_fab2_lib.baseboard_fab2(sch_1):page52_i12:dq(24)" )
			)
			( pin "J6L2.183"
				( objectStatus "@baseboard_fab2_lib.baseboard_fab2(sch_1):page52_i12:dq(25)" )
			)
			( pin "J6L2.45"
				( objectStatus "@baseboard_fab2_lib.baseboard_fab2(sch_1):page52_i12:dq(26)" )
			)
			( pin "J6L2.190"
				( objectStatus "@baseboard_fab2_lib.baseboard_fab2(sch_1):page52_i12:dq(27)" )
			)
			( pin "J6L2.36"
				( objectStatus "@baseboard_fab2_lib.baseboard_fab2(sch_1):page52_i12:dq(28)" )
			)
			( pin "J6L2.181"
				( objectStatus "@baseboard_fab2_lib.baseboard_fab2(sch_1):page52_i12:dq(29)" )
			)
			( pin "J6L2.43"
				( objectStatus "@baseboard_fab2_lib.baseboard_fab2(sch_1):page52_i12:dq(30)" )
			)
			( pin "J6L2.188"
				( objectStatus "@baseboard_fab2_lib.baseboard_fab2(sch_1):page52_i12:dq(31)" )
			)
			( pin "J6L2.97"
				( objectStatus "@baseboard_fab2_lib.baseboard_fab2(sch_1):page52_i12:dq(32)" )
			)
			( pin "J6L2.242"
				( objectStatus "@baseboard_fab2_lib.baseboard_fab2(sch_1):page52_i12:dq(33)" )
			)
			( pin "J6L2.104"
				( objectStatus "@baseboard_fab2_lib.baseboard_fab2(sch_1):page52_i12:dq(34)" )
			)
			( pin "J6L2.249"
				( objectStatus "@baseboard_fab2_lib.baseboard_fab2(sch_1):page52_i12:dq(35)" )
			)
			( pin "J6L2.95"
				( objectStatus "@baseboard_fab2_lib.baseboard_fab2(sch_1):page52_i12:dq(36)" )
			)
			( pin "J6L2.240"
				( objectStatus "@baseboard_fab2_lib.baseboard_fab2(sch_1):page52_i12:dq(37)" )
			)
			( pin "J6L2.102"
				( objectStatus "@baseboard_fab2_lib.baseboard_fab2(sch_1):page52_i12:dq(38)" )
			)
			( pin "J6L2.247"
				( objectStatus "@baseboard_fab2_lib.baseboard_fab2(sch_1):page52_i12:dq(39)" )
			)
			( pin "J6L2.108"
				( objectStatus "@baseboard_fab2_lib.baseboard_fab2(sch_1):page52_i12:dq(40)" )
			)
			( pin "J6L2.253"
				( objectStatus "@baseboard_fab2_lib.baseboard_fab2(sch_1):page52_i12:dq(41)" )
			)
			( pin "J6L2.115"
				( objectStatus "@baseboard_fab2_lib.baseboard_fab2(sch_1):page52_i12:dq(42)" )
			)
			( pin "J6L2.260"
				( objectStatus "@baseboard_fab2_lib.baseboard_fab2(sch_1):page52_i12:dq(43)" )
			)
			( pin "J6L2.106"
				( objectStatus "@baseboard_fab2_lib.baseboard_fab2(sch_1):page52_i12:dq(44)" )
			)
			( pin "J6L2.251"
				( objectStatus "@baseboard_fab2_lib.baseboard_fab2(sch_1):page52_i12:dq(45)" )
			)
			( pin "J6L2.113"
				( objectStatus "@baseboard_fab2_lib.baseboard_fab2(sch_1):page52_i12:dq(46)" )
			)
			( pin "J6L2.258"
				( objectStatus "@baseboard_fab2_lib.baseboard_fab2(sch_1):page52_i12:dq(47)" )
			)
			( pin "J6L2.119"
				( objectStatus "@baseboard_fab2_lib.baseboard_fab2(sch_1):page52_i12:dq(48)" )
			)
			( pin "J6L2.264"
				( objectStatus "@baseboard_fab2_lib.baseboard_fab2(sch_1):page52_i12:dq(49)" )
			)
			( pin "J6L2.126"
				( objectStatus "@baseboard_fab2_lib.baseboard_fab2(sch_1):page52_i12:dq(50)" )
			)
			( pin "J6L2.271"
				( objectStatus "@baseboard_fab2_lib.baseboard_fab2(sch_1):page52_i12:dq(51)" )
			)
			( pin "J6L2.117"
				( objectStatus "@baseboard_fab2_lib.baseboard_fab2(sch_1):page52_i12:dq(52)" )
			)
			( pin "J6L2.262"
				( objectStatus "@baseboard_fab2_lib.baseboard_fab2(sch_1):page52_i12:dq(53)" )
			)
			( pin "J6L2.124"
				( objectStatus "@baseboard_fab2_lib.baseboard_fab2(sch_1):page52_i12:dq(54)" )
			)
			( pin "J6L2.269"
				( objectStatus "@baseboard_fab2_lib.baseboard_fab2(sch_1):page52_i12:dq(55)" )
			)
			( pin "J6L2.130"
				( objectStatus "@baseboard_fab2_lib.baseboard_fab2(sch_1):page52_i12:dq(56)" )
			)
			( pin "J6L2.275"
				( objectStatus "@baseboard_fab2_lib.baseboard_fab2(sch_1):page52_i12:dq(57)" )
			)
			( pin "J6L2.137"
				( objectStatus "@baseboard_fab2_lib.baseboard_fab2(sch_1):page52_i12:dq(58)" )
			)
			( pin "J6L2.282"
				( objectStatus "@baseboard_fab2_lib.baseboard_fab2(sch_1):page52_i12:dq(59)" )
			)
			( pin "J6L2.128"
				( objectStatus "@baseboard_fab2_lib.baseboard_fab2(sch_1):page52_i12:dq(60)" )
			)
			( pin "J6L2.273"
				( objectStatus "@baseboard_fab2_lib.baseboard_fab2(sch_1):page52_i12:dq(61)" )
			)
			( pin "J6L2.135"
				( objectStatus "@baseboard_fab2_lib.baseboard_fab2(sch_1):page52_i12:dq(62)" )
			)
			( pin "J6L2.280"
				( objectStatus "@baseboard_fab2_lib.baseboard_fab2(sch_1):page52_i12:dq(63)" )
			)
			( pin "J6L2.78"
				( objectStatus "@baseboard_fab2_lib.baseboard_fab2(sch_1):page52_i12:event_n" )
			)
			( pin "J6L2.87"
				( objectStatus "@baseboard_fab2_lib.baseboard_fab2(sch_1):page52_i12:odt(0)" )
			)
			( pin "J6L2.91"
				( objectStatus "@baseboard_fab2_lib.baseboard_fab2(sch_1):page52_i12:odt(1)" )
			)
			( pin "J6L2.222"
				( objectStatus "@baseboard_fab2_lib.baseboard_fab2(sch_1):page52_i12:par" )
			)
			( pin "J6L2.58"
				( objectStatus "@baseboard_fab2_lib.baseboard_fab2(sch_1):page52_i12:reset_n" )
			)
			( pin "J6L2.205"
				( objectStatus "@baseboard_fab2_lib.baseboard_fab2(sch_1):page52_i12:rfu(0)" )
			)
			( pin "J6L2.227"
				( objectStatus "@baseboard_fab2_lib.baseboard_fab2(sch_1):page52_i12:rfu(1)" )
			)
			( pin "J6L2.144"
				( objectStatus "@baseboard_fab2_lib.baseboard_fab2(sch_1):page52_i12:rfu(2)" )
			)
			( pin "J6L2.84"
				( objectStatus "@baseboard_fab2_lib.baseboard_fab2(sch_1):page52_i12:s0_n" )
			)
			( pin "J6L2.89"
				( objectStatus "@baseboard_fab2_lib.baseboard_fab2(sch_1):page52_i12:s1_n" )
			)
			( pin "J6L2.93"
				( objectStatus "@baseboard_fab2_lib.baseboard_fab2(sch_1):page52_i12:s2_n_c(0)" )
			)
			( pin "J6L2.237"
				( objectStatus "@baseboard_fab2_lib.baseboard_fab2(sch_1):page52_i12:s3_n_c(1)" )
			)
			( pin "J6L2.139"
				( objectStatus "@baseboard_fab2_lib.baseboard_fab2(sch_1):page52_i12:sa(0)" )
			)
			( pin "J6L2.140"
				( objectStatus "@baseboard_fab2_lib.baseboard_fab2(sch_1):page52_i12:sa(1)" )
			)
			( pin "J6L2.238"
				( objectStatus "@baseboard_fab2_lib.baseboard_fab2(sch_1):page52_i12:sa(2)" )
			)
			( pin "J6L2.230"
				( objectStatus "@baseboard_fab2_lib.baseboard_fab2(sch_1):page52_i12:save_n_nc" )
			)
			( pin "J6L2.141"
				( objectStatus "@baseboard_fab2_lib.baseboard_fab2(sch_1):page52_i12:scl" )
			)
			( pin "J6L2.285"
				( objectStatus "@baseboard_fab2_lib.baseboard_fab2(sch_1):page52_i12:sda" )
			)
			( pin "J6L2.284"
				( objectStatus "@baseboard_fab2_lib.baseboard_fab2(sch_1):page52_i12:vddspd" )
			)
			( pin "J6L2.146"
				( objectStatus "@baseboard_fab2_lib.baseboard_fab2(sch_1):page52_i12:vrefca" )
			)
			( pin "J6L2.145"
				( objectStatus "@baseboard_fab2_lib.baseboard_fab2(sch_1):page52_i55:\12v\(0)" )
			)
			( pin "J6L2.1"
				( objectStatus "@baseboard_fab2_lib.baseboard_fab2(sch_1):page52_i55:\12v\(1)" )
			)
			( pin "J6L2.236"
				( objectStatus "@baseboard_fab2_lib.baseboard_fab2(sch_1):page52_i55:vdd(0)" )
			)
			( pin "J6L2.233"
				( objectStatus "@baseboard_fab2_lib.baseboard_fab2(sch_1):page52_i55:vdd(1)" )
			)
			( pin "J6L2.231"
				( objectStatus "@baseboard_fab2_lib.baseboard_fab2(sch_1):page52_i55:vdd(2)" )
			)
			( pin "J6L2.229"
				( objectStatus "@baseboard_fab2_lib.baseboard_fab2(sch_1):page52_i55:vdd(3)" )
			)
			( pin "J6L2.226"
				( objectStatus "@baseboard_fab2_lib.baseboard_fab2(sch_1):page52_i55:vdd(4)" )
			)
			( pin "J6L2.223"
				( objectStatus "@baseboard_fab2_lib.baseboard_fab2(sch_1):page52_i55:vdd(5)" )
			)
			( pin "J6L2.220"
				( objectStatus "@baseboard_fab2_lib.baseboard_fab2(sch_1):page52_i55:vdd(6)" )
			)
			( pin "J6L2.217"
				( objectStatus "@baseboard_fab2_lib.baseboard_fab2(sch_1):page52_i55:vdd(7)" )
			)
			( pin "J6L2.215"
				( objectStatus "@baseboard_fab2_lib.baseboard_fab2(sch_1):page52_i55:vdd(8)" )
			)
			( pin "J6L2.212"
				( objectStatus "@baseboard_fab2_lib.baseboard_fab2(sch_1):page52_i55:vdd(9)" )
			)
			( pin "J6L2.209"
				( objectStatus "@baseboard_fab2_lib.baseboard_fab2(sch_1):page52_i55:vdd(10)" )
			)
			( pin "J6L2.206"
				( objectStatus "@baseboard_fab2_lib.baseboard_fab2(sch_1):page52_i55:vdd(11)" )
			)
			( pin "J6L2.204"
				( objectStatus "@baseboard_fab2_lib.baseboard_fab2(sch_1):page52_i55:vdd(12)" )
			)
			( pin "J6L2.92"
				( objectStatus "@baseboard_fab2_lib.baseboard_fab2(sch_1):page52_i55:vdd(13)" )
			)
			( pin "J6L2.90"
				( objectStatus "@baseboard_fab2_lib.baseboard_fab2(sch_1):page52_i55:vdd(14)" )
			)
			( pin "J6L2.88"
				( objectStatus "@baseboard_fab2_lib.baseboard_fab2(sch_1):page52_i55:vdd(15)" )
			)
			( pin "J6L2.85"
				( objectStatus "@baseboard_fab2_lib.baseboard_fab2(sch_1):page52_i55:vdd(16)" )
			)
			( pin "J6L2.83"
				( objectStatus "@baseboard_fab2_lib.baseboard_fab2(sch_1):page52_i55:vdd(17)" )
			)
			( pin "J6L2.80"
				( objectStatus "@baseboard_fab2_lib.baseboard_fab2(sch_1):page52_i55:vdd(18)" )
			)
			( pin "J6L2.76"
				( objectStatus "@baseboard_fab2_lib.baseboard_fab2(sch_1):page52_i55:vdd(19)" )
			)
			( pin "J6L2.73"
				( objectStatus "@baseboard_fab2_lib.baseboard_fab2(sch_1):page52_i55:vdd(20)" )
			)
			( pin "J6L2.70"
				( objectStatus "@baseboard_fab2_lib.baseboard_fab2(sch_1):page52_i55:vdd(21)" )
			)
			( pin "J6L2.67"
				( objectStatus "@baseboard_fab2_lib.baseboard_fab2(sch_1):page52_i55:vdd(22)" )
			)
			( pin "J6L2.64"
				( objectStatus "@baseboard_fab2_lib.baseboard_fab2(sch_1):page52_i55:vdd(23)" )
			)
			( pin "J6L2.61"
				( objectStatus "@baseboard_fab2_lib.baseboard_fab2(sch_1):page52_i55:vdd(24)" )
			)
			( pin "J6L2.59"
				( objectStatus "@baseboard_fab2_lib.baseboard_fab2(sch_1):page52_i55:vdd(25)" )
			)
			( pin "J6L2.287"
				( objectStatus "@baseboard_fab2_lib.baseboard_fab2(sch_1):page52_i55:vpp(0)" )
			)
			( pin "J6L2.286"
				( objectStatus "@baseboard_fab2_lib.baseboard_fab2(sch_1):page52_i55:vpp(1)" )
			)
			( pin "J6L2.288"
				( objectStatus "@baseboard_fab2_lib.baseboard_fab2(sch_1):page52_i55:vpp(2)" )
			)
			( pin "J6L2.143"
				( objectStatus "@baseboard_fab2_lib.baseboard_fab2(sch_1):page52_i55:vpp(3)" )
			)
			( pin "J6L2.142"
				( objectStatus "@baseboard_fab2_lib.baseboard_fab2(sch_1):page52_i55:vpp(4)" )
			)
			( pin "J6L2.221"
				( objectStatus "@baseboard_fab2_lib.baseboard_fab2(sch_1):page52_i55:vtt(0)" )
			)
			( pin "J6L2.77"
				( objectStatus "@baseboard_fab2_lib.baseboard_fab2(sch_1):page52_i55:vtt(1)" )
			)
			( pin "J6L2.152"
				( objectStatus "@baseboard_fab2_lib.baseboard_fab2(sch_1):page52_i100:dqs0n" )
			)
			( pin "J6L2.153"
				( objectStatus "@baseboard_fab2_lib.baseboard_fab2(sch_1):page52_i100:dqs0p" )
			)
			( pin "J6L2.163"
				( objectStatus "@baseboard_fab2_lib.baseboard_fab2(sch_1):page52_i100:dqs1n" )
			)
			( pin "J6L2.164"
				( objectStatus "@baseboard_fab2_lib.baseboard_fab2(sch_1):page52_i100:dqs1p" )
			)
			( pin "J6L2.174"
				( objectStatus "@baseboard_fab2_lib.baseboard_fab2(sch_1):page52_i100:dqs2n" )
			)
			( pin "J6L2.175"
				( objectStatus "@baseboard_fab2_lib.baseboard_fab2(sch_1):page52_i100:dqs2p" )
			)
			( pin "J6L2.185"
				( objectStatus "@baseboard_fab2_lib.baseboard_fab2(sch_1):page52_i100:dqs3n" )
			)
			( pin "J6L2.186"
				( objectStatus "@baseboard_fab2_lib.baseboard_fab2(sch_1):page52_i100:dqs3p" )
			)
			( pin "J6L2.244"
				( objectStatus "@baseboard_fab2_lib.baseboard_fab2(sch_1):page52_i100:dqs4n" )
			)
			( pin "J6L2.245"
				( objectStatus "@baseboard_fab2_lib.baseboard_fab2(sch_1):page52_i100:dqs4p" )
			)
			( pin "J6L2.255"
				( objectStatus "@baseboard_fab2_lib.baseboard_fab2(sch_1):page52_i100:dqs5n" )
			)
			( pin "J6L2.256"
				( objectStatus "@baseboard_fab2_lib.baseboard_fab2(sch_1):page52_i100:dqs5p" )
			)
			( pin "J6L2.266"
				( objectStatus "@baseboard_fab2_lib.baseboard_fab2(sch_1):page52_i100:dqs6n" )
			)
			( pin "J6L2.267"
				( objectStatus "@baseboard_fab2_lib.baseboard_fab2(sch_1):page52_i100:dqs6p" )
			)
			( pin "J6L2.277"
				( objectStatus "@baseboard_fab2_lib.baseboard_fab2(sch_1):page52_i100:dqs7n" )
			)
			( pin "J6L2.278"
				( objectStatus "@baseboard_fab2_lib.baseboard_fab2(sch_1):page52_i100:dqs7p" )
			)
			( pin "J6L2.196"
				( objectStatus "@baseboard_fab2_lib.baseboard_fab2(sch_1):page52_i100:dqs8n" )
			)
			( pin "J6L2.197"
				( objectStatus "@baseboard_fab2_lib.baseboard_fab2(sch_1):page52_i100:dqs8p" )
			)
			( pin "J6L2.8"
				( objectStatus "@baseboard_fab2_lib.baseboard_fab2(sch_1):page52_i100:dqs9n" )
			)
			( pin "J6L2.7"
				( objectStatus "@baseboard_fab2_lib.baseboard_fab2(sch_1):page52_i100:dqs9p" )
			)
			( pin "J6L2.19"
				( objectStatus "@baseboard_fab2_lib.baseboard_fab2(sch_1):page52_i100:dqs10n" )
			)
			( pin "J6L2.18"
				( objectStatus "@baseboard_fab2_lib.baseboard_fab2(sch_1):page52_i100:dqs10p" )
			)
			( pin "J6L2.30"
				( objectStatus "@baseboard_fab2_lib.baseboard_fab2(sch_1):page52_i100:dqs11n" )
			)
			( pin "J6L2.29"
				( objectStatus "@baseboard_fab2_lib.baseboard_fab2(sch_1):page52_i100:dqs11p" )
			)
			( pin "J6L2.41"
				( objectStatus "@baseboard_fab2_lib.baseboard_fab2(sch_1):page52_i100:dqs12n" )
			)
			( pin "J6L2.40"
				( objectStatus "@baseboard_fab2_lib.baseboard_fab2(sch_1):page52_i100:dqs12p" )
			)
			( pin "J6L2.100"
				( objectStatus "@baseboard_fab2_lib.baseboard_fab2(sch_1):page52_i100:dqs13n" )
			)
			( pin "J6L2.99"
				( objectStatus "@baseboard_fab2_lib.baseboard_fab2(sch_1):page52_i100:dqs13p" )
			)
			( pin "J6L2.111"
				( objectStatus "@baseboard_fab2_lib.baseboard_fab2(sch_1):page52_i100:dqs14n" )
			)
			( pin "J6L2.110"
				( objectStatus "@baseboard_fab2_lib.baseboard_fab2(sch_1):page52_i100:dqs14p" )
			)
			( pin "J6L2.122"
				( objectStatus "@baseboard_fab2_lib.baseboard_fab2(sch_1):page52_i100:dqs15n" )
			)
			( pin "J6L2.121"
				( objectStatus "@baseboard_fab2_lib.baseboard_fab2(sch_1):page52_i100:dqs15p" )
			)
			( pin "J6L2.133"
				( objectStatus "@baseboard_fab2_lib.baseboard_fab2(sch_1):page52_i100:dqs16n" )
			)
			( pin "J6L2.132"
				( objectStatus "@baseboard_fab2_lib.baseboard_fab2(sch_1):page52_i100:dqs16p" )
			)
			( pin "J6L2.52"
				( objectStatus "@baseboard_fab2_lib.baseboard_fab2(sch_1):page52_i100:dqs17n" )
			)
			( pin "J6L2.51"
				( objectStatus "@baseboard_fab2_lib.baseboard_fab2(sch_1):page52_i100:dqs17p" )
			)
			( pin "J6L2.283"
				( objectStatus "@baseboard_fab2_lib.baseboard_fab2(sch_1):page52_i138:vss(0)" )
			)
			( pin "J6L2.281"
				( objectStatus "@baseboard_fab2_lib.baseboard_fab2(sch_1):page52_i138:vss(1)" )
			)
			( pin "J6L2.279"
				( objectStatus "@baseboard_fab2_lib.baseboard_fab2(sch_1):page52_i138:vss(2)" )
			)
			( pin "J6L2.276"
				( objectStatus "@baseboard_fab2_lib.baseboard_fab2(sch_1):page52_i138:vss(3)" )
			)
			( pin "J6L2.274"
				( objectStatus "@baseboard_fab2_lib.baseboard_fab2(sch_1):page52_i138:vss(4)" )
			)
			( pin "J6L2.272"
				( objectStatus "@baseboard_fab2_lib.baseboard_fab2(sch_1):page52_i138:vss(5)" )
			)
			( pin "J6L2.270"
				( objectStatus "@baseboard_fab2_lib.baseboard_fab2(sch_1):page52_i138:vss(6)" )
			)
			( pin "J6L2.268"
				( objectStatus "@baseboard_fab2_lib.baseboard_fab2(sch_1):page52_i138:vss(7)" )
			)
			( pin "J6L2.265"
				( objectStatus "@baseboard_fab2_lib.baseboard_fab2(sch_1):page52_i138:vss(8)" )
			)
			( pin "J6L2.263"
				( objectStatus "@baseboard_fab2_lib.baseboard_fab2(sch_1):page52_i138:vss(9)" )
			)
			( pin "J6L2.261"
				( objectStatus "@baseboard_fab2_lib.baseboard_fab2(sch_1):page52_i138:vss(10)" )
			)
			( pin "J6L2.259"
				( objectStatus "@baseboard_fab2_lib.baseboard_fab2(sch_1):page52_i138:vss(11)" )
			)
			( pin "J6L2.257"
				( objectStatus "@baseboard_fab2_lib.baseboard_fab2(sch_1):page52_i138:vss(12)" )
			)
			( pin "J6L2.254"
				( objectStatus "@baseboard_fab2_lib.baseboard_fab2(sch_1):page52_i138:vss(13)" )
			)
			( pin "J6L2.252"
				( objectStatus "@baseboard_fab2_lib.baseboard_fab2(sch_1):page52_i138:vss(14)" )
			)
			( pin "J6L2.250"
				( objectStatus "@baseboard_fab2_lib.baseboard_fab2(sch_1):page52_i138:vss(15)" )
			)
			( pin "J6L2.248"
				( objectStatus "@baseboard_fab2_lib.baseboard_fab2(sch_1):page52_i138:vss(16)" )
			)
			( pin "J6L2.246"
				( objectStatus "@baseboard_fab2_lib.baseboard_fab2(sch_1):page52_i138:vss(17)" )
			)
			( pin "J6L2.243"
				( objectStatus "@baseboard_fab2_lib.baseboard_fab2(sch_1):page52_i138:vss(18)" )
			)
			( pin "J6L2.241"
				( objectStatus "@baseboard_fab2_lib.baseboard_fab2(sch_1):page52_i138:vss(19)" )
			)
			( pin "J6L2.239"
				( objectStatus "@baseboard_fab2_lib.baseboard_fab2(sch_1):page52_i138:vss(20)" )
			)
			( pin "J6L2.202"
				( objectStatus "@baseboard_fab2_lib.baseboard_fab2(sch_1):page52_i138:vss(21)" )
			)
			( pin "J6L2.200"
				( objectStatus "@baseboard_fab2_lib.baseboard_fab2(sch_1):page52_i138:vss(22)" )
			)
			( pin "J6L2.198"
				( objectStatus "@baseboard_fab2_lib.baseboard_fab2(sch_1):page52_i138:vss(23)" )
			)
			( pin "J6L2.195"
				( objectStatus "@baseboard_fab2_lib.baseboard_fab2(sch_1):page52_i138:vss(24)" )
			)
			( pin "J6L2.193"
				( objectStatus "@baseboard_fab2_lib.baseboard_fab2(sch_1):page52_i138:vss(25)" )
			)
			( pin "J6L2.191"
				( objectStatus "@baseboard_fab2_lib.baseboard_fab2(sch_1):page52_i138:vss(26)" )
			)
			( pin "J6L2.189"
				( objectStatus "@baseboard_fab2_lib.baseboard_fab2(sch_1):page52_i138:vss(27)" )
			)
			( pin "J6L2.187"
				( objectStatus "@baseboard_fab2_lib.baseboard_fab2(sch_1):page52_i138:vss(28)" )
			)
			( pin "J6L2.184"
				( objectStatus "@baseboard_fab2_lib.baseboard_fab2(sch_1):page52_i138:vss(29)" )
			)
			( pin "J6L2.182"
				( objectStatus "@baseboard_fab2_lib.baseboard_fab2(sch_1):page52_i138:vss(30)" )
			)
			( pin "J6L2.180"
				( objectStatus "@baseboard_fab2_lib.baseboard_fab2(sch_1):page52_i138:vss(31)" )
			)
			( pin "J6L2.178"
				( objectStatus "@baseboard_fab2_lib.baseboard_fab2(sch_1):page52_i138:vss(32)" )
			)
			( pin "J6L2.176"
				( objectStatus "@baseboard_fab2_lib.baseboard_fab2(sch_1):page52_i138:vss(33)" )
			)
			( pin "J6L2.173"
				( objectStatus "@baseboard_fab2_lib.baseboard_fab2(sch_1):page52_i138:vss(34)" )
			)
			( pin "J6L2.171"
				( objectStatus "@baseboard_fab2_lib.baseboard_fab2(sch_1):page52_i138:vss(35)" )
			)
			( pin "J6L2.169"
				( objectStatus "@baseboard_fab2_lib.baseboard_fab2(sch_1):page52_i138:vss(36)" )
			)
			( pin "J6L2.167"
				( objectStatus "@baseboard_fab2_lib.baseboard_fab2(sch_1):page52_i138:vss(37)" )
			)
			( pin "J6L2.165"
				( objectStatus "@baseboard_fab2_lib.baseboard_fab2(sch_1):page52_i138:vss(38)" )
			)
			( pin "J6L2.162"
				( objectStatus "@baseboard_fab2_lib.baseboard_fab2(sch_1):page52_i138:vss(39)" )
			)
			( pin "J6L2.160"
				( objectStatus "@baseboard_fab2_lib.baseboard_fab2(sch_1):page52_i138:vss(40)" )
			)
			( pin "J6L2.158"
				( objectStatus "@baseboard_fab2_lib.baseboard_fab2(sch_1):page52_i138:vss(41)" )
			)
			( pin "J6L2.156"
				( objectStatus "@baseboard_fab2_lib.baseboard_fab2(sch_1):page52_i138:vss(42)" )
			)
			( pin "J6L2.154"
				( objectStatus "@baseboard_fab2_lib.baseboard_fab2(sch_1):page52_i138:vss(43)" )
			)
			( pin "J6L2.151"
				( objectStatus "@baseboard_fab2_lib.baseboard_fab2(sch_1):page52_i138:vss(44)" )
			)
			( pin "J6L2.149"
				( objectStatus "@baseboard_fab2_lib.baseboard_fab2(sch_1):page52_i138:vss(45)" )
			)
			( pin "J6L2.147"
				( objectStatus "@baseboard_fab2_lib.baseboard_fab2(sch_1):page52_i138:vss(46)" )
			)
			( pin "J6L2.138"
				( objectStatus "@baseboard_fab2_lib.baseboard_fab2(sch_1):page52_i138:vss(47)" )
			)
			( pin "J6L2.136"
				( objectStatus "@baseboard_fab2_lib.baseboard_fab2(sch_1):page52_i138:vss(48)" )
			)
			( pin "J6L2.134"
				( objectStatus "@baseboard_fab2_lib.baseboard_fab2(sch_1):page52_i138:vss(49)" )
			)
			( pin "J6L2.131"
				( objectStatus "@baseboard_fab2_lib.baseboard_fab2(sch_1):page52_i138:vss(50)" )
			)
			( pin "J6L2.129"
				( objectStatus "@baseboard_fab2_lib.baseboard_fab2(sch_1):page52_i138:vss(51)" )
			)
			( pin "J6L2.127"
				( objectStatus "@baseboard_fab2_lib.baseboard_fab2(sch_1):page52_i138:vss(52)" )
			)
			( pin "J6L2.125"
				( objectStatus "@baseboard_fab2_lib.baseboard_fab2(sch_1):page52_i138:vss(53)" )
			)
			( pin "J6L2.123"
				( objectStatus "@baseboard_fab2_lib.baseboard_fab2(sch_1):page52_i138:vss(54)" )
			)
			( pin "J6L2.120"
				( objectStatus "@baseboard_fab2_lib.baseboard_fab2(sch_1):page52_i138:vss(55)" )
			)
			( pin "J6L2.118"
				( objectStatus "@baseboard_fab2_lib.baseboard_fab2(sch_1):page52_i138:vss(56)" )
			)
			( pin "J6L2.116"
				( objectStatus "@baseboard_fab2_lib.baseboard_fab2(sch_1):page52_i138:vss(57)" )
			)
			( pin "J6L2.114"
				( objectStatus "@baseboard_fab2_lib.baseboard_fab2(sch_1):page52_i138:vss(58)" )
			)
			( pin "J6L2.112"
				( objectStatus "@baseboard_fab2_lib.baseboard_fab2(sch_1):page52_i138:vss(59)" )
			)
			( pin "J6L2.109"
				( objectStatus "@baseboard_fab2_lib.baseboard_fab2(sch_1):page52_i138:vss(60)" )
			)
			( pin "J6L2.107"
				( objectStatus "@baseboard_fab2_lib.baseboard_fab2(sch_1):page52_i138:vss(61)" )
			)
			( pin "J6L2.105"
				( objectStatus "@baseboard_fab2_lib.baseboard_fab2(sch_1):page52_i138:vss(62)" )
			)
			( pin "J6L2.103"
				( objectStatus "@baseboard_fab2_lib.baseboard_fab2(sch_1):page52_i138:vss(63)" )
			)
			( pin "J6L2.101"
				( objectStatus "@baseboard_fab2_lib.baseboard_fab2(sch_1):page52_i138:vss(64)" )
			)
			( pin "J6L2.98"
				( objectStatus "@baseboard_fab2_lib.baseboard_fab2(sch_1):page52_i138:vss(65)" )
			)
			( pin "J6L2.96"
				( objectStatus "@baseboard_fab2_lib.baseboard_fab2(sch_1):page52_i138:vss(66)" )
			)
			( pin "J6L2.94"
				( objectStatus "@baseboard_fab2_lib.baseboard_fab2(sch_1):page52_i138:vss(67)" )
			)
			( pin "J6L2.57"
				( objectStatus "@baseboard_fab2_lib.baseboard_fab2(sch_1):page52_i138:vss(68)" )
			)
			( pin "J6L2.55"
				( objectStatus "@baseboard_fab2_lib.baseboard_fab2(sch_1):page52_i138:vss(69)" )
			)
			( pin "J6L2.53"
				( objectStatus "@baseboard_fab2_lib.baseboard_fab2(sch_1):page52_i138:vss(70)" )
			)
			( pin "J6L2.50"
				( objectStatus "@baseboard_fab2_lib.baseboard_fab2(sch_1):page52_i138:vss(71)" )
			)
			( pin "J6L2.48"
				( objectStatus "@baseboard_fab2_lib.baseboard_fab2(sch_1):page52_i138:vss(72)" )
			)
			( pin "J6L2.46"
				( objectStatus "@baseboard_fab2_lib.baseboard_fab2(sch_1):page52_i138:vss(73)" )
			)
			( pin "J6L2.44"
				( objectStatus "@baseboard_fab2_lib.baseboard_fab2(sch_1):page52_i138:vss(74)" )
			)
			( pin "J6L2.42"
				( objectStatus "@baseboard_fab2_lib.baseboard_fab2(sch_1):page52_i138:vss(75)" )
			)
			( pin "J6L2.39"
				( objectStatus "@baseboard_fab2_lib.baseboard_fab2(sch_1):page52_i138:vss(76)" )
			)
			( pin "J6L2.37"
				( objectStatus "@baseboard_fab2_lib.baseboard_fab2(sch_1):page52_i138:vss(77)" )
			)
			( pin "J6L2.35"
				( objectStatus "@baseboard_fab2_lib.baseboard_fab2(sch_1):page52_i138:vss(78)" )
			)
			( pin "J6L2.33"
				( objectStatus "@baseboard_fab2_lib.baseboard_fab2(sch_1):page52_i138:vss(79)" )
			)
			( pin "J6L2.31"
				( objectStatus "@baseboard_fab2_lib.baseboard_fab2(sch_1):page52_i138:vss(80)" )
			)
			( pin "J6L2.28"
				( objectStatus "@baseboard_fab2_lib.baseboard_fab2(sch_1):page52_i138:vss(81)" )
			)
			( pin "J6L2.26"
				( objectStatus "@baseboard_fab2_lib.baseboard_fab2(sch_1):page52_i138:vss(82)" )
			)
			( pin "J6L2.24"
				( objectStatus "@baseboard_fab2_lib.baseboard_fab2(sch_1):page52_i138:vss(83)" )
			)
			( pin "J6L2.22"
				( objectStatus "@baseboard_fab2_lib.baseboard_fab2(sch_1):page52_i138:vss(84)" )
			)
			( pin "J6L2.20"
				( objectStatus "@baseboard_fab2_lib.baseboard_fab2(sch_1):page52_i138:vss(85)" )
			)
			( pin "J6L2.17"
				( objectStatus "@baseboard_fab2_lib.baseboard_fab2(sch_1):page52_i138:vss(86)" )
			)
			( pin "J6L2.15"
				( objectStatus "@baseboard_fab2_lib.baseboard_fab2(sch_1):page52_i138:vss(87)" )
			)
			( pin "J6L2.13"
				( objectStatus "@baseboard_fab2_lib.baseboard_fab2(sch_1):page52_i138:vss(88)" )
			)
			( pin "J6L2.11"
				( objectStatus "@baseboard_fab2_lib.baseboard_fab2(sch_1):page52_i138:vss(89)" )
			)
			( pin "J6L2.9"
				( objectStatus "@baseboard_fab2_lib.baseboard_fab2(sch_1):page52_i138:vss(90)" )
			)
			( pin "J6L2.6"
				( objectStatus "@baseboard_fab2_lib.baseboard_fab2(sch_1):page52_i138:vss(91)" )
			)
			( pin "J6L2.4"
				( objectStatus "@baseboard_fab2_lib.baseboard_fab2(sch_1):page52_i138:vss(92)" )
			)
			( pin "J6L2.2"
				( objectStatus "@baseboard_fab2_lib.baseboard_fab2(sch_1):page52_i138:vss(93)" )
			)
			( pin "J4A1.283"
				( objectStatus "@baseboard_fab2_lib.baseboard_fab2(sch_1):page53_i43:vss(0)" )
			)
			( pin "J4A1.281"
				( objectStatus "@baseboard_fab2_lib.baseboard_fab2(sch_1):page53_i43:vss(1)" )
			)
			( pin "J4A1.279"
				( objectStatus "@baseboard_fab2_lib.baseboard_fab2(sch_1):page53_i43:vss(2)" )
			)
			( pin "J4A1.276"
				( objectStatus "@baseboard_fab2_lib.baseboard_fab2(sch_1):page53_i43:vss(3)" )
			)
			( pin "J4A1.274"
				( objectStatus "@baseboard_fab2_lib.baseboard_fab2(sch_1):page53_i43:vss(4)" )
			)
			( pin "J4A1.272"
				( objectStatus "@baseboard_fab2_lib.baseboard_fab2(sch_1):page53_i43:vss(5)" )
			)
			( pin "J4A1.270"
				( objectStatus "@baseboard_fab2_lib.baseboard_fab2(sch_1):page53_i43:vss(6)" )
			)
			( pin "J4A1.268"
				( objectStatus "@baseboard_fab2_lib.baseboard_fab2(sch_1):page53_i43:vss(7)" )
			)
			( pin "J4A1.265"
				( objectStatus "@baseboard_fab2_lib.baseboard_fab2(sch_1):page53_i43:vss(8)" )
			)
			( pin "J4A1.263"
				( objectStatus "@baseboard_fab2_lib.baseboard_fab2(sch_1):page53_i43:vss(9)" )
			)
			( pin "J4A1.261"
				( objectStatus "@baseboard_fab2_lib.baseboard_fab2(sch_1):page53_i43:vss(10)" )
			)
			( pin "J4A1.259"
				( objectStatus "@baseboard_fab2_lib.baseboard_fab2(sch_1):page53_i43:vss(11)" )
			)
			( pin "J4A1.257"
				( objectStatus "@baseboard_fab2_lib.baseboard_fab2(sch_1):page53_i43:vss(12)" )
			)
			( pin "J4A1.254"
				( objectStatus "@baseboard_fab2_lib.baseboard_fab2(sch_1):page53_i43:vss(13)" )
			)
			( pin "J4A1.252"
				( objectStatus "@baseboard_fab2_lib.baseboard_fab2(sch_1):page53_i43:vss(14)" )
			)
			( pin "J4A1.250"
				( objectStatus "@baseboard_fab2_lib.baseboard_fab2(sch_1):page53_i43:vss(15)" )
			)
			( pin "J4A1.248"
				( objectStatus "@baseboard_fab2_lib.baseboard_fab2(sch_1):page53_i43:vss(16)" )
			)
			( pin "J4A1.246"
				( objectStatus "@baseboard_fab2_lib.baseboard_fab2(sch_1):page53_i43:vss(17)" )
			)
			( pin "J4A1.243"
				( objectStatus "@baseboard_fab2_lib.baseboard_fab2(sch_1):page53_i43:vss(18)" )
			)
			( pin "J4A1.241"
				( objectStatus "@baseboard_fab2_lib.baseboard_fab2(sch_1):page53_i43:vss(19)" )
			)
			( pin "J4A1.239"
				( objectStatus "@baseboard_fab2_lib.baseboard_fab2(sch_1):page53_i43:vss(20)" )
			)
			( pin "J4A1.202"
				( objectStatus "@baseboard_fab2_lib.baseboard_fab2(sch_1):page53_i43:vss(21)" )
			)
			( pin "J4A1.200"
				( objectStatus "@baseboard_fab2_lib.baseboard_fab2(sch_1):page53_i43:vss(22)" )
			)
			( pin "J4A1.198"
				( objectStatus "@baseboard_fab2_lib.baseboard_fab2(sch_1):page53_i43:vss(23)" )
			)
			( pin "J4A1.195"
				( objectStatus "@baseboard_fab2_lib.baseboard_fab2(sch_1):page53_i43:vss(24)" )
			)
			( pin "J4A1.193"
				( objectStatus "@baseboard_fab2_lib.baseboard_fab2(sch_1):page53_i43:vss(25)" )
			)
			( pin "J4A1.191"
				( objectStatus "@baseboard_fab2_lib.baseboard_fab2(sch_1):page53_i43:vss(26)" )
			)
			( pin "J4A1.189"
				( objectStatus "@baseboard_fab2_lib.baseboard_fab2(sch_1):page53_i43:vss(27)" )
			)
			( pin "J4A1.187"
				( objectStatus "@baseboard_fab2_lib.baseboard_fab2(sch_1):page53_i43:vss(28)" )
			)
			( pin "J4A1.184"
				( objectStatus "@baseboard_fab2_lib.baseboard_fab2(sch_1):page53_i43:vss(29)" )
			)
			( pin "J4A1.182"
				( objectStatus "@baseboard_fab2_lib.baseboard_fab2(sch_1):page53_i43:vss(30)" )
			)
			( pin "J4A1.180"
				( objectStatus "@baseboard_fab2_lib.baseboard_fab2(sch_1):page53_i43:vss(31)" )
			)
			( pin "J4A1.178"
				( objectStatus "@baseboard_fab2_lib.baseboard_fab2(sch_1):page53_i43:vss(32)" )
			)
			( pin "J4A1.176"
				( objectStatus "@baseboard_fab2_lib.baseboard_fab2(sch_1):page53_i43:vss(33)" )
			)
			( pin "J4A1.173"
				( objectStatus "@baseboard_fab2_lib.baseboard_fab2(sch_1):page53_i43:vss(34)" )
			)
			( pin "J4A1.171"
				( objectStatus "@baseboard_fab2_lib.baseboard_fab2(sch_1):page53_i43:vss(35)" )
			)
			( pin "J4A1.169"
				( objectStatus "@baseboard_fab2_lib.baseboard_fab2(sch_1):page53_i43:vss(36)" )
			)
			( pin "J4A1.167"
				( objectStatus "@baseboard_fab2_lib.baseboard_fab2(sch_1):page53_i43:vss(37)" )
			)
			( pin "J4A1.165"
				( objectStatus "@baseboard_fab2_lib.baseboard_fab2(sch_1):page53_i43:vss(38)" )
			)
			( pin "J4A1.162"
				( objectStatus "@baseboard_fab2_lib.baseboard_fab2(sch_1):page53_i43:vss(39)" )
			)
			( pin "J4A1.160"
				( objectStatus "@baseboard_fab2_lib.baseboard_fab2(sch_1):page53_i43:vss(40)" )
			)
			( pin "J4A1.158"
				( objectStatus "@baseboard_fab2_lib.baseboard_fab2(sch_1):page53_i43:vss(41)" )
			)
			( pin "J4A1.156"
				( objectStatus "@baseboard_fab2_lib.baseboard_fab2(sch_1):page53_i43:vss(42)" )
			)
			( pin "J4A1.154"
				( objectStatus "@baseboard_fab2_lib.baseboard_fab2(sch_1):page53_i43:vss(43)" )
			)
			( pin "J4A1.151"
				( objectStatus "@baseboard_fab2_lib.baseboard_fab2(sch_1):page53_i43:vss(44)" )
			)
			( pin "J4A1.149"
				( objectStatus "@baseboard_fab2_lib.baseboard_fab2(sch_1):page53_i43:vss(45)" )
			)
			( pin "J4A1.147"
				( objectStatus "@baseboard_fab2_lib.baseboard_fab2(sch_1):page53_i43:vss(46)" )
			)
			( pin "J4A1.138"
				( objectStatus "@baseboard_fab2_lib.baseboard_fab2(sch_1):page53_i43:vss(47)" )
			)
			( pin "J4A1.136"
				( objectStatus "@baseboard_fab2_lib.baseboard_fab2(sch_1):page53_i43:vss(48)" )
			)
			( pin "J4A1.134"
				( objectStatus "@baseboard_fab2_lib.baseboard_fab2(sch_1):page53_i43:vss(49)" )
			)
			( pin "J4A1.131"
				( objectStatus "@baseboard_fab2_lib.baseboard_fab2(sch_1):page53_i43:vss(50)" )
			)
			( pin "J4A1.129"
				( objectStatus "@baseboard_fab2_lib.baseboard_fab2(sch_1):page53_i43:vss(51)" )
			)
			( pin "J4A1.127"
				( objectStatus "@baseboard_fab2_lib.baseboard_fab2(sch_1):page53_i43:vss(52)" )
			)
			( pin "J4A1.125"
				( objectStatus "@baseboard_fab2_lib.baseboard_fab2(sch_1):page53_i43:vss(53)" )
			)
			( pin "J4A1.123"
				( objectStatus "@baseboard_fab2_lib.baseboard_fab2(sch_1):page53_i43:vss(54)" )
			)
			( pin "J4A1.120"
				( objectStatus "@baseboard_fab2_lib.baseboard_fab2(sch_1):page53_i43:vss(55)" )
			)
			( pin "J4A1.118"
				( objectStatus "@baseboard_fab2_lib.baseboard_fab2(sch_1):page53_i43:vss(56)" )
			)
			( pin "J4A1.116"
				( objectStatus "@baseboard_fab2_lib.baseboard_fab2(sch_1):page53_i43:vss(57)" )
			)
			( pin "J4A1.114"
				( objectStatus "@baseboard_fab2_lib.baseboard_fab2(sch_1):page53_i43:vss(58)" )
			)
			( pin "J4A1.112"
				( objectStatus "@baseboard_fab2_lib.baseboard_fab2(sch_1):page53_i43:vss(59)" )
			)
			( pin "J4A1.109"
				( objectStatus "@baseboard_fab2_lib.baseboard_fab2(sch_1):page53_i43:vss(60)" )
			)
			( pin "J4A1.107"
				( objectStatus "@baseboard_fab2_lib.baseboard_fab2(sch_1):page53_i43:vss(61)" )
			)
			( pin "J4A1.105"
				( objectStatus "@baseboard_fab2_lib.baseboard_fab2(sch_1):page53_i43:vss(62)" )
			)
			( pin "J4A1.103"
				( objectStatus "@baseboard_fab2_lib.baseboard_fab2(sch_1):page53_i43:vss(63)" )
			)
			( pin "J4A1.101"
				( objectStatus "@baseboard_fab2_lib.baseboard_fab2(sch_1):page53_i43:vss(64)" )
			)
			( pin "J4A1.98"
				( objectStatus "@baseboard_fab2_lib.baseboard_fab2(sch_1):page53_i43:vss(65)" )
			)
			( pin "J4A1.96"
				( objectStatus "@baseboard_fab2_lib.baseboard_fab2(sch_1):page53_i43:vss(66)" )
			)
			( pin "J4A1.94"
				( objectStatus "@baseboard_fab2_lib.baseboard_fab2(sch_1):page53_i43:vss(67)" )
			)
			( pin "J4A1.57"
				( objectStatus "@baseboard_fab2_lib.baseboard_fab2(sch_1):page53_i43:vss(68)" )
			)
			( pin "J4A1.55"
				( objectStatus "@baseboard_fab2_lib.baseboard_fab2(sch_1):page53_i43:vss(69)" )
			)
			( pin "J4A1.53"
				( objectStatus "@baseboard_fab2_lib.baseboard_fab2(sch_1):page53_i43:vss(70)" )
			)
			( pin "J4A1.50"
				( objectStatus "@baseboard_fab2_lib.baseboard_fab2(sch_1):page53_i43:vss(71)" )
			)
			( pin "J4A1.48"
				( objectStatus "@baseboard_fab2_lib.baseboard_fab2(sch_1):page53_i43:vss(72)" )
			)
			( pin "J4A1.46"
				( objectStatus "@baseboard_fab2_lib.baseboard_fab2(sch_1):page53_i43:vss(73)" )
			)
			( pin "J4A1.44"
				( objectStatus "@baseboard_fab2_lib.baseboard_fab2(sch_1):page53_i43:vss(74)" )
			)
			( pin "J4A1.42"
				( objectStatus "@baseboard_fab2_lib.baseboard_fab2(sch_1):page53_i43:vss(75)" )
			)
			( pin "J4A1.39"
				( objectStatus "@baseboard_fab2_lib.baseboard_fab2(sch_1):page53_i43:vss(76)" )
			)
			( pin "J4A1.37"
				( objectStatus "@baseboard_fab2_lib.baseboard_fab2(sch_1):page53_i43:vss(77)" )
			)
			( pin "J4A1.35"
				( objectStatus "@baseboard_fab2_lib.baseboard_fab2(sch_1):page53_i43:vss(78)" )
			)
			( pin "J4A1.33"
				( objectStatus "@baseboard_fab2_lib.baseboard_fab2(sch_1):page53_i43:vss(79)" )
			)
			( pin "J4A1.31"
				( objectStatus "@baseboard_fab2_lib.baseboard_fab2(sch_1):page53_i43:vss(80)" )
			)
			( pin "J4A1.28"
				( objectStatus "@baseboard_fab2_lib.baseboard_fab2(sch_1):page53_i43:vss(81)" )
			)
			( pin "J4A1.26"
				( objectStatus "@baseboard_fab2_lib.baseboard_fab2(sch_1):page53_i43:vss(82)" )
			)
			( pin "J4A1.24"
				( objectStatus "@baseboard_fab2_lib.baseboard_fab2(sch_1):page53_i43:vss(83)" )
			)
			( pin "J4A1.22"
				( objectStatus "@baseboard_fab2_lib.baseboard_fab2(sch_1):page53_i43:vss(84)" )
			)
			( pin "J4A1.20"
				( objectStatus "@baseboard_fab2_lib.baseboard_fab2(sch_1):page53_i43:vss(85)" )
			)
			( pin "J4A1.17"
				( objectStatus "@baseboard_fab2_lib.baseboard_fab2(sch_1):page53_i43:vss(86)" )
			)
			( pin "J4A1.15"
				( objectStatus "@baseboard_fab2_lib.baseboard_fab2(sch_1):page53_i43:vss(87)" )
			)
			( pin "J4A1.13"
				( objectStatus "@baseboard_fab2_lib.baseboard_fab2(sch_1):page53_i43:vss(88)" )
			)
			( pin "J4A1.11"
				( objectStatus "@baseboard_fab2_lib.baseboard_fab2(sch_1):page53_i43:vss(89)" )
			)
			( pin "J4A1.9"
				( objectStatus "@baseboard_fab2_lib.baseboard_fab2(sch_1):page53_i43:vss(90)" )
			)
			( pin "J4A1.6"
				( objectStatus "@baseboard_fab2_lib.baseboard_fab2(sch_1):page53_i43:vss(91)" )
			)
			( pin "J4A1.4"
				( objectStatus "@baseboard_fab2_lib.baseboard_fab2(sch_1):page53_i43:vss(92)" )
			)
			( pin "J4A1.2"
				( objectStatus "@baseboard_fab2_lib.baseboard_fab2(sch_1):page53_i43:vss(93)" )
			)
			( pin "J4A1.152"
				( objectStatus "@baseboard_fab2_lib.baseboard_fab2(sch_1):page53_i66:dqs0n" )
			)
			( pin "J4A1.153"
				( objectStatus "@baseboard_fab2_lib.baseboard_fab2(sch_1):page53_i66:dqs0p" )
			)
			( pin "J4A1.163"
				( objectStatus "@baseboard_fab2_lib.baseboard_fab2(sch_1):page53_i66:dqs1n" )
			)
			( pin "J4A1.164"
				( objectStatus "@baseboard_fab2_lib.baseboard_fab2(sch_1):page53_i66:dqs1p" )
			)
			( pin "J4A1.174"
				( objectStatus "@baseboard_fab2_lib.baseboard_fab2(sch_1):page53_i66:dqs2n" )
			)
			( pin "J4A1.175"
				( objectStatus "@baseboard_fab2_lib.baseboard_fab2(sch_1):page53_i66:dqs2p" )
			)
			( pin "J4A1.185"
				( objectStatus "@baseboard_fab2_lib.baseboard_fab2(sch_1):page53_i66:dqs3n" )
			)
			( pin "J4A1.186"
				( objectStatus "@baseboard_fab2_lib.baseboard_fab2(sch_1):page53_i66:dqs3p" )
			)
			( pin "J4A1.244"
				( objectStatus "@baseboard_fab2_lib.baseboard_fab2(sch_1):page53_i66:dqs4n" )
			)
			( pin "J4A1.245"
				( objectStatus "@baseboard_fab2_lib.baseboard_fab2(sch_1):page53_i66:dqs4p" )
			)
			( pin "J4A1.255"
				( objectStatus "@baseboard_fab2_lib.baseboard_fab2(sch_1):page53_i66:dqs5n" )
			)
			( pin "J4A1.256"
				( objectStatus "@baseboard_fab2_lib.baseboard_fab2(sch_1):page53_i66:dqs5p" )
			)
			( pin "J4A1.266"
				( objectStatus "@baseboard_fab2_lib.baseboard_fab2(sch_1):page53_i66:dqs6n" )
			)
			( pin "J4A1.267"
				( objectStatus "@baseboard_fab2_lib.baseboard_fab2(sch_1):page53_i66:dqs6p" )
			)
			( pin "J4A1.277"
				( objectStatus "@baseboard_fab2_lib.baseboard_fab2(sch_1):page53_i66:dqs7n" )
			)
			( pin "J4A1.278"
				( objectStatus "@baseboard_fab2_lib.baseboard_fab2(sch_1):page53_i66:dqs7p" )
			)
			( pin "J4A1.196"
				( objectStatus "@baseboard_fab2_lib.baseboard_fab2(sch_1):page53_i66:dqs8n" )
			)
			( pin "J4A1.197"
				( objectStatus "@baseboard_fab2_lib.baseboard_fab2(sch_1):page53_i66:dqs8p" )
			)
			( pin "J4A1.8"
				( objectStatus "@baseboard_fab2_lib.baseboard_fab2(sch_1):page53_i66:dqs9n" )
			)
			( pin "J4A1.7"
				( objectStatus "@baseboard_fab2_lib.baseboard_fab2(sch_1):page53_i66:dqs9p" )
			)
			( pin "J4A1.19"
				( objectStatus "@baseboard_fab2_lib.baseboard_fab2(sch_1):page53_i66:dqs10n" )
			)
			( pin "J4A1.18"
				( objectStatus "@baseboard_fab2_lib.baseboard_fab2(sch_1):page53_i66:dqs10p" )
			)
			( pin "J4A1.30"
				( objectStatus "@baseboard_fab2_lib.baseboard_fab2(sch_1):page53_i66:dqs11n" )
			)
			( pin "J4A1.29"
				( objectStatus "@baseboard_fab2_lib.baseboard_fab2(sch_1):page53_i66:dqs11p" )
			)
			( pin "J4A1.41"
				( objectStatus "@baseboard_fab2_lib.baseboard_fab2(sch_1):page53_i66:dqs12n" )
			)
			( pin "J4A1.40"
				( objectStatus "@baseboard_fab2_lib.baseboard_fab2(sch_1):page53_i66:dqs12p" )
			)
			( pin "J4A1.100"
				( objectStatus "@baseboard_fab2_lib.baseboard_fab2(sch_1):page53_i66:dqs13n" )
			)
			( pin "J4A1.99"
				( objectStatus "@baseboard_fab2_lib.baseboard_fab2(sch_1):page53_i66:dqs13p" )
			)
			( pin "J4A1.111"
				( objectStatus "@baseboard_fab2_lib.baseboard_fab2(sch_1):page53_i66:dqs14n" )
			)
			( pin "J4A1.110"
				( objectStatus "@baseboard_fab2_lib.baseboard_fab2(sch_1):page53_i66:dqs14p" )
			)
			( pin "J4A1.122"
				( objectStatus "@baseboard_fab2_lib.baseboard_fab2(sch_1):page53_i66:dqs15n" )
			)
			( pin "J4A1.121"
				( objectStatus "@baseboard_fab2_lib.baseboard_fab2(sch_1):page53_i66:dqs15p" )
			)
			( pin "J4A1.133"
				( objectStatus "@baseboard_fab2_lib.baseboard_fab2(sch_1):page53_i66:dqs16n" )
			)
			( pin "J4A1.132"
				( objectStatus "@baseboard_fab2_lib.baseboard_fab2(sch_1):page53_i66:dqs16p" )
			)
			( pin "J4A1.52"
				( objectStatus "@baseboard_fab2_lib.baseboard_fab2(sch_1):page53_i66:dqs17n" )
			)
			( pin "J4A1.51"
				( objectStatus "@baseboard_fab2_lib.baseboard_fab2(sch_1):page53_i66:dqs17p" )
			)
			( pin "J4A1.79"
				( objectStatus "@baseboard_fab2_lib.baseboard_fab2(sch_1):page53_i111:a0" )
			)
			( pin "J4A1.72"
				( objectStatus "@baseboard_fab2_lib.baseboard_fab2(sch_1):page53_i111:a1" )
			)
			( pin "J4A1.216"
				( objectStatus "@baseboard_fab2_lib.baseboard_fab2(sch_1):page53_i111:a2" )
			)
			( pin "J4A1.71"
				( objectStatus "@baseboard_fab2_lib.baseboard_fab2(sch_1):page53_i111:a3" )
			)
			( pin "J4A1.214"
				( objectStatus "@baseboard_fab2_lib.baseboard_fab2(sch_1):page53_i111:a4" )
			)
			( pin "J4A1.213"
				( objectStatus "@baseboard_fab2_lib.baseboard_fab2(sch_1):page53_i111:a5" )
			)
			( pin "J4A1.69"
				( objectStatus "@baseboard_fab2_lib.baseboard_fab2(sch_1):page53_i111:a6" )
			)
			( pin "J4A1.211"
				( objectStatus "@baseboard_fab2_lib.baseboard_fab2(sch_1):page53_i111:a7" )
			)
			( pin "J4A1.68"
				( objectStatus "@baseboard_fab2_lib.baseboard_fab2(sch_1):page53_i111:a8" )
			)
			( pin "J4A1.66"
				( objectStatus "@baseboard_fab2_lib.baseboard_fab2(sch_1):page53_i111:a9" )
			)
			( pin "J4A1.225"
				( objectStatus "@baseboard_fab2_lib.baseboard_fab2(sch_1):page53_i111:a10" )
			)
			( pin "J4A1.210"
				( objectStatus "@baseboard_fab2_lib.baseboard_fab2(sch_1):page53_i111:a11" )
			)
			( pin "J4A1.65"
				( objectStatus "@baseboard_fab2_lib.baseboard_fab2(sch_1):page53_i111:a12" )
			)
			( pin "J4A1.232"
				( objectStatus "@baseboard_fab2_lib.baseboard_fab2(sch_1):page53_i111:a13" )
			)
			( pin "J4A1.228"
				( objectStatus "@baseboard_fab2_lib.baseboard_fab2(sch_1):page53_i111:a14_we_n" )
			)
			( pin "J4A1.86"
				( objectStatus "@baseboard_fab2_lib.baseboard_fab2(sch_1):page53_i111:a15_cas_n" )
			)
			( pin "J4A1.82"
				( objectStatus "@baseboard_fab2_lib.baseboard_fab2(sch_1):page53_i111:a16_ras_n" )
			)
			( pin "J4A1.234"
				( objectStatus "@baseboard_fab2_lib.baseboard_fab2(sch_1):page53_i111:a17" )
			)
			( pin "J4A1.62"
				( objectStatus "@baseboard_fab2_lib.baseboard_fab2(sch_1):page53_i111:act_n" )
			)
			( pin "J4A1.208"
				( objectStatus "@baseboard_fab2_lib.baseboard_fab2(sch_1):page53_i111:alert_n" )
			)
			( pin "J4A1.81"
				( objectStatus "@baseboard_fab2_lib.baseboard_fab2(sch_1):page53_i111:ba(0)" )
			)
			( pin "J4A1.224"
				( objectStatus "@baseboard_fab2_lib.baseboard_fab2(sch_1):page53_i111:ba(1)" )
			)
			( pin "J4A1.63"
				( objectStatus "@baseboard_fab2_lib.baseboard_fab2(sch_1):page53_i111:bg(0)" )
			)
			( pin "J4A1.207"
				( objectStatus "@baseboard_fab2_lib.baseboard_fab2(sch_1):page53_i111:bg(1)" )
			)
			( pin "J4A1.235"
				( objectStatus "@baseboard_fab2_lib.baseboard_fab2(sch_1):page53_i111:c(2)" )
			)
			( pin "J4A1.49"
				( objectStatus "@baseboard_fab2_lib.baseboard_fab2(sch_1):page53_i111:cb(0)" )
			)
			( pin "J4A1.194"
				( objectStatus "@baseboard_fab2_lib.baseboard_fab2(sch_1):page53_i111:cb(1)" )
			)
			( pin "J4A1.56"
				( objectStatus "@baseboard_fab2_lib.baseboard_fab2(sch_1):page53_i111:cb(2)" )
			)
			( pin "J4A1.201"
				( objectStatus "@baseboard_fab2_lib.baseboard_fab2(sch_1):page53_i111:cb(3)" )
			)
			( pin "J4A1.47"
				( objectStatus "@baseboard_fab2_lib.baseboard_fab2(sch_1):page53_i111:cb(4)" )
			)
			( pin "J4A1.192"
				( objectStatus "@baseboard_fab2_lib.baseboard_fab2(sch_1):page53_i111:cb(5)" )
			)
			( pin "J4A1.54"
				( objectStatus "@baseboard_fab2_lib.baseboard_fab2(sch_1):page53_i111:cb(6)" )
			)
			( pin "J4A1.199"
				( objectStatus "@baseboard_fab2_lib.baseboard_fab2(sch_1):page53_i111:cb(7)" )
			)
			( pin "J4A1.75"
				( objectStatus "@baseboard_fab2_lib.baseboard_fab2(sch_1):page53_i111:ck0n" )
			)
			( pin "J4A1.74"
				( objectStatus "@baseboard_fab2_lib.baseboard_fab2(sch_1):page53_i111:ck0p" )
			)
			( pin "J4A1.219"
				( objectStatus "@baseboard_fab2_lib.baseboard_fab2(sch_1):page53_i111:ck1n" )
			)
			( pin "J4A1.218"
				( objectStatus "@baseboard_fab2_lib.baseboard_fab2(sch_1):page53_i111:ck1p" )
			)
			( pin "J4A1.60"
				( objectStatus "@baseboard_fab2_lib.baseboard_fab2(sch_1):page53_i111:cke(0)" )
			)
			( pin "J4A1.203"
				( objectStatus "@baseboard_fab2_lib.baseboard_fab2(sch_1):page53_i111:cke(1)" )
			)
			( pin "J4A1.5"
				( objectStatus "@baseboard_fab2_lib.baseboard_fab2(sch_1):page53_i111:dq(0)" )
			)
			( pin "J4A1.150"
				( objectStatus "@baseboard_fab2_lib.baseboard_fab2(sch_1):page53_i111:dq(1)" )
			)
			( pin "J4A1.12"
				( objectStatus "@baseboard_fab2_lib.baseboard_fab2(sch_1):page53_i111:dq(2)" )
			)
			( pin "J4A1.157"
				( objectStatus "@baseboard_fab2_lib.baseboard_fab2(sch_1):page53_i111:dq(3)" )
			)
			( pin "J4A1.3"
				( objectStatus "@baseboard_fab2_lib.baseboard_fab2(sch_1):page53_i111:dq(4)" )
			)
			( pin "J4A1.148"
				( objectStatus "@baseboard_fab2_lib.baseboard_fab2(sch_1):page53_i111:dq(5)" )
			)
			( pin "J4A1.10"
				( objectStatus "@baseboard_fab2_lib.baseboard_fab2(sch_1):page53_i111:dq(6)" )
			)
			( pin "J4A1.155"
				( objectStatus "@baseboard_fab2_lib.baseboard_fab2(sch_1):page53_i111:dq(7)" )
			)
			( pin "J4A1.16"
				( objectStatus "@baseboard_fab2_lib.baseboard_fab2(sch_1):page53_i111:dq(8)" )
			)
			( pin "J4A1.161"
				( objectStatus "@baseboard_fab2_lib.baseboard_fab2(sch_1):page53_i111:dq(9)" )
			)
			( pin "J4A1.23"
				( objectStatus "@baseboard_fab2_lib.baseboard_fab2(sch_1):page53_i111:dq(10)" )
			)
			( pin "J4A1.168"
				( objectStatus "@baseboard_fab2_lib.baseboard_fab2(sch_1):page53_i111:dq(11)" )
			)
			( pin "J4A1.14"
				( objectStatus "@baseboard_fab2_lib.baseboard_fab2(sch_1):page53_i111:dq(12)" )
			)
			( pin "J4A1.159"
				( objectStatus "@baseboard_fab2_lib.baseboard_fab2(sch_1):page53_i111:dq(13)" )
			)
			( pin "J4A1.21"
				( objectStatus "@baseboard_fab2_lib.baseboard_fab2(sch_1):page53_i111:dq(14)" )
			)
			( pin "J4A1.166"
				( objectStatus "@baseboard_fab2_lib.baseboard_fab2(sch_1):page53_i111:dq(15)" )
			)
			( pin "J4A1.27"
				( objectStatus "@baseboard_fab2_lib.baseboard_fab2(sch_1):page53_i111:dq(16)" )
			)
			( pin "J4A1.172"
				( objectStatus "@baseboard_fab2_lib.baseboard_fab2(sch_1):page53_i111:dq(17)" )
			)
			( pin "J4A1.34"
				( objectStatus "@baseboard_fab2_lib.baseboard_fab2(sch_1):page53_i111:dq(18)" )
			)
			( pin "J4A1.179"
				( objectStatus "@baseboard_fab2_lib.baseboard_fab2(sch_1):page53_i111:dq(19)" )
			)
			( pin "J4A1.25"
				( objectStatus "@baseboard_fab2_lib.baseboard_fab2(sch_1):page53_i111:dq(20)" )
			)
			( pin "J4A1.170"
				( objectStatus "@baseboard_fab2_lib.baseboard_fab2(sch_1):page53_i111:dq(21)" )
			)
			( pin "J4A1.32"
				( objectStatus "@baseboard_fab2_lib.baseboard_fab2(sch_1):page53_i111:dq(22)" )
			)
			( pin "J4A1.177"
				( objectStatus "@baseboard_fab2_lib.baseboard_fab2(sch_1):page53_i111:dq(23)" )
			)
			( pin "J4A1.38"
				( objectStatus "@baseboard_fab2_lib.baseboard_fab2(sch_1):page53_i111:dq(24)" )
			)
			( pin "J4A1.183"
				( objectStatus "@baseboard_fab2_lib.baseboard_fab2(sch_1):page53_i111:dq(25)" )
			)
			( pin "J4A1.45"
				( objectStatus "@baseboard_fab2_lib.baseboard_fab2(sch_1):page53_i111:dq(26)" )
			)
			( pin "J4A1.190"
				( objectStatus "@baseboard_fab2_lib.baseboard_fab2(sch_1):page53_i111:dq(27)" )
			)
			( pin "J4A1.36"
				( objectStatus "@baseboard_fab2_lib.baseboard_fab2(sch_1):page53_i111:dq(28)" )
			)
			( pin "J4A1.181"
				( objectStatus "@baseboard_fab2_lib.baseboard_fab2(sch_1):page53_i111:dq(29)" )
			)
			( pin "J4A1.43"
				( objectStatus "@baseboard_fab2_lib.baseboard_fab2(sch_1):page53_i111:dq(30)" )
			)
			( pin "J4A1.188"
				( objectStatus "@baseboard_fab2_lib.baseboard_fab2(sch_1):page53_i111:dq(31)" )
			)
			( pin "J4A1.97"
				( objectStatus "@baseboard_fab2_lib.baseboard_fab2(sch_1):page53_i111:dq(32)" )
			)
			( pin "J4A1.242"
				( objectStatus "@baseboard_fab2_lib.baseboard_fab2(sch_1):page53_i111:dq(33)" )
			)
			( pin "J4A1.104"
				( objectStatus "@baseboard_fab2_lib.baseboard_fab2(sch_1):page53_i111:dq(34)" )
			)
			( pin "J4A1.249"
				( objectStatus "@baseboard_fab2_lib.baseboard_fab2(sch_1):page53_i111:dq(35)" )
			)
			( pin "J4A1.95"
				( objectStatus "@baseboard_fab2_lib.baseboard_fab2(sch_1):page53_i111:dq(36)" )
			)
			( pin "J4A1.240"
				( objectStatus "@baseboard_fab2_lib.baseboard_fab2(sch_1):page53_i111:dq(37)" )
			)
			( pin "J4A1.102"
				( objectStatus "@baseboard_fab2_lib.baseboard_fab2(sch_1):page53_i111:dq(38)" )
			)
			( pin "J4A1.247"
				( objectStatus "@baseboard_fab2_lib.baseboard_fab2(sch_1):page53_i111:dq(39)" )
			)
			( pin "J4A1.108"
				( objectStatus "@baseboard_fab2_lib.baseboard_fab2(sch_1):page53_i111:dq(40)" )
			)
			( pin "J4A1.253"
				( objectStatus "@baseboard_fab2_lib.baseboard_fab2(sch_1):page53_i111:dq(41)" )
			)
			( pin "J4A1.115"
				( objectStatus "@baseboard_fab2_lib.baseboard_fab2(sch_1):page53_i111:dq(42)" )
			)
			( pin "J4A1.260"
				( objectStatus "@baseboard_fab2_lib.baseboard_fab2(sch_1):page53_i111:dq(43)" )
			)
			( pin "J4A1.106"
				( objectStatus "@baseboard_fab2_lib.baseboard_fab2(sch_1):page53_i111:dq(44)" )
			)
			( pin "J4A1.251"
				( objectStatus "@baseboard_fab2_lib.baseboard_fab2(sch_1):page53_i111:dq(45)" )
			)
			( pin "J4A1.113"
				( objectStatus "@baseboard_fab2_lib.baseboard_fab2(sch_1):page53_i111:dq(46)" )
			)
			( pin "J4A1.258"
				( objectStatus "@baseboard_fab2_lib.baseboard_fab2(sch_1):page53_i111:dq(47)" )
			)
			( pin "J4A1.119"
				( objectStatus "@baseboard_fab2_lib.baseboard_fab2(sch_1):page53_i111:dq(48)" )
			)
			( pin "J4A1.264"
				( objectStatus "@baseboard_fab2_lib.baseboard_fab2(sch_1):page53_i111:dq(49)" )
			)
			( pin "J4A1.126"
				( objectStatus "@baseboard_fab2_lib.baseboard_fab2(sch_1):page53_i111:dq(50)" )
			)
			( pin "J4A1.271"
				( objectStatus "@baseboard_fab2_lib.baseboard_fab2(sch_1):page53_i111:dq(51)" )
			)
			( pin "J4A1.117"
				( objectStatus "@baseboard_fab2_lib.baseboard_fab2(sch_1):page53_i111:dq(52)" )
			)
			( pin "J4A1.262"
				( objectStatus "@baseboard_fab2_lib.baseboard_fab2(sch_1):page53_i111:dq(53)" )
			)
			( pin "J4A1.124"
				( objectStatus "@baseboard_fab2_lib.baseboard_fab2(sch_1):page53_i111:dq(54)" )
			)
			( pin "J4A1.269"
				( objectStatus "@baseboard_fab2_lib.baseboard_fab2(sch_1):page53_i111:dq(55)" )
			)
			( pin "J4A1.130"
				( objectStatus "@baseboard_fab2_lib.baseboard_fab2(sch_1):page53_i111:dq(56)" )
			)
			( pin "J4A1.275"
				( objectStatus "@baseboard_fab2_lib.baseboard_fab2(sch_1):page53_i111:dq(57)" )
			)
			( pin "J4A1.137"
				( objectStatus "@baseboard_fab2_lib.baseboard_fab2(sch_1):page53_i111:dq(58)" )
			)
			( pin "J4A1.282"
				( objectStatus "@baseboard_fab2_lib.baseboard_fab2(sch_1):page53_i111:dq(59)" )
			)
			( pin "J4A1.128"
				( objectStatus "@baseboard_fab2_lib.baseboard_fab2(sch_1):page53_i111:dq(60)" )
			)
			( pin "J4A1.273"
				( objectStatus "@baseboard_fab2_lib.baseboard_fab2(sch_1):page53_i111:dq(61)" )
			)
			( pin "J4A1.135"
				( objectStatus "@baseboard_fab2_lib.baseboard_fab2(sch_1):page53_i111:dq(62)" )
			)
			( pin "J4A1.280"
				( objectStatus "@baseboard_fab2_lib.baseboard_fab2(sch_1):page53_i111:dq(63)" )
			)
			( pin "J4A1.78"
				( objectStatus "@baseboard_fab2_lib.baseboard_fab2(sch_1):page53_i111:event_n" )
			)
			( pin "J4A1.87"
				( objectStatus "@baseboard_fab2_lib.baseboard_fab2(sch_1):page53_i111:odt(0)" )
			)
			( pin "J4A1.91"
				( objectStatus "@baseboard_fab2_lib.baseboard_fab2(sch_1):page53_i111:odt(1)" )
			)
			( pin "J4A1.222"
				( objectStatus "@baseboard_fab2_lib.baseboard_fab2(sch_1):page53_i111:par" )
			)
			( pin "J4A1.58"
				( objectStatus "@baseboard_fab2_lib.baseboard_fab2(sch_1):page53_i111:reset_n" )
			)
			( pin "J4A1.205"
				( objectStatus "@baseboard_fab2_lib.baseboard_fab2(sch_1):page53_i111:rfu(0)" )
			)
			( pin "J4A1.227"
				( objectStatus "@baseboard_fab2_lib.baseboard_fab2(sch_1):page53_i111:rfu(1)" )
			)
			( pin "J4A1.144"
				( objectStatus "@baseboard_fab2_lib.baseboard_fab2(sch_1):page53_i111:rfu(2)" )
			)
			( pin "J4A1.84"
				( objectStatus "@baseboard_fab2_lib.baseboard_fab2(sch_1):page53_i111:s0_n" )
			)
			( pin "J4A1.89"
				( objectStatus "@baseboard_fab2_lib.baseboard_fab2(sch_1):page53_i111:s1_n" )
			)
			( pin "J4A1.93"
				( objectStatus "@baseboard_fab2_lib.baseboard_fab2(sch_1):page53_i111:s2_n_c(0)" )
			)
			( pin "J4A1.237"
				( objectStatus "@baseboard_fab2_lib.baseboard_fab2(sch_1):page53_i111:s3_n_c(1)" )
			)
			( pin "J4A1.139"
				( objectStatus "@baseboard_fab2_lib.baseboard_fab2(sch_1):page53_i111:sa(0)" )
			)
			( pin "J4A1.140"
				( objectStatus "@baseboard_fab2_lib.baseboard_fab2(sch_1):page53_i111:sa(1)" )
			)
			( pin "J4A1.238"
				( objectStatus "@baseboard_fab2_lib.baseboard_fab2(sch_1):page53_i111:sa(2)" )
			)
			( pin "J4A1.230"
				( objectStatus "@baseboard_fab2_lib.baseboard_fab2(sch_1):page53_i111:save_n_nc" )
			)
			( pin "J4A1.141"
				( objectStatus "@baseboard_fab2_lib.baseboard_fab2(sch_1):page53_i111:scl" )
			)
			( pin "J4A1.285"
				( objectStatus "@baseboard_fab2_lib.baseboard_fab2(sch_1):page53_i111:sda" )
			)
			( pin "J4A1.284"
				( objectStatus "@baseboard_fab2_lib.baseboard_fab2(sch_1):page53_i111:vddspd" )
			)
			( pin "J4A1.146"
				( objectStatus "@baseboard_fab2_lib.baseboard_fab2(sch_1):page53_i111:vrefca" )
			)
			( pin "J4A1.145"
				( objectStatus "@baseboard_fab2_lib.baseboard_fab2(sch_1):page53_i171:\12v\(0)" )
			)
			( pin "J4A1.1"
				( objectStatus "@baseboard_fab2_lib.baseboard_fab2(sch_1):page53_i171:\12v\(1)" )
			)
			( pin "J4A1.236"
				( objectStatus "@baseboard_fab2_lib.baseboard_fab2(sch_1):page53_i171:vdd(0)" )
			)
			( pin "J4A1.233"
				( objectStatus "@baseboard_fab2_lib.baseboard_fab2(sch_1):page53_i171:vdd(1)" )
			)
			( pin "J4A1.231"
				( objectStatus "@baseboard_fab2_lib.baseboard_fab2(sch_1):page53_i171:vdd(2)" )
			)
			( pin "J4A1.229"
				( objectStatus "@baseboard_fab2_lib.baseboard_fab2(sch_1):page53_i171:vdd(3)" )
			)
			( pin "J4A1.226"
				( objectStatus "@baseboard_fab2_lib.baseboard_fab2(sch_1):page53_i171:vdd(4)" )
			)
			( pin "J4A1.223"
				( objectStatus "@baseboard_fab2_lib.baseboard_fab2(sch_1):page53_i171:vdd(5)" )
			)
			( pin "J4A1.220"
				( objectStatus "@baseboard_fab2_lib.baseboard_fab2(sch_1):page53_i171:vdd(6)" )
			)
			( pin "J4A1.217"
				( objectStatus "@baseboard_fab2_lib.baseboard_fab2(sch_1):page53_i171:vdd(7)" )
			)
			( pin "J4A1.215"
				( objectStatus "@baseboard_fab2_lib.baseboard_fab2(sch_1):page53_i171:vdd(8)" )
			)
			( pin "J4A1.212"
				( objectStatus "@baseboard_fab2_lib.baseboard_fab2(sch_1):page53_i171:vdd(9)" )
			)
			( pin "J4A1.209"
				( objectStatus "@baseboard_fab2_lib.baseboard_fab2(sch_1):page53_i171:vdd(10)" )
			)
			( pin "J4A1.206"
				( objectStatus "@baseboard_fab2_lib.baseboard_fab2(sch_1):page53_i171:vdd(11)" )
			)
			( pin "J4A1.204"
				( objectStatus "@baseboard_fab2_lib.baseboard_fab2(sch_1):page53_i171:vdd(12)" )
			)
			( pin "J4A1.92"
				( objectStatus "@baseboard_fab2_lib.baseboard_fab2(sch_1):page53_i171:vdd(13)" )
			)
			( pin "J4A1.90"
				( objectStatus "@baseboard_fab2_lib.baseboard_fab2(sch_1):page53_i171:vdd(14)" )
			)
			( pin "J4A1.88"
				( objectStatus "@baseboard_fab2_lib.baseboard_fab2(sch_1):page53_i171:vdd(15)" )
			)
			( pin "J4A1.85"
				( objectStatus "@baseboard_fab2_lib.baseboard_fab2(sch_1):page53_i171:vdd(16)" )
			)
			( pin "J4A1.83"
				( objectStatus "@baseboard_fab2_lib.baseboard_fab2(sch_1):page53_i171:vdd(17)" )
			)
			( pin "J4A1.80"
				( objectStatus "@baseboard_fab2_lib.baseboard_fab2(sch_1):page53_i171:vdd(18)" )
			)
			( pin "J4A1.76"
				( objectStatus "@baseboard_fab2_lib.baseboard_fab2(sch_1):page53_i171:vdd(19)" )
			)
			( pin "J4A1.73"
				( objectStatus "@baseboard_fab2_lib.baseboard_fab2(sch_1):page53_i171:vdd(20)" )
			)
			( pin "J4A1.70"
				( objectStatus "@baseboard_fab2_lib.baseboard_fab2(sch_1):page53_i171:vdd(21)" )
			)
			( pin "J4A1.67"
				( objectStatus "@baseboard_fab2_lib.baseboard_fab2(sch_1):page53_i171:vdd(22)" )
			)
			( pin "J4A1.64"
				( objectStatus "@baseboard_fab2_lib.baseboard_fab2(sch_1):page53_i171:vdd(23)" )
			)
			( pin "J4A1.61"
				( objectStatus "@baseboard_fab2_lib.baseboard_fab2(sch_1):page53_i171:vdd(24)" )
			)
			( pin "J4A1.59"
				( objectStatus "@baseboard_fab2_lib.baseboard_fab2(sch_1):page53_i171:vdd(25)" )
			)
			( pin "J4A1.287"
				( objectStatus "@baseboard_fab2_lib.baseboard_fab2(sch_1):page53_i171:vpp(0)" )
			)
			( pin "J4A1.286"
				( objectStatus "@baseboard_fab2_lib.baseboard_fab2(sch_1):page53_i171:vpp(1)" )
			)
			( pin "J4A1.288"
				( objectStatus "@baseboard_fab2_lib.baseboard_fab2(sch_1):page53_i171:vpp(2)" )
			)
			( pin "J4A1.143"
				( objectStatus "@baseboard_fab2_lib.baseboard_fab2(sch_1):page53_i171:vpp(3)" )
			)
			( pin "J4A1.142"
				( objectStatus "@baseboard_fab2_lib.baseboard_fab2(sch_1):page53_i171:vpp(4)" )
			)
			( pin "J4A1.221"
				( objectStatus "@baseboard_fab2_lib.baseboard_fab2(sch_1):page53_i171:vtt(0)" )
			)
			( pin "J4A1.77"
				( objectStatus "@baseboard_fab2_lib.baseboard_fab2(sch_1):page53_i171:vtt(1)" )
			)
			( pin "C6L1.1"
				( objectStatus "@baseboard_fab2_lib.baseboard_fab2(sch_1):page53_i178:a" )
			)
			( pin "C6L1.2"
				( objectStatus "@baseboard_fab2_lib.baseboard_fab2(sch_1):page53_i178:b" )
			)
			( pin "J6L1.283"
				( objectStatus "@baseboard_fab2_lib.baseboard_fab2(sch_1):page54_i43:vss(0)" )
			)
			( pin "J6L1.281"
				( objectStatus "@baseboard_fab2_lib.baseboard_fab2(sch_1):page54_i43:vss(1)" )
			)
			( pin "J6L1.279"
				( objectStatus "@baseboard_fab2_lib.baseboard_fab2(sch_1):page54_i43:vss(2)" )
			)
			( pin "J6L1.276"
				( objectStatus "@baseboard_fab2_lib.baseboard_fab2(sch_1):page54_i43:vss(3)" )
			)
			( pin "J6L1.274"
				( objectStatus "@baseboard_fab2_lib.baseboard_fab2(sch_1):page54_i43:vss(4)" )
			)
			( pin "J6L1.272"
				( objectStatus "@baseboard_fab2_lib.baseboard_fab2(sch_1):page54_i43:vss(5)" )
			)
			( pin "J6L1.270"
				( objectStatus "@baseboard_fab2_lib.baseboard_fab2(sch_1):page54_i43:vss(6)" )
			)
			( pin "J6L1.268"
				( objectStatus "@baseboard_fab2_lib.baseboard_fab2(sch_1):page54_i43:vss(7)" )
			)
			( pin "J6L1.265"
				( objectStatus "@baseboard_fab2_lib.baseboard_fab2(sch_1):page54_i43:vss(8)" )
			)
			( pin "J6L1.263"
				( objectStatus "@baseboard_fab2_lib.baseboard_fab2(sch_1):page54_i43:vss(9)" )
			)
			( pin "J6L1.261"
				( objectStatus "@baseboard_fab2_lib.baseboard_fab2(sch_1):page54_i43:vss(10)" )
			)
			( pin "J6L1.259"
				( objectStatus "@baseboard_fab2_lib.baseboard_fab2(sch_1):page54_i43:vss(11)" )
			)
			( pin "J6L1.257"
				( objectStatus "@baseboard_fab2_lib.baseboard_fab2(sch_1):page54_i43:vss(12)" )
			)
			( pin "J6L1.254"
				( objectStatus "@baseboard_fab2_lib.baseboard_fab2(sch_1):page54_i43:vss(13)" )
			)
			( pin "J6L1.252"
				( objectStatus "@baseboard_fab2_lib.baseboard_fab2(sch_1):page54_i43:vss(14)" )
			)
			( pin "J6L1.250"
				( objectStatus "@baseboard_fab2_lib.baseboard_fab2(sch_1):page54_i43:vss(15)" )
			)
			( pin "J6L1.248"
				( objectStatus "@baseboard_fab2_lib.baseboard_fab2(sch_1):page54_i43:vss(16)" )
			)
			( pin "J6L1.246"
				( objectStatus "@baseboard_fab2_lib.baseboard_fab2(sch_1):page54_i43:vss(17)" )
			)
			( pin "J6L1.243"
				( objectStatus "@baseboard_fab2_lib.baseboard_fab2(sch_1):page54_i43:vss(18)" )
			)
			( pin "J6L1.241"
				( objectStatus "@baseboard_fab2_lib.baseboard_fab2(sch_1):page54_i43:vss(19)" )
			)
			( pin "J6L1.239"
				( objectStatus "@baseboard_fab2_lib.baseboard_fab2(sch_1):page54_i43:vss(20)" )
			)
			( pin "J6L1.202"
				( objectStatus "@baseboard_fab2_lib.baseboard_fab2(sch_1):page54_i43:vss(21)" )
			)
			( pin "J6L1.200"
				( objectStatus "@baseboard_fab2_lib.baseboard_fab2(sch_1):page54_i43:vss(22)" )
			)
			( pin "J6L1.198"
				( objectStatus "@baseboard_fab2_lib.baseboard_fab2(sch_1):page54_i43:vss(23)" )
			)
			( pin "J6L1.195"
				( objectStatus "@baseboard_fab2_lib.baseboard_fab2(sch_1):page54_i43:vss(24)" )
			)
			( pin "J6L1.193"
				( objectStatus "@baseboard_fab2_lib.baseboard_fab2(sch_1):page54_i43:vss(25)" )
			)
			( pin "J6L1.191"
				( objectStatus "@baseboard_fab2_lib.baseboard_fab2(sch_1):page54_i43:vss(26)" )
			)
			( pin "J6L1.189"
				( objectStatus "@baseboard_fab2_lib.baseboard_fab2(sch_1):page54_i43:vss(27)" )
			)
			( pin "J6L1.187"
				( objectStatus "@baseboard_fab2_lib.baseboard_fab2(sch_1):page54_i43:vss(28)" )
			)
			( pin "J6L1.184"
				( objectStatus "@baseboard_fab2_lib.baseboard_fab2(sch_1):page54_i43:vss(29)" )
			)
			( pin "J6L1.182"
				( objectStatus "@baseboard_fab2_lib.baseboard_fab2(sch_1):page54_i43:vss(30)" )
			)
			( pin "J6L1.180"
				( objectStatus "@baseboard_fab2_lib.baseboard_fab2(sch_1):page54_i43:vss(31)" )
			)
			( pin "J6L1.178"
				( objectStatus "@baseboard_fab2_lib.baseboard_fab2(sch_1):page54_i43:vss(32)" )
			)
			( pin "J6L1.176"
				( objectStatus "@baseboard_fab2_lib.baseboard_fab2(sch_1):page54_i43:vss(33)" )
			)
			( pin "J6L1.173"
				( objectStatus "@baseboard_fab2_lib.baseboard_fab2(sch_1):page54_i43:vss(34)" )
			)
			( pin "J6L1.171"
				( objectStatus "@baseboard_fab2_lib.baseboard_fab2(sch_1):page54_i43:vss(35)" )
			)
			( pin "J6L1.169"
				( objectStatus "@baseboard_fab2_lib.baseboard_fab2(sch_1):page54_i43:vss(36)" )
			)
			( pin "J6L1.167"
				( objectStatus "@baseboard_fab2_lib.baseboard_fab2(sch_1):page54_i43:vss(37)" )
			)
			( pin "J6L1.165"
				( objectStatus "@baseboard_fab2_lib.baseboard_fab2(sch_1):page54_i43:vss(38)" )
			)
			( pin "J6L1.162"
				( objectStatus "@baseboard_fab2_lib.baseboard_fab2(sch_1):page54_i43:vss(39)" )
			)
			( pin "J6L1.160"
				( objectStatus "@baseboard_fab2_lib.baseboard_fab2(sch_1):page54_i43:vss(40)" )
			)
			( pin "J6L1.158"
				( objectStatus "@baseboard_fab2_lib.baseboard_fab2(sch_1):page54_i43:vss(41)" )
			)
			( pin "J6L1.156"
				( objectStatus "@baseboard_fab2_lib.baseboard_fab2(sch_1):page54_i43:vss(42)" )
			)
			( pin "J6L1.154"
				( objectStatus "@baseboard_fab2_lib.baseboard_fab2(sch_1):page54_i43:vss(43)" )
			)
			( pin "J6L1.151"
				( objectStatus "@baseboard_fab2_lib.baseboard_fab2(sch_1):page54_i43:vss(44)" )
			)
			( pin "J6L1.149"
				( objectStatus "@baseboard_fab2_lib.baseboard_fab2(sch_1):page54_i43:vss(45)" )
			)
			( pin "J6L1.147"
				( objectStatus "@baseboard_fab2_lib.baseboard_fab2(sch_1):page54_i43:vss(46)" )
			)
			( pin "J6L1.138"
				( objectStatus "@baseboard_fab2_lib.baseboard_fab2(sch_1):page54_i43:vss(47)" )
			)
			( pin "J6L1.136"
				( objectStatus "@baseboard_fab2_lib.baseboard_fab2(sch_1):page54_i43:vss(48)" )
			)
			( pin "J6L1.134"
				( objectStatus "@baseboard_fab2_lib.baseboard_fab2(sch_1):page54_i43:vss(49)" )
			)
			( pin "J6L1.131"
				( objectStatus "@baseboard_fab2_lib.baseboard_fab2(sch_1):page54_i43:vss(50)" )
			)
			( pin "J6L1.129"
				( objectStatus "@baseboard_fab2_lib.baseboard_fab2(sch_1):page54_i43:vss(51)" )
			)
			( pin "J6L1.127"
				( objectStatus "@baseboard_fab2_lib.baseboard_fab2(sch_1):page54_i43:vss(52)" )
			)
			( pin "J6L1.125"
				( objectStatus "@baseboard_fab2_lib.baseboard_fab2(sch_1):page54_i43:vss(53)" )
			)
			( pin "J6L1.123"
				( objectStatus "@baseboard_fab2_lib.baseboard_fab2(sch_1):page54_i43:vss(54)" )
			)
			( pin "J6L1.120"
				( objectStatus "@baseboard_fab2_lib.baseboard_fab2(sch_1):page54_i43:vss(55)" )
			)
			( pin "J6L1.118"
				( objectStatus "@baseboard_fab2_lib.baseboard_fab2(sch_1):page54_i43:vss(56)" )
			)
			( pin "J6L1.116"
				( objectStatus "@baseboard_fab2_lib.baseboard_fab2(sch_1):page54_i43:vss(57)" )
			)
			( pin "J6L1.114"
				( objectStatus "@baseboard_fab2_lib.baseboard_fab2(sch_1):page54_i43:vss(58)" )
			)
			( pin "J6L1.112"
				( objectStatus "@baseboard_fab2_lib.baseboard_fab2(sch_1):page54_i43:vss(59)" )
			)
			( pin "J6L1.109"
				( objectStatus "@baseboard_fab2_lib.baseboard_fab2(sch_1):page54_i43:vss(60)" )
			)
			( pin "J6L1.107"
				( objectStatus "@baseboard_fab2_lib.baseboard_fab2(sch_1):page54_i43:vss(61)" )
			)
			( pin "J6L1.105"
				( objectStatus "@baseboard_fab2_lib.baseboard_fab2(sch_1):page54_i43:vss(62)" )
			)
			( pin "J6L1.103"
				( objectStatus "@baseboard_fab2_lib.baseboard_fab2(sch_1):page54_i43:vss(63)" )
			)
			( pin "J6L1.101"
				( objectStatus "@baseboard_fab2_lib.baseboard_fab2(sch_1):page54_i43:vss(64)" )
			)
			( pin "J6L1.98"
				( objectStatus "@baseboard_fab2_lib.baseboard_fab2(sch_1):page54_i43:vss(65)" )
			)
			( pin "J6L1.96"
				( objectStatus "@baseboard_fab2_lib.baseboard_fab2(sch_1):page54_i43:vss(66)" )
			)
			( pin "J6L1.94"
				( objectStatus "@baseboard_fab2_lib.baseboard_fab2(sch_1):page54_i43:vss(67)" )
			)
			( pin "J6L1.57"
				( objectStatus "@baseboard_fab2_lib.baseboard_fab2(sch_1):page54_i43:vss(68)" )
			)
			( pin "J6L1.55"
				( objectStatus "@baseboard_fab2_lib.baseboard_fab2(sch_1):page54_i43:vss(69)" )
			)
			( pin "J6L1.53"
				( objectStatus "@baseboard_fab2_lib.baseboard_fab2(sch_1):page54_i43:vss(70)" )
			)
			( pin "J6L1.50"
				( objectStatus "@baseboard_fab2_lib.baseboard_fab2(sch_1):page54_i43:vss(71)" )
			)
			( pin "J6L1.48"
				( objectStatus "@baseboard_fab2_lib.baseboard_fab2(sch_1):page54_i43:vss(72)" )
			)
			( pin "J6L1.46"
				( objectStatus "@baseboard_fab2_lib.baseboard_fab2(sch_1):page54_i43:vss(73)" )
			)
			( pin "J6L1.44"
				( objectStatus "@baseboard_fab2_lib.baseboard_fab2(sch_1):page54_i43:vss(74)" )
			)
			( pin "J6L1.42"
				( objectStatus "@baseboard_fab2_lib.baseboard_fab2(sch_1):page54_i43:vss(75)" )
			)
			( pin "J6L1.39"
				( objectStatus "@baseboard_fab2_lib.baseboard_fab2(sch_1):page54_i43:vss(76)" )
			)
			( pin "J6L1.37"
				( objectStatus "@baseboard_fab2_lib.baseboard_fab2(sch_1):page54_i43:vss(77)" )
			)
			( pin "J6L1.35"
				( objectStatus "@baseboard_fab2_lib.baseboard_fab2(sch_1):page54_i43:vss(78)" )
			)
			( pin "J6L1.33"
				( objectStatus "@baseboard_fab2_lib.baseboard_fab2(sch_1):page54_i43:vss(79)" )
			)
			( pin "J6L1.31"
				( objectStatus "@baseboard_fab2_lib.baseboard_fab2(sch_1):page54_i43:vss(80)" )
			)
			( pin "J6L1.28"
				( objectStatus "@baseboard_fab2_lib.baseboard_fab2(sch_1):page54_i43:vss(81)" )
			)
			( pin "J6L1.26"
				( objectStatus "@baseboard_fab2_lib.baseboard_fab2(sch_1):page54_i43:vss(82)" )
			)
			( pin "J6L1.24"
				( objectStatus "@baseboard_fab2_lib.baseboard_fab2(sch_1):page54_i43:vss(83)" )
			)
			( pin "J6L1.22"
				( objectStatus "@baseboard_fab2_lib.baseboard_fab2(sch_1):page54_i43:vss(84)" )
			)
			( pin "J6L1.20"
				( objectStatus "@baseboard_fab2_lib.baseboard_fab2(sch_1):page54_i43:vss(85)" )
			)
			( pin "J6L1.17"
				( objectStatus "@baseboard_fab2_lib.baseboard_fab2(sch_1):page54_i43:vss(86)" )
			)
			( pin "J6L1.15"
				( objectStatus "@baseboard_fab2_lib.baseboard_fab2(sch_1):page54_i43:vss(87)" )
			)
			( pin "J6L1.13"
				( objectStatus "@baseboard_fab2_lib.baseboard_fab2(sch_1):page54_i43:vss(88)" )
			)
			( pin "J6L1.11"
				( objectStatus "@baseboard_fab2_lib.baseboard_fab2(sch_1):page54_i43:vss(89)" )
			)
			( pin "J6L1.9"
				( objectStatus "@baseboard_fab2_lib.baseboard_fab2(sch_1):page54_i43:vss(90)" )
			)
			( pin "J6L1.6"
				( objectStatus "@baseboard_fab2_lib.baseboard_fab2(sch_1):page54_i43:vss(91)" )
			)
			( pin "J6L1.4"
				( objectStatus "@baseboard_fab2_lib.baseboard_fab2(sch_1):page54_i43:vss(92)" )
			)
			( pin "J6L1.2"
				( objectStatus "@baseboard_fab2_lib.baseboard_fab2(sch_1):page54_i43:vss(93)" )
			)
			( pin "J6L1.152"
				( objectStatus "@baseboard_fab2_lib.baseboard_fab2(sch_1):page54_i66:dqs0n" )
			)
			( pin "J6L1.153"
				( objectStatus "@baseboard_fab2_lib.baseboard_fab2(sch_1):page54_i66:dqs0p" )
			)
			( pin "J6L1.163"
				( objectStatus "@baseboard_fab2_lib.baseboard_fab2(sch_1):page54_i66:dqs1n" )
			)
			( pin "J6L1.164"
				( objectStatus "@baseboard_fab2_lib.baseboard_fab2(sch_1):page54_i66:dqs1p" )
			)
			( pin "J6L1.174"
				( objectStatus "@baseboard_fab2_lib.baseboard_fab2(sch_1):page54_i66:dqs2n" )
			)
			( pin "J6L1.175"
				( objectStatus "@baseboard_fab2_lib.baseboard_fab2(sch_1):page54_i66:dqs2p" )
			)
			( pin "J6L1.185"
				( objectStatus "@baseboard_fab2_lib.baseboard_fab2(sch_1):page54_i66:dqs3n" )
			)
			( pin "J6L1.186"
				( objectStatus "@baseboard_fab2_lib.baseboard_fab2(sch_1):page54_i66:dqs3p" )
			)
			( pin "J6L1.244"
				( objectStatus "@baseboard_fab2_lib.baseboard_fab2(sch_1):page54_i66:dqs4n" )
			)
			( pin "J6L1.245"
				( objectStatus "@baseboard_fab2_lib.baseboard_fab2(sch_1):page54_i66:dqs4p" )
			)
			( pin "J6L1.255"
				( objectStatus "@baseboard_fab2_lib.baseboard_fab2(sch_1):page54_i66:dqs5n" )
			)
			( pin "J6L1.256"
				( objectStatus "@baseboard_fab2_lib.baseboard_fab2(sch_1):page54_i66:dqs5p" )
			)
			( pin "J6L1.266"
				( objectStatus "@baseboard_fab2_lib.baseboard_fab2(sch_1):page54_i66:dqs6n" )
			)
			( pin "J6L1.267"
				( objectStatus "@baseboard_fab2_lib.baseboard_fab2(sch_1):page54_i66:dqs6p" )
			)
			( pin "J6L1.277"
				( objectStatus "@baseboard_fab2_lib.baseboard_fab2(sch_1):page54_i66:dqs7n" )
			)
			( pin "J6L1.278"
				( objectStatus "@baseboard_fab2_lib.baseboard_fab2(sch_1):page54_i66:dqs7p" )
			)
			( pin "J6L1.196"
				( objectStatus "@baseboard_fab2_lib.baseboard_fab2(sch_1):page54_i66:dqs8n" )
			)
			( pin "J6L1.197"
				( objectStatus "@baseboard_fab2_lib.baseboard_fab2(sch_1):page54_i66:dqs8p" )
			)
			( pin "J6L1.8"
				( objectStatus "@baseboard_fab2_lib.baseboard_fab2(sch_1):page54_i66:dqs9n" )
			)
			( pin "J6L1.7"
				( objectStatus "@baseboard_fab2_lib.baseboard_fab2(sch_1):page54_i66:dqs9p" )
			)
			( pin "J6L1.19"
				( objectStatus "@baseboard_fab2_lib.baseboard_fab2(sch_1):page54_i66:dqs10n" )
			)
			( pin "J6L1.18"
				( objectStatus "@baseboard_fab2_lib.baseboard_fab2(sch_1):page54_i66:dqs10p" )
			)
			( pin "J6L1.30"
				( objectStatus "@baseboard_fab2_lib.baseboard_fab2(sch_1):page54_i66:dqs11n" )
			)
			( pin "J6L1.29"
				( objectStatus "@baseboard_fab2_lib.baseboard_fab2(sch_1):page54_i66:dqs11p" )
			)
			( pin "J6L1.41"
				( objectStatus "@baseboard_fab2_lib.baseboard_fab2(sch_1):page54_i66:dqs12n" )
			)
			( pin "J6L1.40"
				( objectStatus "@baseboard_fab2_lib.baseboard_fab2(sch_1):page54_i66:dqs12p" )
			)
			( pin "J6L1.100"
				( objectStatus "@baseboard_fab2_lib.baseboard_fab2(sch_1):page54_i66:dqs13n" )
			)
			( pin "J6L1.99"
				( objectStatus "@baseboard_fab2_lib.baseboard_fab2(sch_1):page54_i66:dqs13p" )
			)
			( pin "J6L1.111"
				( objectStatus "@baseboard_fab2_lib.baseboard_fab2(sch_1):page54_i66:dqs14n" )
			)
			( pin "J6L1.110"
				( objectStatus "@baseboard_fab2_lib.baseboard_fab2(sch_1):page54_i66:dqs14p" )
			)
			( pin "J6L1.122"
				( objectStatus "@baseboard_fab2_lib.baseboard_fab2(sch_1):page54_i66:dqs15n" )
			)
			( pin "J6L1.121"
				( objectStatus "@baseboard_fab2_lib.baseboard_fab2(sch_1):page54_i66:dqs15p" )
			)
			( pin "J6L1.133"
				( objectStatus "@baseboard_fab2_lib.baseboard_fab2(sch_1):page54_i66:dqs16n" )
			)
			( pin "J6L1.132"
				( objectStatus "@baseboard_fab2_lib.baseboard_fab2(sch_1):page54_i66:dqs16p" )
			)
			( pin "J6L1.52"
				( objectStatus "@baseboard_fab2_lib.baseboard_fab2(sch_1):page54_i66:dqs17n" )
			)
			( pin "J6L1.51"
				( objectStatus "@baseboard_fab2_lib.baseboard_fab2(sch_1):page54_i66:dqs17p" )
			)
			( pin "J6L1.79"
				( objectStatus "@baseboard_fab2_lib.baseboard_fab2(sch_1):page54_i111:a0" )
			)
			( pin "J6L1.72"
				( objectStatus "@baseboard_fab2_lib.baseboard_fab2(sch_1):page54_i111:a1" )
			)
			( pin "J6L1.216"
				( objectStatus "@baseboard_fab2_lib.baseboard_fab2(sch_1):page54_i111:a2" )
			)
			( pin "J6L1.71"
				( objectStatus "@baseboard_fab2_lib.baseboard_fab2(sch_1):page54_i111:a3" )
			)
			( pin "J6L1.214"
				( objectStatus "@baseboard_fab2_lib.baseboard_fab2(sch_1):page54_i111:a4" )
			)
			( pin "J6L1.213"
				( objectStatus "@baseboard_fab2_lib.baseboard_fab2(sch_1):page54_i111:a5" )
			)
			( pin "J6L1.69"
				( objectStatus "@baseboard_fab2_lib.baseboard_fab2(sch_1):page54_i111:a6" )
			)
			( pin "J6L1.211"
				( objectStatus "@baseboard_fab2_lib.baseboard_fab2(sch_1):page54_i111:a7" )
			)
			( pin "J6L1.68"
				( objectStatus "@baseboard_fab2_lib.baseboard_fab2(sch_1):page54_i111:a8" )
			)
			( pin "J6L1.66"
				( objectStatus "@baseboard_fab2_lib.baseboard_fab2(sch_1):page54_i111:a9" )
			)
			( pin "J6L1.225"
				( objectStatus "@baseboard_fab2_lib.baseboard_fab2(sch_1):page54_i111:a10" )
			)
			( pin "J6L1.210"
				( objectStatus "@baseboard_fab2_lib.baseboard_fab2(sch_1):page54_i111:a11" )
			)
			( pin "J6L1.65"
				( objectStatus "@baseboard_fab2_lib.baseboard_fab2(sch_1):page54_i111:a12" )
			)
			( pin "J6L1.232"
				( objectStatus "@baseboard_fab2_lib.baseboard_fab2(sch_1):page54_i111:a13" )
			)
			( pin "J6L1.228"
				( objectStatus "@baseboard_fab2_lib.baseboard_fab2(sch_1):page54_i111:a14_we_n" )
			)
			( pin "J6L1.86"
				( objectStatus "@baseboard_fab2_lib.baseboard_fab2(sch_1):page54_i111:a15_cas_n" )
			)
			( pin "J6L1.82"
				( objectStatus "@baseboard_fab2_lib.baseboard_fab2(sch_1):page54_i111:a16_ras_n" )
			)
			( pin "J6L1.234"
				( objectStatus "@baseboard_fab2_lib.baseboard_fab2(sch_1):page54_i111:a17" )
			)
			( pin "J6L1.62"
				( objectStatus "@baseboard_fab2_lib.baseboard_fab2(sch_1):page54_i111:act_n" )
			)
			( pin "J6L1.208"
				( objectStatus "@baseboard_fab2_lib.baseboard_fab2(sch_1):page54_i111:alert_n" )
			)
			( pin "J6L1.81"
				( objectStatus "@baseboard_fab2_lib.baseboard_fab2(sch_1):page54_i111:ba(0)" )
			)
			( pin "J6L1.224"
				( objectStatus "@baseboard_fab2_lib.baseboard_fab2(sch_1):page54_i111:ba(1)" )
			)
			( pin "J6L1.63"
				( objectStatus "@baseboard_fab2_lib.baseboard_fab2(sch_1):page54_i111:bg(0)" )
			)
			( pin "J6L1.207"
				( objectStatus "@baseboard_fab2_lib.baseboard_fab2(sch_1):page54_i111:bg(1)" )
			)
			( pin "J6L1.235"
				( objectStatus "@baseboard_fab2_lib.baseboard_fab2(sch_1):page54_i111:c(2)" )
			)
			( pin "J6L1.49"
				( objectStatus "@baseboard_fab2_lib.baseboard_fab2(sch_1):page54_i111:cb(0)" )
			)
			( pin "J6L1.194"
				( objectStatus "@baseboard_fab2_lib.baseboard_fab2(sch_1):page54_i111:cb(1)" )
			)
			( pin "J6L1.56"
				( objectStatus "@baseboard_fab2_lib.baseboard_fab2(sch_1):page54_i111:cb(2)" )
			)
			( pin "J6L1.201"
				( objectStatus "@baseboard_fab2_lib.baseboard_fab2(sch_1):page54_i111:cb(3)" )
			)
			( pin "J6L1.47"
				( objectStatus "@baseboard_fab2_lib.baseboard_fab2(sch_1):page54_i111:cb(4)" )
			)
			( pin "J6L1.192"
				( objectStatus "@baseboard_fab2_lib.baseboard_fab2(sch_1):page54_i111:cb(5)" )
			)
			( pin "J6L1.54"
				( objectStatus "@baseboard_fab2_lib.baseboard_fab2(sch_1):page54_i111:cb(6)" )
			)
			( pin "J6L1.199"
				( objectStatus "@baseboard_fab2_lib.baseboard_fab2(sch_1):page54_i111:cb(7)" )
			)
			( pin "J6L1.75"
				( objectStatus "@baseboard_fab2_lib.baseboard_fab2(sch_1):page54_i111:ck0n" )
			)
			( pin "J6L1.74"
				( objectStatus "@baseboard_fab2_lib.baseboard_fab2(sch_1):page54_i111:ck0p" )
			)
			( pin "J6L1.219"
				( objectStatus "@baseboard_fab2_lib.baseboard_fab2(sch_1):page54_i111:ck1n" )
			)
			( pin "J6L1.218"
				( objectStatus "@baseboard_fab2_lib.baseboard_fab2(sch_1):page54_i111:ck1p" )
			)
			( pin "J6L1.60"
				( objectStatus "@baseboard_fab2_lib.baseboard_fab2(sch_1):page54_i111:cke(0)" )
			)
			( pin "J6L1.203"
				( objectStatus "@baseboard_fab2_lib.baseboard_fab2(sch_1):page54_i111:cke(1)" )
			)
			( pin "J6L1.5"
				( objectStatus "@baseboard_fab2_lib.baseboard_fab2(sch_1):page54_i111:dq(0)" )
			)
			( pin "J6L1.150"
				( objectStatus "@baseboard_fab2_lib.baseboard_fab2(sch_1):page54_i111:dq(1)" )
			)
			( pin "J6L1.12"
				( objectStatus "@baseboard_fab2_lib.baseboard_fab2(sch_1):page54_i111:dq(2)" )
			)
			( pin "J6L1.157"
				( objectStatus "@baseboard_fab2_lib.baseboard_fab2(sch_1):page54_i111:dq(3)" )
			)
			( pin "J6L1.3"
				( objectStatus "@baseboard_fab2_lib.baseboard_fab2(sch_1):page54_i111:dq(4)" )
			)
			( pin "J6L1.148"
				( objectStatus "@baseboard_fab2_lib.baseboard_fab2(sch_1):page54_i111:dq(5)" )
			)
			( pin "J6L1.10"
				( objectStatus "@baseboard_fab2_lib.baseboard_fab2(sch_1):page54_i111:dq(6)" )
			)
			( pin "J6L1.155"
				( objectStatus "@baseboard_fab2_lib.baseboard_fab2(sch_1):page54_i111:dq(7)" )
			)
			( pin "J6L1.16"
				( objectStatus "@baseboard_fab2_lib.baseboard_fab2(sch_1):page54_i111:dq(8)" )
			)
			( pin "J6L1.161"
				( objectStatus "@baseboard_fab2_lib.baseboard_fab2(sch_1):page54_i111:dq(9)" )
			)
			( pin "J6L1.23"
				( objectStatus "@baseboard_fab2_lib.baseboard_fab2(sch_1):page54_i111:dq(10)" )
			)
			( pin "J6L1.168"
				( objectStatus "@baseboard_fab2_lib.baseboard_fab2(sch_1):page54_i111:dq(11)" )
			)
			( pin "J6L1.14"
				( objectStatus "@baseboard_fab2_lib.baseboard_fab2(sch_1):page54_i111:dq(12)" )
			)
			( pin "J6L1.159"
				( objectStatus "@baseboard_fab2_lib.baseboard_fab2(sch_1):page54_i111:dq(13)" )
			)
			( pin "J6L1.21"
				( objectStatus "@baseboard_fab2_lib.baseboard_fab2(sch_1):page54_i111:dq(14)" )
			)
			( pin "J6L1.166"
				( objectStatus "@baseboard_fab2_lib.baseboard_fab2(sch_1):page54_i111:dq(15)" )
			)
			( pin "J6L1.27"
				( objectStatus "@baseboard_fab2_lib.baseboard_fab2(sch_1):page54_i111:dq(16)" )
			)
			( pin "J6L1.172"
				( objectStatus "@baseboard_fab2_lib.baseboard_fab2(sch_1):page54_i111:dq(17)" )
			)
			( pin "J6L1.34"
				( objectStatus "@baseboard_fab2_lib.baseboard_fab2(sch_1):page54_i111:dq(18)" )
			)
			( pin "J6L1.179"
				( objectStatus "@baseboard_fab2_lib.baseboard_fab2(sch_1):page54_i111:dq(19)" )
			)
			( pin "J6L1.25"
				( objectStatus "@baseboard_fab2_lib.baseboard_fab2(sch_1):page54_i111:dq(20)" )
			)
			( pin "J6L1.170"
				( objectStatus "@baseboard_fab2_lib.baseboard_fab2(sch_1):page54_i111:dq(21)" )
			)
			( pin "J6L1.32"
				( objectStatus "@baseboard_fab2_lib.baseboard_fab2(sch_1):page54_i111:dq(22)" )
			)
			( pin "J6L1.177"
				( objectStatus "@baseboard_fab2_lib.baseboard_fab2(sch_1):page54_i111:dq(23)" )
			)
			( pin "J6L1.38"
				( objectStatus "@baseboard_fab2_lib.baseboard_fab2(sch_1):page54_i111:dq(24)" )
			)
			( pin "J6L1.183"
				( objectStatus "@baseboard_fab2_lib.baseboard_fab2(sch_1):page54_i111:dq(25)" )
			)
			( pin "J6L1.45"
				( objectStatus "@baseboard_fab2_lib.baseboard_fab2(sch_1):page54_i111:dq(26)" )
			)
			( pin "J6L1.190"
				( objectStatus "@baseboard_fab2_lib.baseboard_fab2(sch_1):page54_i111:dq(27)" )
			)
			( pin "J6L1.36"
				( objectStatus "@baseboard_fab2_lib.baseboard_fab2(sch_1):page54_i111:dq(28)" )
			)
			( pin "J6L1.181"
				( objectStatus "@baseboard_fab2_lib.baseboard_fab2(sch_1):page54_i111:dq(29)" )
			)
			( pin "J6L1.43"
				( objectStatus "@baseboard_fab2_lib.baseboard_fab2(sch_1):page54_i111:dq(30)" )
			)
			( pin "J6L1.188"
				( objectStatus "@baseboard_fab2_lib.baseboard_fab2(sch_1):page54_i111:dq(31)" )
			)
			( pin "J6L1.97"
				( objectStatus "@baseboard_fab2_lib.baseboard_fab2(sch_1):page54_i111:dq(32)" )
			)
			( pin "J6L1.242"
				( objectStatus "@baseboard_fab2_lib.baseboard_fab2(sch_1):page54_i111:dq(33)" )
			)
			( pin "J6L1.104"
				( objectStatus "@baseboard_fab2_lib.baseboard_fab2(sch_1):page54_i111:dq(34)" )
			)
			( pin "J6L1.249"
				( objectStatus "@baseboard_fab2_lib.baseboard_fab2(sch_1):page54_i111:dq(35)" )
			)
			( pin "J6L1.95"
				( objectStatus "@baseboard_fab2_lib.baseboard_fab2(sch_1):page54_i111:dq(36)" )
			)
			( pin "J6L1.240"
				( objectStatus "@baseboard_fab2_lib.baseboard_fab2(sch_1):page54_i111:dq(37)" )
			)
			( pin "J6L1.102"
				( objectStatus "@baseboard_fab2_lib.baseboard_fab2(sch_1):page54_i111:dq(38)" )
			)
			( pin "J6L1.247"
				( objectStatus "@baseboard_fab2_lib.baseboard_fab2(sch_1):page54_i111:dq(39)" )
			)
			( pin "J6L1.108"
				( objectStatus "@baseboard_fab2_lib.baseboard_fab2(sch_1):page54_i111:dq(40)" )
			)
			( pin "J6L1.253"
				( objectStatus "@baseboard_fab2_lib.baseboard_fab2(sch_1):page54_i111:dq(41)" )
			)
			( pin "J6L1.115"
				( objectStatus "@baseboard_fab2_lib.baseboard_fab2(sch_1):page54_i111:dq(42)" )
			)
			( pin "J6L1.260"
				( objectStatus "@baseboard_fab2_lib.baseboard_fab2(sch_1):page54_i111:dq(43)" )
			)
			( pin "J6L1.106"
				( objectStatus "@baseboard_fab2_lib.baseboard_fab2(sch_1):page54_i111:dq(44)" )
			)
			( pin "J6L1.251"
				( objectStatus "@baseboard_fab2_lib.baseboard_fab2(sch_1):page54_i111:dq(45)" )
			)
			( pin "J6L1.113"
				( objectStatus "@baseboard_fab2_lib.baseboard_fab2(sch_1):page54_i111:dq(46)" )
			)
			( pin "J6L1.258"
				( objectStatus "@baseboard_fab2_lib.baseboard_fab2(sch_1):page54_i111:dq(47)" )
			)
			( pin "J6L1.119"
				( objectStatus "@baseboard_fab2_lib.baseboard_fab2(sch_1):page54_i111:dq(48)" )
			)
			( pin "J6L1.264"
				( objectStatus "@baseboard_fab2_lib.baseboard_fab2(sch_1):page54_i111:dq(49)" )
			)
			( pin "J6L1.126"
				( objectStatus "@baseboard_fab2_lib.baseboard_fab2(sch_1):page54_i111:dq(50)" )
			)
			( pin "J6L1.271"
				( objectStatus "@baseboard_fab2_lib.baseboard_fab2(sch_1):page54_i111:dq(51)" )
			)
			( pin "J6L1.117"
				( objectStatus "@baseboard_fab2_lib.baseboard_fab2(sch_1):page54_i111:dq(52)" )
			)
			( pin "J6L1.262"
				( objectStatus "@baseboard_fab2_lib.baseboard_fab2(sch_1):page54_i111:dq(53)" )
			)
			( pin "J6L1.124"
				( objectStatus "@baseboard_fab2_lib.baseboard_fab2(sch_1):page54_i111:dq(54)" )
			)
			( pin "J6L1.269"
				( objectStatus "@baseboard_fab2_lib.baseboard_fab2(sch_1):page54_i111:dq(55)" )
			)
			( pin "J6L1.130"
				( objectStatus "@baseboard_fab2_lib.baseboard_fab2(sch_1):page54_i111:dq(56)" )
			)
			( pin "J6L1.275"
				( objectStatus "@baseboard_fab2_lib.baseboard_fab2(sch_1):page54_i111:dq(57)" )
			)
			( pin "J6L1.137"
				( objectStatus "@baseboard_fab2_lib.baseboard_fab2(sch_1):page54_i111:dq(58)" )
			)
			( pin "J6L1.282"
				( objectStatus "@baseboard_fab2_lib.baseboard_fab2(sch_1):page54_i111:dq(59)" )
			)
			( pin "J6L1.128"
				( objectStatus "@baseboard_fab2_lib.baseboard_fab2(sch_1):page54_i111:dq(60)" )
			)
			( pin "J6L1.273"
				( objectStatus "@baseboard_fab2_lib.baseboard_fab2(sch_1):page54_i111:dq(61)" )
			)
			( pin "J6L1.135"
				( objectStatus "@baseboard_fab2_lib.baseboard_fab2(sch_1):page54_i111:dq(62)" )
			)
			( pin "J6L1.280"
				( objectStatus "@baseboard_fab2_lib.baseboard_fab2(sch_1):page54_i111:dq(63)" )
			)
			( pin "J6L1.78"
				( objectStatus "@baseboard_fab2_lib.baseboard_fab2(sch_1):page54_i111:event_n" )
			)
			( pin "J6L1.87"
				( objectStatus "@baseboard_fab2_lib.baseboard_fab2(sch_1):page54_i111:odt(0)" )
			)
			( pin "J6L1.91"
				( objectStatus "@baseboard_fab2_lib.baseboard_fab2(sch_1):page54_i111:odt(1)" )
			)
			( pin "J6L1.222"
				( objectStatus "@baseboard_fab2_lib.baseboard_fab2(sch_1):page54_i111:par" )
			)
			( pin "J6L1.58"
				( objectStatus "@baseboard_fab2_lib.baseboard_fab2(sch_1):page54_i111:reset_n" )
			)
			( pin "J6L1.205"
				( objectStatus "@baseboard_fab2_lib.baseboard_fab2(sch_1):page54_i111:rfu(0)" )
			)
			( pin "J6L1.227"
				( objectStatus "@baseboard_fab2_lib.baseboard_fab2(sch_1):page54_i111:rfu(1)" )
			)
			( pin "J6L1.144"
				( objectStatus "@baseboard_fab2_lib.baseboard_fab2(sch_1):page54_i111:rfu(2)" )
			)
			( pin "J6L1.84"
				( objectStatus "@baseboard_fab2_lib.baseboard_fab2(sch_1):page54_i111:s0_n" )
			)
			( pin "J6L1.89"
				( objectStatus "@baseboard_fab2_lib.baseboard_fab2(sch_1):page54_i111:s1_n" )
			)
			( pin "J6L1.93"
				( objectStatus "@baseboard_fab2_lib.baseboard_fab2(sch_1):page54_i111:s2_n_c(0)" )
			)
			( pin "J6L1.237"
				( objectStatus "@baseboard_fab2_lib.baseboard_fab2(sch_1):page54_i111:s3_n_c(1)" )
			)
			( pin "J6L1.139"
				( objectStatus "@baseboard_fab2_lib.baseboard_fab2(sch_1):page54_i111:sa(0)" )
			)
			( pin "J6L1.140"
				( objectStatus "@baseboard_fab2_lib.baseboard_fab2(sch_1):page54_i111:sa(1)" )
			)
			( pin "J6L1.238"
				( objectStatus "@baseboard_fab2_lib.baseboard_fab2(sch_1):page54_i111:sa(2)" )
			)
			( pin "J6L1.230"
				( objectStatus "@baseboard_fab2_lib.baseboard_fab2(sch_1):page54_i111:save_n_nc" )
			)
			( pin "J6L1.141"
				( objectStatus "@baseboard_fab2_lib.baseboard_fab2(sch_1):page54_i111:scl" )
			)
			( pin "J6L1.285"
				( objectStatus "@baseboard_fab2_lib.baseboard_fab2(sch_1):page54_i111:sda" )
			)
			( pin "J6L1.284"
				( objectStatus "@baseboard_fab2_lib.baseboard_fab2(sch_1):page54_i111:vddspd" )
			)
			( pin "J6L1.146"
				( objectStatus "@baseboard_fab2_lib.baseboard_fab2(sch_1):page54_i111:vrefca" )
			)
			( pin "J6L1.145"
				( objectStatus "@baseboard_fab2_lib.baseboard_fab2(sch_1):page54_i170:\12v\(0)" )
			)
			( pin "J6L1.1"
				( objectStatus "@baseboard_fab2_lib.baseboard_fab2(sch_1):page54_i170:\12v\(1)" )
			)
			( pin "J6L1.236"
				( objectStatus "@baseboard_fab2_lib.baseboard_fab2(sch_1):page54_i170:vdd(0)" )
			)
			( pin "J6L1.233"
				( objectStatus "@baseboard_fab2_lib.baseboard_fab2(sch_1):page54_i170:vdd(1)" )
			)
			( pin "J6L1.231"
				( objectStatus "@baseboard_fab2_lib.baseboard_fab2(sch_1):page54_i170:vdd(2)" )
			)
			( pin "J6L1.229"
				( objectStatus "@baseboard_fab2_lib.baseboard_fab2(sch_1):page54_i170:vdd(3)" )
			)
			( pin "J6L1.226"
				( objectStatus "@baseboard_fab2_lib.baseboard_fab2(sch_1):page54_i170:vdd(4)" )
			)
			( pin "J6L1.223"
				( objectStatus "@baseboard_fab2_lib.baseboard_fab2(sch_1):page54_i170:vdd(5)" )
			)
			( pin "J6L1.220"
				( objectStatus "@baseboard_fab2_lib.baseboard_fab2(sch_1):page54_i170:vdd(6)" )
			)
			( pin "J6L1.217"
				( objectStatus "@baseboard_fab2_lib.baseboard_fab2(sch_1):page54_i170:vdd(7)" )
			)
			( pin "J6L1.215"
				( objectStatus "@baseboard_fab2_lib.baseboard_fab2(sch_1):page54_i170:vdd(8)" )
			)
			( pin "J6L1.212"
				( objectStatus "@baseboard_fab2_lib.baseboard_fab2(sch_1):page54_i170:vdd(9)" )
			)
			( pin "J6L1.209"
				( objectStatus "@baseboard_fab2_lib.baseboard_fab2(sch_1):page54_i170:vdd(10)" )
			)
			( pin "J6L1.206"
				( objectStatus "@baseboard_fab2_lib.baseboard_fab2(sch_1):page54_i170:vdd(11)" )
			)
			( pin "J6L1.204"
				( objectStatus "@baseboard_fab2_lib.baseboard_fab2(sch_1):page54_i170:vdd(12)" )
			)
			( pin "J6L1.92"
				( objectStatus "@baseboard_fab2_lib.baseboard_fab2(sch_1):page54_i170:vdd(13)" )
			)
			( pin "J6L1.90"
				( objectStatus "@baseboard_fab2_lib.baseboard_fab2(sch_1):page54_i170:vdd(14)" )
			)
			( pin "J6L1.88"
				( objectStatus "@baseboard_fab2_lib.baseboard_fab2(sch_1):page54_i170:vdd(15)" )
			)
			( pin "J6L1.85"
				( objectStatus "@baseboard_fab2_lib.baseboard_fab2(sch_1):page54_i170:vdd(16)" )
			)
			( pin "J6L1.83"
				( objectStatus "@baseboard_fab2_lib.baseboard_fab2(sch_1):page54_i170:vdd(17)" )
			)
			( pin "J6L1.80"
				( objectStatus "@baseboard_fab2_lib.baseboard_fab2(sch_1):page54_i170:vdd(18)" )
			)
			( pin "J6L1.76"
				( objectStatus "@baseboard_fab2_lib.baseboard_fab2(sch_1):page54_i170:vdd(19)" )
			)
			( pin "J6L1.73"
				( objectStatus "@baseboard_fab2_lib.baseboard_fab2(sch_1):page54_i170:vdd(20)" )
			)
			( pin "J6L1.70"
				( objectStatus "@baseboard_fab2_lib.baseboard_fab2(sch_1):page54_i170:vdd(21)" )
			)
			( pin "J6L1.67"
				( objectStatus "@baseboard_fab2_lib.baseboard_fab2(sch_1):page54_i170:vdd(22)" )
			)
			( pin "J6L1.64"
				( objectStatus "@baseboard_fab2_lib.baseboard_fab2(sch_1):page54_i170:vdd(23)" )
			)
			( pin "J6L1.61"
				( objectStatus "@baseboard_fab2_lib.baseboard_fab2(sch_1):page54_i170:vdd(24)" )
			)
			( pin "J6L1.59"
				( objectStatus "@baseboard_fab2_lib.baseboard_fab2(sch_1):page54_i170:vdd(25)" )
			)
			( pin "J6L1.287"
				( objectStatus "@baseboard_fab2_lib.baseboard_fab2(sch_1):page54_i170:vpp(0)" )
			)
			( pin "J6L1.286"
				( objectStatus "@baseboard_fab2_lib.baseboard_fab2(sch_1):page54_i170:vpp(1)" )
			)
			( pin "J6L1.288"
				( objectStatus "@baseboard_fab2_lib.baseboard_fab2(sch_1):page54_i170:vpp(2)" )
			)
			( pin "J6L1.143"
				( objectStatus "@baseboard_fab2_lib.baseboard_fab2(sch_1):page54_i170:vpp(3)" )
			)
			( pin "J6L1.142"
				( objectStatus "@baseboard_fab2_lib.baseboard_fab2(sch_1):page54_i170:vpp(4)" )
			)
			( pin "J6L1.221"
				( objectStatus "@baseboard_fab2_lib.baseboard_fab2(sch_1):page54_i170:vtt(0)" )
			)
			( pin "J6L1.77"
				( objectStatus "@baseboard_fab2_lib.baseboard_fab2(sch_1):page54_i170:vtt(1)" )
			)
			( pin "C4A5.1"
				( objectStatus "@baseboard_fab2_lib.baseboard_fab2(sch_1):page54_i179:a" )
			)
			( pin "C4A5.2"
				( objectStatus "@baseboard_fab2_lib.baseboard_fab2(sch_1):page54_i179:b" )
			)
			( pin "R9N1.1"
				( objectStatus "@baseboard_fab2_lib.baseboard_fab2(sch_1):page55_i4:a" )
			)
			( pin "R9N1.2"
				( objectStatus "@baseboard_fab2_lib.baseboard_fab2(sch_1):page55_i4:b" )
			)
			( pin "R9N2.1"
				( objectStatus "@baseboard_fab2_lib.baseboard_fab2(sch_1):page55_i7:a" )
			)
			( pin "R9N2.2"
				( objectStatus "@baseboard_fab2_lib.baseboard_fab2(sch_1):page55_i7:b" )
			)
			( pin "R3B2.1"
				( objectStatus "@baseboard_fab2_lib.baseboard_fab2(sch_1):page55_i19:a" )
			)
			( pin "R3B2.2"
				( objectStatus "@baseboard_fab2_lib.baseboard_fab2(sch_1):page55_i19:b" )
			)
			( pin "R3B4.1"
				( objectStatus "@baseboard_fab2_lib.baseboard_fab2(sch_1):page55_i21:a" )
			)
			( pin "R3B4.2"
				( objectStatus "@baseboard_fab2_lib.baseboard_fab2(sch_1):page55_i21:b" )
			)
			( pin "R1C2.1"
				( objectStatus "@baseboard_fab2_lib.baseboard_fab2(sch_1):page55_i24:a" )
			)
			( pin "R1C2.2"
				( objectStatus "@baseboard_fab2_lib.baseboard_fab2(sch_1):page55_i24:b" )
			)
			( pin "R1C3.1"
				( objectStatus "@baseboard_fab2_lib.baseboard_fab2(sch_1):page55_i25:a" )
			)
			( pin "R1C3.2"
				( objectStatus "@baseboard_fab2_lib.baseboard_fab2(sch_1):page55_i25:b" )
			)
			( pin "R1C1.1"
				( objectStatus "@baseboard_fab2_lib.baseboard_fab2(sch_1):page55_i26:a" )
			)
			( pin "R1C1.2"
				( objectStatus "@baseboard_fab2_lib.baseboard_fab2(sch_1):page55_i26:b" )
			)
			( pin "R3B1.1"
				( objectStatus "@baseboard_fab2_lib.baseboard_fab2(sch_1):page55_i27:a" )
			)
			( pin "R3B1.2"
				( objectStatus "@baseboard_fab2_lib.baseboard_fab2(sch_1):page55_i27:b" )
			)
			( pin "R3B5.1"
				( objectStatus "@baseboard_fab2_lib.baseboard_fab2(sch_1):page55_i28:a" )
			)
			( pin "R3B5.2"
				( objectStatus "@baseboard_fab2_lib.baseboard_fab2(sch_1):page55_i28:b" )
			)
			( pin "R3B3.1"
				( objectStatus "@baseboard_fab2_lib.baseboard_fab2(sch_1):page55_i29:a" )
			)
			( pin "R3B3.2"
				( objectStatus "@baseboard_fab2_lib.baseboard_fab2(sch_1):page55_i29:b" )
			)
			( pin "R7P19.1"
				( objectStatus "@baseboard_fab2_lib.baseboard_fab2(sch_1):page55_i115:a" )
			)
			( pin "R7P19.2"
				( objectStatus "@baseboard_fab2_lib.baseboard_fab2(sch_1):page55_i115:b" )
			)
			( pin "R3D1.1"
				( objectStatus "@baseboard_fab2_lib.baseboard_fab2(sch_1):page55_i116:a" )
			)
			( pin "R3D1.2"
				( objectStatus "@baseboard_fab2_lib.baseboard_fab2(sch_1):page55_i116:b" )
			)
			( pin "R3D2.1"
				( objectStatus "@baseboard_fab2_lib.baseboard_fab2(sch_1):page55_i117:a" )
			)
			( pin "R3D2.2"
				( objectStatus "@baseboard_fab2_lib.baseboard_fab2(sch_1):page55_i117:b" )
			)
			( pin "R3D3.1"
				( objectStatus "@baseboard_fab2_lib.baseboard_fab2(sch_1):page55_i118:a" )
			)
			( pin "R3D3.2"
				( objectStatus "@baseboard_fab2_lib.baseboard_fab2(sch_1):page55_i118:b" )
			)
			( pin "R7P16.1"
				( objectStatus "@baseboard_fab2_lib.baseboard_fab2(sch_1):page55_i119:a" )
			)
			( pin "R7P16.2"
				( objectStatus "@baseboard_fab2_lib.baseboard_fab2(sch_1):page55_i119:b" )
			)
			( pin "R7P8.1"
				( objectStatus "@baseboard_fab2_lib.baseboard_fab2(sch_1):page55_i123:a" )
			)
			( pin "R7P8.2"
				( objectStatus "@baseboard_fab2_lib.baseboard_fab2(sch_1):page55_i123:b" )
			)
			( pin "R7P10.1"
				( objectStatus "@baseboard_fab2_lib.baseboard_fab2(sch_1):page55_i124:a" )
			)
			( pin "R7P10.2"
				( objectStatus "@baseboard_fab2_lib.baseboard_fab2(sch_1):page55_i124:b" )
			)
			( pin "R3D19.1"
				( objectStatus "@baseboard_fab2_lib.baseboard_fab2(sch_1):page55_i125:a" )
			)
			( pin "R3D19.2"
				( objectStatus "@baseboard_fab2_lib.baseboard_fab2(sch_1):page55_i125:b" )
			)
			( pin "R7P11.1"
				( objectStatus "@baseboard_fab2_lib.baseboard_fab2(sch_1):page55_i126:a" )
			)
			( pin "R7P11.2"
				( objectStatus "@baseboard_fab2_lib.baseboard_fab2(sch_1):page55_i126:b" )
			)
			( pin "R7P17.1"
				( objectStatus "@baseboard_fab2_lib.baseboard_fab2(sch_1):page55_i140:a" )
			)
			( pin "R7P17.2"
				( objectStatus "@baseboard_fab2_lib.baseboard_fab2(sch_1):page55_i140:b" )
			)
			( pin "R3D4.1"
				( objectStatus "@baseboard_fab2_lib.baseboard_fab2(sch_1):page55_i155:a" )
			)
			( pin "R3D4.2"
				( objectStatus "@baseboard_fab2_lib.baseboard_fab2(sch_1):page55_i155:b" )
			)
			( pin "R7P26.1"
				( objectStatus "@baseboard_fab2_lib.baseboard_fab2(sch_1):page55_i156:a" )
			)
			( pin "R7P26.2"
				( objectStatus "@baseboard_fab2_lib.baseboard_fab2(sch_1):page55_i156:b" )
			)
			( pin "R8N1.1"
				( objectStatus "@baseboard_fab2_lib.baseboard_fab2(sch_1):page55_i157:a" )
			)
			( pin "R8N1.2"
				( objectStatus "@baseboard_fab2_lib.baseboard_fab2(sch_1):page55_i157:b" )
			)
			( pin "R8N4.1"
				( objectStatus "@baseboard_fab2_lib.baseboard_fab2(sch_1):page55_i158:a" )
			)
			( pin "R8N4.2"
				( objectStatus "@baseboard_fab2_lib.baseboard_fab2(sch_1):page55_i158:b" )
			)
			( pin "R8N3.1"
				( objectStatus "@baseboard_fab2_lib.baseboard_fab2(sch_1):page55_i159:a" )
			)
			( pin "R8N3.2"
				( objectStatus "@baseboard_fab2_lib.baseboard_fab2(sch_1):page55_i159:b" )
			)
			( pin "R8N5.1"
				( objectStatus "@baseboard_fab2_lib.baseboard_fab2(sch_1):page55_i160:a" )
			)
			( pin "R8N5.2"
				( objectStatus "@baseboard_fab2_lib.baseboard_fab2(sch_1):page55_i160:b" )
			)
			( pin "R8N2.1"
				( objectStatus "@baseboard_fab2_lib.baseboard_fab2(sch_1):page55_i161:a" )
			)
			( pin "R8N2.2"
				( objectStatus "@baseboard_fab2_lib.baseboard_fab2(sch_1):page55_i161:b" )
			)
			( pin "R7P25.1"
				( objectStatus "@baseboard_fab2_lib.baseboard_fab2(sch_1):page55_i170:a" )
			)
			( pin "R7P25.2"
				( objectStatus "@baseboard_fab2_lib.baseboard_fab2(sch_1):page55_i170:b" )
			)
			( pin "U2D1.AU24"
				( objectStatus "@baseboard_fab2_lib.baseboard_fab2(sch_1):page55_i172:bclk0_dn" )
			)
			( pin "U2D1.AW24"
				( objectStatus "@baseboard_fab2_lib.baseboard_fab2(sch_1):page55_i172:bclk0_dp" )
			)
			( pin "U2D1.CR26"
				( objectStatus "@baseboard_fab2_lib.baseboard_fab2(sch_1):page55_i172:bclk1_dn" )
			)
			( pin "U2D1.CP27"
				( objectStatus "@baseboard_fab2_lib.baseboard_fab2(sch_1):page55_i172:bclk1_dp" )
			)
			( pin "U2D1.CT25"
				( objectStatus "@baseboard_fab2_lib.baseboard_fab2(sch_1):page55_i172:bclk2_dn" )
			)
			( pin "U2D1.CU26"
				( objectStatus "@baseboard_fab2_lib.baseboard_fab2(sch_1):page55_i172:bclk2_dp" )
			)
			( pin "U2D1.BA20"
				( objectStatus "@baseboard_fab2_lib.baseboard_fab2(sch_1):page55_i172:bist_enable" )
			)
			( pin "U2D1.BD23"
				( objectStatus "@baseboard_fab2_lib.baseboard_fab2(sch_1):page55_i172:bmcinit" )
			)
			( pin "U2D1.AJ10"
				( objectStatus "@baseboard_fab2_lib.baseboard_fab2(sch_1):page55_i172:bpm_n(0)" )
			)
			( pin "U2D1.AH11"
				( objectStatus "@baseboard_fab2_lib.baseboard_fab2(sch_1):page55_i172:bpm_n(1)" )
			)
			( pin "U2D1.AG10"
				( objectStatus "@baseboard_fab2_lib.baseboard_fab2(sch_1):page55_i172:bpm_n(2)" )
			)
			( pin "U2D1.AF11"
				( objectStatus "@baseboard_fab2_lib.baseboard_fab2(sch_1):page55_i172:bpm_n(3)" )
			)
			( pin "U2D1.AA12"
				( objectStatus "@baseboard_fab2_lib.baseboard_fab2(sch_1):page55_i172:bpm_n(4)" )
			)
			( pin "U2D1.Y11"
				( objectStatus "@baseboard_fab2_lib.baseboard_fab2(sch_1):page55_i172:bpm_n(5)" )
			)
			( pin "U2D1.AE12"
				( objectStatus "@baseboard_fab2_lib.baseboard_fab2(sch_1):page55_i172:bpm_n(6)" )
			)
			( pin "U2D1.AC12"
				( objectStatus "@baseboard_fab2_lib.baseboard_fab2(sch_1):page55_i172:bpm_n(7)" )
			)
			( pin "U2D1.AL14"
				( objectStatus "@baseboard_fab2_lib.baseboard_fab2(sch_1):page55_i172:caterr_n" )
			)
			( pin "U2D1.AJ64"
				( objectStatus "@baseboard_fab2_lib.baseboard_fab2(sch_1):page55_i172:ddr0_cavref" )
			)
			( pin "U2D1.AK63"
				( objectStatus "@baseboard_fab2_lib.baseboard_fab2(sch_1):page55_i172:ddr1_cavref" )
			)
			( pin "U2D1.AH63"
				( objectStatus "@baseboard_fab2_lib.baseboard_fab2(sch_1):page55_i172:ddr2_cavref" )
			)
			( pin "U2D1.CP61"
				( objectStatus "@baseboard_fab2_lib.baseboard_fab2(sch_1):page55_i172:ddr3_cavref" )
			)
			( pin "U2D1.CT61"
				( objectStatus "@baseboard_fab2_lib.baseboard_fab2(sch_1):page55_i172:ddr4_cavref" )
			)
			( pin "U2D1.CV61"
				( objectStatus "@baseboard_fab2_lib.baseboard_fab2(sch_1):page55_i172:ddr5_cavref" )
			)
			( pin "U2D1.AN30"
				( objectStatus "@baseboard_fab2_lib.baseboard_fab2(sch_1):page55_i172:ddr012_dram_pwr_ok" )
			)
			( pin "U2D1.Y43"
				( objectStatus "@baseboard_fab2_lib.baseboard_fab2(sch_1):page55_i172:ddr012_rcomp(0)" )
			)
			( pin "U2D1.AB43"
				( objectStatus "@baseboard_fab2_lib.baseboard_fab2(sch_1):page55_i172:ddr012_rcomp(1)" )
			)
			( pin "U2D1.AC42"
				( objectStatus "@baseboard_fab2_lib.baseboard_fab2(sch_1):page55_i172:ddr012_rcomp(2)" )
			)
			( pin "U2D1.U64"
				( objectStatus "@baseboard_fab2_lib.baseboard_fab2(sch_1):page55_i172:ddr012_reset_n" )
			)
			( pin "U2D1.AJ18"
				( objectStatus "@baseboard_fab2_lib.baseboard_fab2(sch_1):page55_i172:ddr012_spdscl" )
			)
			( pin "U2D1.AF17"
				( objectStatus "@baseboard_fab2_lib.baseboard_fab2(sch_1):page55_i172:ddr012_spdsda" )
			)
			( pin "U2D1.CR28"
				( objectStatus "@baseboard_fab2_lib.baseboard_fab2(sch_1):page55_i172:ddr345_dram_pwr_ok" )
			)
			( pin "U2D1.DC48"
				( objectStatus "@baseboard_fab2_lib.baseboard_fab2(sch_1):page55_i172:ddr345_rcomp(0)" )
			)
			( pin "U2D1.DD47"
				( objectStatus "@baseboard_fab2_lib.baseboard_fab2(sch_1):page55_i172:ddr345_rcomp(1)" )
			)
			( pin "U2D1.DD49"
				( objectStatus "@baseboard_fab2_lib.baseboard_fab2(sch_1):page55_i172:ddr345_rcomp(2)" )
			)
			( pin "U2D1.DV63"
				( objectStatus "@baseboard_fab2_lib.baseboard_fab2(sch_1):page55_i172:ddr345_reset_n" )
			)
			( pin "U2D1.AE18"
				( objectStatus "@baseboard_fab2_lib.baseboard_fab2(sch_1):page55_i172:ddr345_spdscl" )
			)
			( pin "U2D1.AD17"
				( objectStatus "@baseboard_fab2_lib.baseboard_fab2(sch_1):page55_i172:ddr345_spdsda" )
			)
			( pin "U2D1.AJ14"
				( objectStatus "@baseboard_fab2_lib.baseboard_fab2(sch_1):page55_i172:ear_n" )
			)
			( pin "U2D1.AJ12"
				( objectStatus "@baseboard_fab2_lib.baseboard_fab2(sch_1):page55_i172:error_n(0)" )
			)
			( pin "U2D1.AK11"
				( objectStatus "@baseboard_fab2_lib.baseboard_fab2(sch_1):page55_i172:error_n(1)" )
			)
			( pin "U2D1.AL12"
				( objectStatus "@baseboard_fab2_lib.baseboard_fab2(sch_1):page55_i172:error_n(2)" )
			)
			( pin "U2D1.AV17"
				( objectStatus "@baseboard_fab2_lib.baseboard_fab2(sch_1):page55_i172:frmagent" )
			)
			( pin "U2D1.AE20"
				( objectStatus "@baseboard_fab2_lib.baseboard_fab2(sch_1):page55_i172:legacy_skt" )
			)
			( pin "U2D1.CU32"
				( objectStatus "@baseboard_fab2_lib.baseboard_fab2(sch_1):page55_i172:mcp01_rbias(0)" )
			)
			( pin "U2D1.CT31"
				( objectStatus "@baseboard_fab2_lib.baseboard_fab2(sch_1):page55_i172:mcp01_rbias(1)" )
			)
			( pin "U2D1.AH13"
				( objectStatus "@baseboard_fab2_lib.baseboard_fab2(sch_1):page55_i172:mem_hot_c012_n" )
			)
			( pin "U2D1.AF13"
				( objectStatus "@baseboard_fab2_lib.baseboard_fab2(sch_1):page55_i172:mem_hot_c345_n" )
			)
			( pin "U2D1.AN20"
				( objectStatus "@baseboard_fab2_lib.baseboard_fab2(sch_1):page55_i172:msmi_n" )
			)
			( pin "U2D1.AP11"
				( objectStatus "@baseboard_fab2_lib.baseboard_fab2(sch_1):page55_i172:nmi" )
			)
			( pin "U2D1.CP29"
				( objectStatus "@baseboard_fab2_lib.baseboard_fab2(sch_1):page55_i172:pe3_rbias(0)" )
			)
			( pin "U2D1.CR30"
				( objectStatus "@baseboard_fab2_lib.baseboard_fab2(sch_1):page55_i172:pe3_rbias(1)" )
			)
			( pin "U2D1.CN30"
				( objectStatus "@baseboard_fab2_lib.baseboard_fab2(sch_1):page55_i172:pe012_rbias(0)" )
			)
			( pin "U2D1.CL30"
				( objectStatus "@baseboard_fab2_lib.baseboard_fab2(sch_1):page55_i172:pe012_rbias(1)" )
			)
			( pin "U2D1.AM19"
				( objectStatus "@baseboard_fab2_lib.baseboard_fab2(sch_1):page55_i172:pe_hp_scl" )
			)
			( pin "U2D1.AL18"
				( objectStatus "@baseboard_fab2_lib.baseboard_fab2(sch_1):page55_i172:pe_hp_sda" )
			)
			( pin "U2D1.AU12"
				( objectStatus "@baseboard_fab2_lib.baseboard_fab2(sch_1):page55_i172:peci" )
			)
			( pin "U2D1.CU58"
				( objectStatus "@baseboard_fab2_lib.baseboard_fab2(sch_1):page55_i172:pirom_addr(0)" )
			)
			( pin "U2D1.CV57"
				( objectStatus "@baseboard_fab2_lib.baseboard_fab2(sch_1):page55_i172:pirom_addr(1)" )
			)
			( pin "U2D1.CW56"
				( objectStatus "@baseboard_fab2_lib.baseboard_fab2(sch_1):page55_i172:pirom_addr(2)" )
			)
			( pin "U2D1.DC72"
				( objectStatus "@baseboard_fab2_lib.baseboard_fab2(sch_1):page55_i172:pkgid(0)" )
			)
			( pin "U2D1.CW72"
				( objectStatus "@baseboard_fab2_lib.baseboard_fab2(sch_1):page55_i172:pkgid(1)" )
			)
			( pin "U2D1.DA72"
				( objectStatus "@baseboard_fab2_lib.baseboard_fab2(sch_1):page55_i172:pkgid(2)" )
			)
			( pin "U2D1.AF15"
				( objectStatus "@baseboard_fab2_lib.baseboard_fab2(sch_1):page55_i172:pm_fast_wake_n" )
			)
			( pin "U2D1.AR14"
				( objectStatus "@baseboard_fab2_lib.baseboard_fab2(sch_1):page55_i172:pmsync" )
			)
			( pin "U2D1.AT19"
				( objectStatus "@baseboard_fab2_lib.baseboard_fab2(sch_1):page55_i172:pmsync_clk" )
			)
			( pin "U2D1.AG16"
				( objectStatus "@baseboard_fab2_lib.baseboard_fab2(sch_1):page55_i172:prdy_n" )
			)
			( pin "U2D1.AR12"
				( objectStatus "@baseboard_fab2_lib.baseboard_fab2(sch_1):page55_i172:preq_n" )
			)
			( pin "U2D1.CY71"
				( objectStatus "@baseboard_fab2_lib.baseboard_fab2(sch_1):page55_i172:proc_id(0)" )
			)
			( pin "U2D1.DB71"
				( objectStatus "@baseboard_fab2_lib.baseboard_fab2(sch_1):page55_i172:proc_id(1)" )
			)
			( pin "U2D1.AB17"
				( objectStatus "@baseboard_fab2_lib.baseboard_fab2(sch_1):page55_i172:procdis_n" )
			)
			( pin "U2D1.AC16"
				( objectStatus "@baseboard_fab2_lib.baseboard_fab2(sch_1):page55_i172:prochot_n" )
			)
			( pin "U2D1.BC24"
				( objectStatus "@baseboard_fab2_lib.baseboard_fab2(sch_1):page55_i172:pwrgood" )
			)
			( pin "U2D1.AP21"
				( objectStatus "@baseboard_fab2_lib.baseboard_fab2(sch_1):page55_i172:reset_n" )
			)
			( pin "U2D1.AR18"
				( objectStatus "@baseboard_fab2_lib.baseboard_fab2(sch_1):page55_i172:safe_mode_boot" )
			)
			( pin "U2D1.AB13"
				( objectStatus "@baseboard_fab2_lib.baseboard_fab2(sch_1):page55_i172:sktocc_n" )
			)
			( pin "U2D1.CV59"
				( objectStatus "@baseboard_fab2_lib.baseboard_fab2(sch_1):page55_i172:sm_wp" )
			)
			( pin "U2D1.CT59"
				( objectStatus "@baseboard_fab2_lib.baseboard_fab2(sch_1):page55_i172:smbclk" )
			)
			( pin "U2D1.CW58"
				( objectStatus "@baseboard_fab2_lib.baseboard_fab2(sch_1):page55_i172:smbdat" )
			)
			( pin "U2D1.AU22"
				( objectStatus "@baseboard_fab2_lib.baseboard_fab2(sch_1):page55_i172:socket_id(0)" )
			)
			( pin "U2D1.AU16"
				( objectStatus "@baseboard_fab2_lib.baseboard_fab2(sch_1):page55_i172:socket_id(1)" )
			)
			( pin "U2D1.AU20"
				( objectStatus "@baseboard_fab2_lib.baseboard_fab2(sch_1):page55_i172:socket_id(2)" )
			)
			( pin "U2D1.DE44"
				( objectStatus "@baseboard_fab2_lib.baseboard_fab2(sch_1):page55_i172:svidalert_n(0)" )
			)
			( pin "U2D1.DL44"
				( objectStatus "@baseboard_fab2_lib.baseboard_fab2(sch_1):page55_i172:svidalert_n(1)" )
			)
			( pin "U2D1.DC44"
				( objectStatus "@baseboard_fab2_lib.baseboard_fab2(sch_1):page55_i172:svidclk(0)" )
			)
			( pin "U2D1.DG44"
				( objectStatus "@baseboard_fab2_lib.baseboard_fab2(sch_1):page55_i172:svidclk(1)" )
			)
			( pin "U2D1.DB45"
				( objectStatus "@baseboard_fab2_lib.baseboard_fab2(sch_1):page55_i172:sviddata(0)" )
			)
			( pin "U2D1.DJ44"
				( objectStatus "@baseboard_fab2_lib.baseboard_fab2(sch_1):page55_i172:sviddata(1)" )
			)
			( pin "U2D1.AA14"
				( objectStatus "@baseboard_fab2_lib.baseboard_fab2(sch_1):page55_i172:tck" )
			)
			( pin "U2D1.AC14"
				( objectStatus "@baseboard_fab2_lib.baseboard_fab2(sch_1):page55_i172:tdi" )
			)
			( pin "U2D1.AE14"
				( objectStatus "@baseboard_fab2_lib.baseboard_fab2(sch_1):page55_i172:tdo" )
			)
			( pin "U2D1.AY19"
				( objectStatus "@baseboard_fab2_lib.baseboard_fab2(sch_1):page55_i172:test_12" )
			)
			( pin "U2D1.DB51"
				( objectStatus "@baseboard_fab2_lib.baseboard_fab2(sch_1):page55_i172:test_13" )
			)
			( pin "U2D1.DC50"
				( objectStatus "@baseboard_fab2_lib.baseboard_fab2(sch_1):page55_i172:test_14" )
			)
			( pin "U2D1.AW14"
				( objectStatus "@baseboard_fab2_lib.baseboard_fab2(sch_1):page55_i172:test_15" )
			)
			( pin "U2D1.AB15"
				( objectStatus "@baseboard_fab2_lib.baseboard_fab2(sch_1):page55_i172:thermtrip_n" )
			)
			( pin "U2D1.W14"
				( objectStatus "@baseboard_fab2_lib.baseboard_fab2(sch_1):page55_i172:tms" )
			)
			( pin "U2D1.Y13"
				( objectStatus "@baseboard_fab2_lib.baseboard_fab2(sch_1):page55_i172:trst_n" )
			)
			( pin "U2D1.AM11"
				( objectStatus "@baseboard_fab2_lib.baseboard_fab2(sch_1):page55_i172:tsc_sync" )
			)
			( pin "U2D1.AW18"
				( objectStatus "@baseboard_fab2_lib.baseboard_fab2(sch_1):page55_i172:txt_agent" )
			)
			( pin "U2D1.AV15"
				( objectStatus "@baseboard_fab2_lib.baseboard_fab2(sch_1):page55_i172:txt_plten" )
			)
			( pin "U2D1.AT29"
				( objectStatus "@baseboard_fab2_lib.baseboard_fab2(sch_1):page55_i172:upi01_rbias(0)" )
			)
			( pin "U2D1.AP29"
				( objectStatus "@baseboard_fab2_lib.baseboard_fab2(sch_1):page55_i172:upi01_rbias(1)" )
			)
			( pin "U2D1.CL28"
				( objectStatus "@baseboard_fab2_lib.baseboard_fab2(sch_1):page55_i172:upi2_rbias(0)" )
			)
			( pin "U2D1.CK29"
				( objectStatus "@baseboard_fab2_lib.baseboard_fab2(sch_1):page55_i172:upi2_rbias(1)" )
			)
			( pin "R6P39.1"
				( objectStatus "@baseboard_fab2_lib.baseboard_fab2(sch_1):page55_i181:a" )
			)
			( pin "R6P39.2"
				( objectStatus "@baseboard_fab2_lib.baseboard_fab2(sch_1):page55_i181:b" )
			)
			( pin "U2D1.AV21"
				( objectStatus "@baseboard_fab2_lib.baseboard_fab2(sch_1):page56_i169:debug_en_n" )
			)
			( pin "U2D1.AW12"
				( objectStatus "@baseboard_fab2_lib.baseboard_fab2(sch_1):page56_i169:dmimode_override" )
			)
			( pin "U2D1.AU14"
				( objectStatus "@baseboard_fab2_lib.baseboard_fab2(sch_1):page56_i169:fivr_fault" )
			)
			( pin "U2D1.AP17"
				( objectStatus "@baseboard_fab2_lib.baseboard_fab2(sch_1):page56_i169:pwr_debug_n" )
			)
			( pin "U2D1.AP61"
				( objectStatus "@baseboard_fab2_lib.baseboard_fab2(sch_1):page56_i169:rsvd(194)" )
			)
			( pin "U2D1.AP27"
				( objectStatus "@baseboard_fab2_lib.baseboard_fab2(sch_1):page56_i169:rsvd(195)" )
			)
			( pin "U2D1.AP25"
				( objectStatus "@baseboard_fab2_lib.baseboard_fab2(sch_1):page56_i169:rsvd(196)" )
			)
			( pin "U2D1.AP23"
				( objectStatus "@baseboard_fab2_lib.baseboard_fab2(sch_1):page56_i169:rsvd(197)" )
			)
			( pin "U2D1.AN62"
				( objectStatus "@baseboard_fab2_lib.baseboard_fab2(sch_1):page56_i169:rsvd(198)" )
			)
			( pin "U2D1.AN60"
				( objectStatus "@baseboard_fab2_lib.baseboard_fab2(sch_1):page56_i169:rsvd(199)" )
			)
			( pin "U2D1.AN26"
				( objectStatus "@baseboard_fab2_lib.baseboard_fab2(sch_1):page56_i169:rsvd(200)" )
			)
			( pin "U2D1.AN24"
				( objectStatus "@baseboard_fab2_lib.baseboard_fab2(sch_1):page56_i169:rsvd(201)" )
			)
			( pin "U2D1.AN22"
				( objectStatus "@baseboard_fab2_lib.baseboard_fab2(sch_1):page56_i169:rsvd(202)" )
			)
			( pin "U2D1.AN18"
				( objectStatus "@baseboard_fab2_lib.baseboard_fab2(sch_1):page56_i169:rsvd(203)" )
			)
			( pin "U2D1.AM61"
				( objectStatus "@baseboard_fab2_lib.baseboard_fab2(sch_1):page56_i169:rsvd(204)" )
			)
			( pin "U2D1.AM59"
				( objectStatus "@baseboard_fab2_lib.baseboard_fab2(sch_1):page56_i169:rsvd(205)" )
			)
			( pin "U2D1.AM27"
				( objectStatus "@baseboard_fab2_lib.baseboard_fab2(sch_1):page56_i169:rsvd(206)" )
			)
			( pin "U2D1.AM25"
				( objectStatus "@baseboard_fab2_lib.baseboard_fab2(sch_1):page56_i169:rsvd(207)" )
			)
			( pin "U2D1.AM23"
				( objectStatus "@baseboard_fab2_lib.baseboard_fab2(sch_1):page56_i169:rsvd(208)" )
			)
			( pin "U2D1.AM21"
				( objectStatus "@baseboard_fab2_lib.baseboard_fab2(sch_1):page56_i169:rsvd(209)" )
			)
			( pin "U2D1.AL62"
				( objectStatus "@baseboard_fab2_lib.baseboard_fab2(sch_1):page56_i169:rsvd(210)" )
			)
			( pin "U2D1.AL60"
				( objectStatus "@baseboard_fab2_lib.baseboard_fab2(sch_1):page56_i169:rsvd(211)" )
			)
			( pin "U2D1.AL58"
				( objectStatus "@baseboard_fab2_lib.baseboard_fab2(sch_1):page56_i169:rsvd(212)" )
			)
			( pin "U2D1.AL26"
				( objectStatus "@baseboard_fab2_lib.baseboard_fab2(sch_1):page56_i169:rsvd(213)" )
			)
			( pin "U2D1.AL22"
				( objectStatus "@baseboard_fab2_lib.baseboard_fab2(sch_1):page56_i169:rsvd(214)" )
			)
			( pin "U2D1.AL20"
				( objectStatus "@baseboard_fab2_lib.baseboard_fab2(sch_1):page56_i169:rsvd(215)" )
			)
			( pin "U2D1.AK69"
				( objectStatus "@baseboard_fab2_lib.baseboard_fab2(sch_1):page56_i169:rsvd(216)" )
			)
			( pin "U2D1.AK61"
				( objectStatus "@baseboard_fab2_lib.baseboard_fab2(sch_1):page56_i169:rsvd(217)" )
			)
			( pin "U2D1.AK59"
				( objectStatus "@baseboard_fab2_lib.baseboard_fab2(sch_1):page56_i169:rsvd(218)" )
			)
			( pin "U2D1.AK57"
				( objectStatus "@baseboard_fab2_lib.baseboard_fab2(sch_1):page56_i169:rsvd(219)" )
			)
			( pin "U2D1.AK27"
				( objectStatus "@baseboard_fab2_lib.baseboard_fab2(sch_1):page56_i169:rsvd(220)" )
			)
			( pin "U2D1.AK21"
				( objectStatus "@baseboard_fab2_lib.baseboard_fab2(sch_1):page56_i169:rsvd(221)" )
			)
			( pin "U2D1.AJ70"
				( objectStatus "@baseboard_fab2_lib.baseboard_fab2(sch_1):page56_i169:rsvd(222)" )
			)
			( pin "U2D1.AJ62"
				( objectStatus "@baseboard_fab2_lib.baseboard_fab2(sch_1):page56_i169:rsvd(223)" )
			)
			( pin "U2D1.AJ60"
				( objectStatus "@baseboard_fab2_lib.baseboard_fab2(sch_1):page56_i169:rsvd(224)" )
			)
			( pin "U2D1.AJ58"
				( objectStatus "@baseboard_fab2_lib.baseboard_fab2(sch_1):page56_i169:rsvd(225)" )
			)
			( pin "U2D1.AJ56"
				( objectStatus "@baseboard_fab2_lib.baseboard_fab2(sch_1):page56_i169:rsvd(226)" )
			)
			( pin "U2D1.AJ20"
				( objectStatus "@baseboard_fab2_lib.baseboard_fab2(sch_1):page56_i169:rsvd(227)" )
			)
			( pin "U2D1.AH73"
				( objectStatus "@baseboard_fab2_lib.baseboard_fab2(sch_1):page56_i169:rsvd(228)" )
			)
			( pin "U2D1.AH71"
				( objectStatus "@baseboard_fab2_lib.baseboard_fab2(sch_1):page56_i169:rsvd(229)" )
			)
			( pin "U2D1.AH57"
				( objectStatus "@baseboard_fab2_lib.baseboard_fab2(sch_1):page56_i169:rsvd(230)" )
			)
			( pin "U2D1.AH55"
				( objectStatus "@baseboard_fab2_lib.baseboard_fab2(sch_1):page56_i169:rsvd(231)" )
			)
			( pin "U2D1.AH19"
				( objectStatus "@baseboard_fab2_lib.baseboard_fab2(sch_1):page56_i169:rsvd(232)" )
			)
			( pin "U2D1.AH15"
				( objectStatus "@baseboard_fab2_lib.baseboard_fab2(sch_1):page56_i169:rsvd(233)" )
			)
			( pin "U2D1.AG72"
				( objectStatus "@baseboard_fab2_lib.baseboard_fab2(sch_1):page56_i169:rsvd(234)" )
			)
			( pin "U2D1.AG56"
				( objectStatus "@baseboard_fab2_lib.baseboard_fab2(sch_1):page56_i169:rsvd(235)" )
			)
			( pin "U2D1.AG54"
				( objectStatus "@baseboard_fab2_lib.baseboard_fab2(sch_1):page56_i169:rsvd(236)" )
			)
			( pin "U2D1.AG52"
				( objectStatus "@baseboard_fab2_lib.baseboard_fab2(sch_1):page56_i169:rsvd(237)" )
			)
			( pin "U2D1.AG50"
				( objectStatus "@baseboard_fab2_lib.baseboard_fab2(sch_1):page56_i169:rsvd(238)" )
			)
			( pin "U2D1.AG48"
				( objectStatus "@baseboard_fab2_lib.baseboard_fab2(sch_1):page56_i169:rsvd(239)" )
			)
			( pin "U2D1.AG20"
				( objectStatus "@baseboard_fab2_lib.baseboard_fab2(sch_1):page56_i169:rsvd(240)" )
			)
			( pin "U2D1.AF71"
				( objectStatus "@baseboard_fab2_lib.baseboard_fab2(sch_1):page56_i169:rsvd(241)" )
			)
			( pin "U2D1.AF53"
				( objectStatus "@baseboard_fab2_lib.baseboard_fab2(sch_1):page56_i169:rsvd(242)" )
			)
			( pin "U2D1.AF51"
				( objectStatus "@baseboard_fab2_lib.baseboard_fab2(sch_1):page56_i169:rsvd(243)" )
			)
			( pin "U2D1.AF49"
				( objectStatus "@baseboard_fab2_lib.baseboard_fab2(sch_1):page56_i169:rsvd(244)" )
			)
			( pin "U2D1.AF47"
				( objectStatus "@baseboard_fab2_lib.baseboard_fab2(sch_1):page56_i169:rsvd(245)" )
			)
			( pin "U2D1.AF19"
				( objectStatus "@baseboard_fab2_lib.baseboard_fab2(sch_1):page56_i169:rsvd(246)" )
			)
			( pin "U2D1.AE72"
				( objectStatus "@baseboard_fab2_lib.baseboard_fab2(sch_1):page56_i169:rsvd(247)" )
			)
			( pin "U2D1.AE52"
				( objectStatus "@baseboard_fab2_lib.baseboard_fab2(sch_1):page56_i169:rsvd(248)" )
			)
			( pin "U2D1.AE50"
				( objectStatus "@baseboard_fab2_lib.baseboard_fab2(sch_1):page56_i169:rsvd(249)" )
			)
			( pin "U2D1.AE48"
				( objectStatus "@baseboard_fab2_lib.baseboard_fab2(sch_1):page56_i169:rsvd(250)" )
			)
			( pin "U2D1.AE46"
				( objectStatus "@baseboard_fab2_lib.baseboard_fab2(sch_1):page56_i169:rsvd(251)" )
			)
			( pin "U2D1.AD51"
				( objectStatus "@baseboard_fab2_lib.baseboard_fab2(sch_1):page56_i169:rsvd(252)" )
			)
			( pin "U2D1.AD49"
				( objectStatus "@baseboard_fab2_lib.baseboard_fab2(sch_1):page56_i169:rsvd(253)" )
			)
			( pin "U2D1.AD47"
				( objectStatus "@baseboard_fab2_lib.baseboard_fab2(sch_1):page56_i169:rsvd(254)" )
			)
			( pin "U2D1.Y65"
				( objectStatus "@baseboard_fab2_lib.baseboard_fab2(sch_1):page56_i169:rsvd(256)" )
			)
			( pin "U2D1.Y23"
				( objectStatus "@baseboard_fab2_lib.baseboard_fab2(sch_1):page56_i169:rsvd(257)" )
			)
			( pin "U2D1.W66"
				( objectStatus "@baseboard_fab2_lib.baseboard_fab2(sch_1):page56_i169:rsvd(258)" )
			)
			( pin "U2D1.V67"
				( objectStatus "@baseboard_fab2_lib.baseboard_fab2(sch_1):page56_i169:rsvd(259)" )
			)
			( pin "U2D1.V65"
				( objectStatus "@baseboard_fab2_lib.baseboard_fab2(sch_1):page56_i169:rsvd(260)" )
			)
			( pin "U2D1.U66"
				( objectStatus "@baseboard_fab2_lib.baseboard_fab2(sch_1):page56_i169:rsvd(261)" )
			)
			( pin "U2D1.T67"
				( objectStatus "@baseboard_fab2_lib.baseboard_fab2(sch_1):page56_i169:rsvd(262)" )
			)
			( pin "U2D1.R66"
				( objectStatus "@baseboard_fab2_lib.baseboard_fab2(sch_1):page56_i169:rsvd(263)" )
			)
			( pin "U2D1.R62"
				( objectStatus "@baseboard_fab2_lib.baseboard_fab2(sch_1):page56_i169:rsvd(264)" )
			)
			( pin "U2D1.P65"
				( objectStatus "@baseboard_fab2_lib.baseboard_fab2(sch_1):page56_i169:rsvd(265)" )
			)
			( pin "U2D1.M63"
				( objectStatus "@baseboard_fab2_lib.baseboard_fab2(sch_1):page56_i169:rsvd(266)" )
			)
			( pin "U2D1.K61"
				( objectStatus "@baseboard_fab2_lib.baseboard_fab2(sch_1):page56_i169:rsvd(267)" )
			)
			( pin "U2D1.J62"
				( objectStatus "@baseboard_fab2_lib.baseboard_fab2(sch_1):page56_i169:rsvd(268)" )
			)
			( pin "U2D1.J46"
				( objectStatus "@baseboard_fab2_lib.baseboard_fab2(sch_1):page56_i169:rsvd(269)" )
			)
			( pin "U2D1.H85"
				( objectStatus "@baseboard_fab2_lib.baseboard_fab2(sch_1):page56_i169:rsvd(270)" )
			)
			( pin "U2D1.H83"
				( objectStatus "@baseboard_fab2_lib.baseboard_fab2(sch_1):page56_i169:rsvd(271)" )
			)
			( pin "U2D1.H1"
				( objectStatus "@baseboard_fab2_lib.baseboard_fab2(sch_1):page56_i169:rsvd(272)" )
			)
			( pin "U2D1.G84"
				( objectStatus "@baseboard_fab2_lib.baseboard_fab2(sch_1):page56_i169:rsvd(273)" )
			)
			( pin "U2D1.G64"
				( objectStatus "@baseboard_fab2_lib.baseboard_fab2(sch_1):page56_i169:rsvd(274)" )
			)
			( pin "U2D1.G2"
				( objectStatus "@baseboard_fab2_lib.baseboard_fab2(sch_1):page56_i169:rsvd(275)" )
			)
			( pin "U2D1.F83"
				( objectStatus "@baseboard_fab2_lib.baseboard_fab2(sch_1):page56_i169:rsvd(276)" )
			)
			( pin "U2D1.F65"
				( objectStatus "@baseboard_fab2_lib.baseboard_fab2(sch_1):page56_i169:rsvd(277)" )
			)
			( pin "U2D1.F23"
				( objectStatus "@baseboard_fab2_lib.baseboard_fab2(sch_1):page56_i169:rsvd(278)" )
			)
			( pin "U2D1.F3"
				( objectStatus "@baseboard_fab2_lib.baseboard_fab2(sch_1):page56_i169:rsvd(279)" )
			)
			( pin "U2D1.E84"
				( objectStatus "@baseboard_fab2_lib.baseboard_fab2(sch_1):page56_i169:rsvd(280)" )
			)
			( pin "U2D1.E24"
				( objectStatus "@baseboard_fab2_lib.baseboard_fab2(sch_1):page56_i169:rsvd(281)" )
			)
			( pin "U2D1.E4"
				( objectStatus "@baseboard_fab2_lib.baseboard_fab2(sch_1):page56_i169:rsvd(282)" )
			)
			( pin "U2D1.E2"
				( objectStatus "@baseboard_fab2_lib.baseboard_fab2(sch_1):page56_i169:rsvd(283)" )
			)
			( pin "U2D1.D83"
				( objectStatus "@baseboard_fab2_lib.baseboard_fab2(sch_1):page56_i169:rsvd(284)" )
			)
			( pin "U2D1.D65"
				( objectStatus "@baseboard_fab2_lib.baseboard_fab2(sch_1):page56_i169:rsvd(285)" )
			)
			( pin "U2D1.D17"
				( objectStatus "@baseboard_fab2_lib.baseboard_fab2(sch_1):page56_i169:rsvd(286)" )
			)
			( pin "U2D1.D5"
				( objectStatus "@baseboard_fab2_lib.baseboard_fab2(sch_1):page56_i169:rsvd(287)" )
			)
			( pin "U2D1.C82"
				( objectStatus "@baseboard_fab2_lib.baseboard_fab2(sch_1):page56_i169:rsvd(288)" )
			)
			( pin "U2D1.C24"
				( objectStatus "@baseboard_fab2_lib.baseboard_fab2(sch_1):page56_i169:rsvd(289)" )
			)
			( pin "U2D1.C18"
				( objectStatus "@baseboard_fab2_lib.baseboard_fab2(sch_1):page56_i169:rsvd(290)" )
			)
			( pin "U2D1.C6"
				( objectStatus "@baseboard_fab2_lib.baseboard_fab2(sch_1):page56_i169:rsvd(291)" )
			)
			( pin "U2D1.B81"
				( objectStatus "@baseboard_fab2_lib.baseboard_fab2(sch_1):page56_i169:rsvd(292)" )
			)
			( pin "U2D1.B77"
				( objectStatus "@baseboard_fab2_lib.baseboard_fab2(sch_1):page56_i169:rsvd(293)" )
			)
			( pin "U2D1.B17"
				( objectStatus "@baseboard_fab2_lib.baseboard_fab2(sch_1):page56_i169:rsvd(294)" )
			)
			( pin "U2D1.B15"
				( objectStatus "@baseboard_fab2_lib.baseboard_fab2(sch_1):page56_i169:rsvd(295)" )
			)
			( pin "U2D1.B13"
				( objectStatus "@baseboard_fab2_lib.baseboard_fab2(sch_1):page56_i169:rsvd(296)" )
			)
			( pin "U2D1.B7"
				( objectStatus "@baseboard_fab2_lib.baseboard_fab2(sch_1):page56_i169:rsvd(298)" )
			)
			( pin "U2D1.B3"
				( objectStatus "@baseboard_fab2_lib.baseboard_fab2(sch_1):page56_i169:rsvd(299)" )
			)
			( pin "U2D1.A24"
				( objectStatus "@baseboard_fab2_lib.baseboard_fab2(sch_1):page56_i169:rsvd(300)" )
			)
			( pin "U2D1.A16"
				( objectStatus "@baseboard_fab2_lib.baseboard_fab2(sch_1):page56_i169:rsvd(301)" )
			)
			( pin "U2D1.A14"
				( objectStatus "@baseboard_fab2_lib.baseboard_fab2(sch_1):page56_i169:rsvd(302)" )
			)
			( pin "U2D1.A6"
				( objectStatus "@baseboard_fab2_lib.baseboard_fab2(sch_1):page56_i169:rsvd(303)" )
			)
			( pin "U2D1.A4"
				( objectStatus "@baseboard_fab2_lib.baseboard_fab2(sch_1):page56_i169:rsvd(304)" )
			)
			( pin "U2D1.AF45"
				( objectStatus "@baseboard_fab2_lib.baseboard_fab2(sch_1):page56_i169:test_1" )
			)
			( pin "U2D1.AG46"
				( objectStatus "@baseboard_fab2_lib.baseboard_fab2(sch_1):page56_i169:test_2" )
			)
			( pin "U2D1.AM13"
				( objectStatus "@baseboard_fab2_lib.baseboard_fab2(sch_1):page56_i169:test_3" )
			)
			( pin "U2D1.AN12"
				( objectStatus "@baseboard_fab2_lib.baseboard_fab2(sch_1):page56_i169:test_4" )
			)
			( pin "U2D1.AN14"
				( objectStatus "@baseboard_fab2_lib.baseboard_fab2(sch_1):page56_i169:test_5" )
			)
			( pin "U2D1.AY13"
				( objectStatus "@baseboard_fab2_lib.baseboard_fab2(sch_1):page56_i169:test_11" )
			)
			( pin "R8P3.1"
				( objectStatus "@baseboard_fab2_lib.baseboard_fab2(sch_1):page56_i173:a" )
			)
			( pin "R8P3.2"
				( objectStatus "@baseboard_fab2_lib.baseboard_fab2(sch_1):page56_i173:b" )
			)
			( pin "R8R1.1"
				( objectStatus "@baseboard_fab2_lib.baseboard_fab2(sch_1):page56_i174:a" )
			)
			( pin "R8R1.2"
				( objectStatus "@baseboard_fab2_lib.baseboard_fab2(sch_1):page56_i174:b" )
			)
			( pin "U2D1.J60"
				( objectStatus "@baseboard_fab2_lib.baseboard_fab2(sch_1):page57_i172:ddr0_act_n" )
			)
			( pin "U2D1.B61"
				( objectStatus "@baseboard_fab2_lib.baseboard_fab2(sch_1):page57_i172:ddr0_alert_n" )
			)
			( pin "U2D1.C52"
				( objectStatus "@baseboard_fab2_lib.baseboard_fab2(sch_1):page57_i172:ddr0_ba(0)" )
			)
			( pin "U2D1.G54"
				( objectStatus "@baseboard_fab2_lib.baseboard_fab2(sch_1):page57_i172:ddr0_ba(1)" )
			)
			( pin "U2D1.D61"
				( objectStatus "@baseboard_fab2_lib.baseboard_fab2(sch_1):page57_i172:ddr0_bg(0)" )
			)
			( pin "U2D1.F63"
				( objectStatus "@baseboard_fab2_lib.baseboard_fab2(sch_1):page57_i172:ddr0_bg(1)" )
			)
			( pin "U2D1.G46"
				( objectStatus "@baseboard_fab2_lib.baseboard_fab2(sch_1):page57_i172:ddr0_cid(2)" )
			)
			( pin "U2D1.C62"
				( objectStatus "@baseboard_fab2_lib.baseboard_fab2(sch_1):page57_i172:ddr0_cke(0)" )
			)
			( pin "U2D1.C64"
				( objectStatus "@baseboard_fab2_lib.baseboard_fab2(sch_1):page57_i172:ddr0_cke(1)" )
			)
			( pin "U2D1.B63"
				( objectStatus "@baseboard_fab2_lib.baseboard_fab2(sch_1):page57_i172:ddr0_cke(2)" )
			)
			( pin "U2D1.D63"
				( objectStatus "@baseboard_fab2_lib.baseboard_fab2(sch_1):page57_i172:ddr0_cke(3)" )
			)
			( pin "U2D1.F55"
				( objectStatus "@baseboard_fab2_lib.baseboard_fab2(sch_1):page57_i172:ddr0_clk_dn(0)" )
			)
			( pin "U2D1.C54"
				( objectStatus "@baseboard_fab2_lib.baseboard_fab2(sch_1):page57_i172:ddr0_clk_dn(1)" )
			)
			( pin "U2D1.J56"
				( objectStatus "@baseboard_fab2_lib.baseboard_fab2(sch_1):page57_i172:ddr0_clk_dn(2)" )
			)
			( pin "U2D1.C56"
				( objectStatus "@baseboard_fab2_lib.baseboard_fab2(sch_1):page57_i172:ddr0_clk_dn(3)" )
			)
			( pin "U2D1.D55"
				( objectStatus "@baseboard_fab2_lib.baseboard_fab2(sch_1):page57_i172:ddr0_clk_dp(0)" )
			)
			( pin "U2D1.B55"
				( objectStatus "@baseboard_fab2_lib.baseboard_fab2(sch_1):page57_i172:ddr0_clk_dp(1)" )
			)
			( pin "U2D1.G56"
				( objectStatus "@baseboard_fab2_lib.baseboard_fab2(sch_1):page57_i172:ddr0_clk_dp(2)" )
			)
			( pin "U2D1.B57"
				( objectStatus "@baseboard_fab2_lib.baseboard_fab2(sch_1):page57_i172:ddr0_clk_dp(3)" )
			)
			( pin "U2D1.G52"
				( objectStatus "@baseboard_fab2_lib.baseboard_fab2(sch_1):page57_i172:ddr0_cs_n(0)" )
			)
			( pin "U2D1.F49"
				( objectStatus "@baseboard_fab2_lib.baseboard_fab2(sch_1):page57_i172:ddr0_cs_n(1)" )
			)
			( pin "U2D1.D47"
				( objectStatus "@baseboard_fab2_lib.baseboard_fab2(sch_1):page57_i172:ddr0_cs_n(2)" )
			)
			( pin "U2D1.F47"
				( objectStatus "@baseboard_fab2_lib.baseboard_fab2(sch_1):page57_i172:ddr0_cs_n(3)" )
			)
			( pin "U2D1.B51"
				( objectStatus "@baseboard_fab2_lib.baseboard_fab2(sch_1):page57_i172:ddr0_cs_n(4)" )
			)
			( pin "U2D1.D49"
				( objectStatus "@baseboard_fab2_lib.baseboard_fab2(sch_1):page57_i172:ddr0_cs_n(5)" )
			)
			( pin "U2D1.F45"
				( objectStatus "@baseboard_fab2_lib.baseboard_fab2(sch_1):page57_i172:ddr0_cs_n(6)" )
			)
			( pin "U2D1.K45"
				( objectStatus "@baseboard_fab2_lib.baseboard_fab2(sch_1):page57_i172:ddr0_cs_n(7)" )
			)
			( pin "U2D1.AN86"
				( objectStatus "@baseboard_fab2_lib.baseboard_fab2(sch_1):page57_i172:ddr0_dq(0)" )
			)
			( pin "U2D1.AN84"
				( objectStatus "@baseboard_fab2_lib.baseboard_fab2(sch_1):page57_i172:ddr0_dq(1)" )
			)
			( pin "U2D1.AE86"
				( objectStatus "@baseboard_fab2_lib.baseboard_fab2(sch_1):page57_i172:ddr0_dq(2)" )
			)
			( pin "U2D1.AE84"
				( objectStatus "@baseboard_fab2_lib.baseboard_fab2(sch_1):page57_i172:ddr0_dq(3)" )
			)
			( pin "U2D1.AR86"
				( objectStatus "@baseboard_fab2_lib.baseboard_fab2(sch_1):page57_i172:ddr0_dq(4)" )
			)
			( pin "U2D1.AR84"
				( objectStatus "@baseboard_fab2_lib.baseboard_fab2(sch_1):page57_i172:ddr0_dq(5)" )
			)
			( pin "U2D1.AG86"
				( objectStatus "@baseboard_fab2_lib.baseboard_fab2(sch_1):page57_i172:ddr0_dq(6)" )
			)
			( pin "U2D1.AG84"
				( objectStatus "@baseboard_fab2_lib.baseboard_fab2(sch_1):page57_i172:ddr0_dq(7)" )
			)
			( pin "U2D1.W86"
				( objectStatus "@baseboard_fab2_lib.baseboard_fab2(sch_1):page57_i172:ddr0_dq(8)" )
			)
			( pin "U2D1.W84"
				( objectStatus "@baseboard_fab2_lib.baseboard_fab2(sch_1):page57_i172:ddr0_dq(9)" )
			)
			( pin "U2D1.L86"
				( objectStatus "@baseboard_fab2_lib.baseboard_fab2(sch_1):page57_i172:ddr0_dq(10)" )
			)
			( pin "U2D1.L84"
				( objectStatus "@baseboard_fab2_lib.baseboard_fab2(sch_1):page57_i172:ddr0_dq(11)" )
			)
			( pin "U2D1.AA86"
				( objectStatus "@baseboard_fab2_lib.baseboard_fab2(sch_1):page57_i172:ddr0_dq(12)" )
			)
			( pin "U2D1.AA84"
				( objectStatus "@baseboard_fab2_lib.baseboard_fab2(sch_1):page57_i172:ddr0_dq(13)" )
			)
			( pin "U2D1.N86"
				( objectStatus "@baseboard_fab2_lib.baseboard_fab2(sch_1):page57_i172:ddr0_dq(14)" )
			)
			( pin "U2D1.N84"
				( objectStatus "@baseboard_fab2_lib.baseboard_fab2(sch_1):page57_i172:ddr0_dq(15)" )
			)
			( pin "U2D1.V81"
				( objectStatus "@baseboard_fab2_lib.baseboard_fab2(sch_1):page57_i172:ddr0_dq(16)" )
			)
			( pin "U2D1.T79"
				( objectStatus "@baseboard_fab2_lib.baseboard_fab2(sch_1):page57_i172:ddr0_dq(17)" )
			)
			( pin "U2D1.N82"
				( objectStatus "@baseboard_fab2_lib.baseboard_fab2(sch_1):page57_i172:ddr0_dq(18)" )
			)
			( pin "U2D1.M81"
				( objectStatus "@baseboard_fab2_lib.baseboard_fab2(sch_1):page57_i172:ddr0_dq(19)" )
			)
			( pin "U2D1.W80"
				( objectStatus "@baseboard_fab2_lib.baseboard_fab2(sch_1):page57_i172:ddr0_dq(20)" )
			)
			( pin "U2D1.V79"
				( objectStatus "@baseboard_fab2_lib.baseboard_fab2(sch_1):page57_i172:ddr0_dq(21)" )
			)
			( pin "U2D1.R82"
				( objectStatus "@baseboard_fab2_lib.baseboard_fab2(sch_1):page57_i172:ddr0_dq(22)" )
			)
			( pin "U2D1.N80"
				( objectStatus "@baseboard_fab2_lib.baseboard_fab2(sch_1):page57_i172:ddr0_dq(23)" )
			)
			( pin "U2D1.L76"
				( objectStatus "@baseboard_fab2_lib.baseboard_fab2(sch_1):page57_i172:ddr0_dq(24)" )
			)
			( pin "U2D1.R76"
				( objectStatus "@baseboard_fab2_lib.baseboard_fab2(sch_1):page57_i172:ddr0_dq(25)" )
			)
			( pin "U2D1.M73"
				( objectStatus "@baseboard_fab2_lib.baseboard_fab2(sch_1):page57_i172:ddr0_dq(26)" )
			)
			( pin "U2D1.P73"
				( objectStatus "@baseboard_fab2_lib.baseboard_fab2(sch_1):page57_i172:ddr0_dq(27)" )
			)
			( pin "U2D1.M77"
				( objectStatus "@baseboard_fab2_lib.baseboard_fab2(sch_1):page57_i172:ddr0_dq(28)" )
			)
			( pin "U2D1.P77"
				( objectStatus "@baseboard_fab2_lib.baseboard_fab2(sch_1):page57_i172:ddr0_dq(29)" )
			)
			( pin "U2D1.L74"
				( objectStatus "@baseboard_fab2_lib.baseboard_fab2(sch_1):page57_i172:ddr0_dq(30)" )
			)
			( pin "U2D1.R74"
				( objectStatus "@baseboard_fab2_lib.baseboard_fab2(sch_1):page57_i172:ddr0_dq(31)" )
			)
			( pin "U2D1.C42"
				( objectStatus "@baseboard_fab2_lib.baseboard_fab2(sch_1):page57_i172:ddr0_dq(32)" )
			)
			( pin "U2D1.B41"
				( objectStatus "@baseboard_fab2_lib.baseboard_fab2(sch_1):page57_i172:ddr0_dq(33)" )
			)
			( pin "U2D1.C38"
				( objectStatus "@baseboard_fab2_lib.baseboard_fab2(sch_1):page57_i172:ddr0_dq(34)" )
			)
			( pin "U2D1.E38"
				( objectStatus "@baseboard_fab2_lib.baseboard_fab2(sch_1):page57_i172:ddr0_dq(35)" )
			)
			( pin "U2D1.E42"
				( objectStatus "@baseboard_fab2_lib.baseboard_fab2(sch_1):page57_i172:ddr0_dq(36)" )
			)
			( pin "U2D1.F41"
				( objectStatus "@baseboard_fab2_lib.baseboard_fab2(sch_1):page57_i172:ddr0_dq(37)" )
			)
			( pin "U2D1.B39"
				( objectStatus "@baseboard_fab2_lib.baseboard_fab2(sch_1):page57_i172:ddr0_dq(38)" )
			)
			( pin "U2D1.F39"
				( objectStatus "@baseboard_fab2_lib.baseboard_fab2(sch_1):page57_i172:ddr0_dq(39)" )
			)
			( pin "U2D1.K37"
				( objectStatus "@baseboard_fab2_lib.baseboard_fab2(sch_1):page57_i172:ddr0_dq(40)" )
			)
			( pin "U2D1.P37"
				( objectStatus "@baseboard_fab2_lib.baseboard_fab2(sch_1):page57_i172:ddr0_dq(41)" )
			)
			( pin "U2D1.L34"
				( objectStatus "@baseboard_fab2_lib.baseboard_fab2(sch_1):page57_i172:ddr0_dq(42)" )
			)
			( pin "U2D1.N34"
				( objectStatus "@baseboard_fab2_lib.baseboard_fab2(sch_1):page57_i172:ddr0_dq(43)" )
			)
			( pin "U2D1.L38"
				( objectStatus "@baseboard_fab2_lib.baseboard_fab2(sch_1):page57_i172:ddr0_dq(44)" )
			)
			( pin "U2D1.N38"
				( objectStatus "@baseboard_fab2_lib.baseboard_fab2(sch_1):page57_i172:ddr0_dq(45)" )
			)
			( pin "U2D1.K35"
				( objectStatus "@baseboard_fab2_lib.baseboard_fab2(sch_1):page57_i172:ddr0_dq(46)" )
			)
			( pin "U2D1.P35"
				( objectStatus "@baseboard_fab2_lib.baseboard_fab2(sch_1):page57_i172:ddr0_dq(47)" )
			)
			( pin "U2D1.K31"
				( objectStatus "@baseboard_fab2_lib.baseboard_fab2(sch_1):page57_i172:ddr0_dq(48)" )
			)
			( pin "U2D1.P31"
				( objectStatus "@baseboard_fab2_lib.baseboard_fab2(sch_1):page57_i172:ddr0_dq(49)" )
			)
			( pin "U2D1.L28"
				( objectStatus "@baseboard_fab2_lib.baseboard_fab2(sch_1):page57_i172:ddr0_dq(50)" )
			)
			( pin "U2D1.N28"
				( objectStatus "@baseboard_fab2_lib.baseboard_fab2(sch_1):page57_i172:ddr0_dq(51)" )
			)
			( pin "U2D1.L32"
				( objectStatus "@baseboard_fab2_lib.baseboard_fab2(sch_1):page57_i172:ddr0_dq(52)" )
			)
			( pin "U2D1.N32"
				( objectStatus "@baseboard_fab2_lib.baseboard_fab2(sch_1):page57_i172:ddr0_dq(53)" )
			)
			( pin "U2D1.K29"
				( objectStatus "@baseboard_fab2_lib.baseboard_fab2(sch_1):page57_i172:ddr0_dq(54)" )
			)
			( pin "U2D1.P29"
				( objectStatus "@baseboard_fab2_lib.baseboard_fab2(sch_1):page57_i172:ddr0_dq(55)" )
			)
			( pin "U2D1.K25"
				( objectStatus "@baseboard_fab2_lib.baseboard_fab2(sch_1):page57_i172:ddr0_dq(56)" )
			)
			( pin "U2D1.P25"
				( objectStatus "@baseboard_fab2_lib.baseboard_fab2(sch_1):page57_i172:ddr0_dq(57)" )
			)
			( pin "U2D1.P23"
				( objectStatus "@baseboard_fab2_lib.baseboard_fab2(sch_1):page57_i172:ddr0_dq(58)" )
			)
			( pin "U2D1.T23"
				( objectStatus "@baseboard_fab2_lib.baseboard_fab2(sch_1):page57_i172:ddr0_dq(59)" )
			)
			( pin "U2D1.L26"
				( objectStatus "@baseboard_fab2_lib.baseboard_fab2(sch_1):page57_i172:ddr0_dq(60)" )
			)
			( pin "U2D1.N26"
				( objectStatus "@baseboard_fab2_lib.baseboard_fab2(sch_1):page57_i172:ddr0_dq(61)" )
			)
			( pin "U2D1.H23"
				( objectStatus "@baseboard_fab2_lib.baseboard_fab2(sch_1):page57_i172:ddr0_dq(62)" )
			)
			( pin "U2D1.K23"
				( objectStatus "@baseboard_fab2_lib.baseboard_fab2(sch_1):page57_i172:ddr0_dq(63)" )
			)
			( pin "U2D1.AJ84"
				( objectStatus "@baseboard_fab2_lib.baseboard_fab2(sch_1):page57_i172:ddr0_dqs_dn(0)" )
			)
			( pin "U2D1.R84"
				( objectStatus "@baseboard_fab2_lib.baseboard_fab2(sch_1):page57_i172:ddr0_dqs_dn(1)" )
			)
			( pin "U2D1.P79"
				( objectStatus "@baseboard_fab2_lib.baseboard_fab2(sch_1):page57_i172:ddr0_dqs_dn(2)" )
			)
			( pin "U2D1.T75"
				( objectStatus "@baseboard_fab2_lib.baseboard_fab2(sch_1):page57_i172:ddr0_dqs_dn(3)" )
			)
			( pin "U2D1.G40"
				( objectStatus "@baseboard_fab2_lib.baseboard_fab2(sch_1):page57_i172:ddr0_dqs_dn(4)" )
			)
			( pin "U2D1.R36"
				( objectStatus "@baseboard_fab2_lib.baseboard_fab2(sch_1):page57_i172:ddr0_dqs_dn(5)" )
			)
			( pin "U2D1.R30"
				( objectStatus "@baseboard_fab2_lib.baseboard_fab2(sch_1):page57_i172:ddr0_dqs_dn(6)" )
			)
			( pin "U2D1.N24"
				( objectStatus "@baseboard_fab2_lib.baseboard_fab2(sch_1):page57_i172:ddr0_dqs_dn(7)" )
			)
			( pin "U2D1.AH67"
				( objectStatus "@baseboard_fab2_lib.baseboard_fab2(sch_1):page57_i172:ddr0_dqs_dn(8)" )
			)
			( pin "U2D1.AL84"
				( objectStatus "@baseboard_fab2_lib.baseboard_fab2(sch_1):page57_i172:ddr0_dqs_dn(9)" )
			)
			( pin "U2D1.U84"
				( objectStatus "@baseboard_fab2_lib.baseboard_fab2(sch_1):page57_i172:ddr0_dqs_dn(10)" )
			)
			( pin "U2D1.U82"
				( objectStatus "@baseboard_fab2_lib.baseboard_fab2(sch_1):page57_i172:ddr0_dqs_dn(11)" )
			)
			( pin "U2D1.K75"
				( objectStatus "@baseboard_fab2_lib.baseboard_fab2(sch_1):page57_i172:ddr0_dqs_dn(12)" )
			)
			( pin "U2D1.A40"
				( objectStatus "@baseboard_fab2_lib.baseboard_fab2(sch_1):page57_i172:ddr0_dqs_dn(13)" )
			)
			( pin "U2D1.J36"
				( objectStatus "@baseboard_fab2_lib.baseboard_fab2(sch_1):page57_i172:ddr0_dqs_dn(14)" )
			)
			( pin "U2D1.J30"
				( objectStatus "@baseboard_fab2_lib.baseboard_fab2(sch_1):page57_i172:ddr0_dqs_dn(15)" )
			)
			( pin "U2D1.J24"
				( objectStatus "@baseboard_fab2_lib.baseboard_fab2(sch_1):page57_i172:ddr0_dqs_dn(16)" )
			)
			( pin "U2D1.AB67"
				( objectStatus "@baseboard_fab2_lib.baseboard_fab2(sch_1):page57_i172:ddr0_dqs_dn(17)" )
			)
			( pin "U2D1.AH85"
				( objectStatus "@baseboard_fab2_lib.baseboard_fab2(sch_1):page57_i172:ddr0_dqs_dp(0)" )
			)
			( pin "U2D1.P85"
				( objectStatus "@baseboard_fab2_lib.baseboard_fab2(sch_1):page57_i172:ddr0_dqs_dp(1)" )
			)
			( pin "U2D1.R80"
				( objectStatus "@baseboard_fab2_lib.baseboard_fab2(sch_1):page57_i172:ddr0_dqs_dp(2)" )
			)
			( pin "U2D1.P75"
				( objectStatus "@baseboard_fab2_lib.baseboard_fab2(sch_1):page57_i172:ddr0_dqs_dp(3)" )
			)
			( pin "U2D1.E40"
				( objectStatus "@baseboard_fab2_lib.baseboard_fab2(sch_1):page57_i172:ddr0_dqs_dp(4)" )
			)
			( pin "U2D1.N36"
				( objectStatus "@baseboard_fab2_lib.baseboard_fab2(sch_1):page57_i172:ddr0_dqs_dp(5)" )
			)
			( pin "U2D1.N30"
				( objectStatus "@baseboard_fab2_lib.baseboard_fab2(sch_1):page57_i172:ddr0_dqs_dp(6)" )
			)
			( pin "U2D1.R24"
				( objectStatus "@baseboard_fab2_lib.baseboard_fab2(sch_1):page57_i172:ddr0_dqs_dp(7)" )
			)
			( pin "U2D1.AF67"
				( objectStatus "@baseboard_fab2_lib.baseboard_fab2(sch_1):page57_i172:ddr0_dqs_dp(8)" )
			)
			( pin "U2D1.AM85"
				( objectStatus "@baseboard_fab2_lib.baseboard_fab2(sch_1):page57_i172:ddr0_dqs_dp(9)" )
			)
			( pin "U2D1.V85"
				( objectStatus "@baseboard_fab2_lib.baseboard_fab2(sch_1):page57_i172:ddr0_dqs_dp(10)" )
			)
			( pin "U2D1.T81"
				( objectStatus "@baseboard_fab2_lib.baseboard_fab2(sch_1):page57_i172:ddr0_dqs_dp(11)" )
			)
			( pin "U2D1.M75"
				( objectStatus "@baseboard_fab2_lib.baseboard_fab2(sch_1):page57_i172:ddr0_dqs_dp(12)" )
			)
			( pin "U2D1.C40"
				( objectStatus "@baseboard_fab2_lib.baseboard_fab2(sch_1):page57_i172:ddr0_dqs_dp(13)" )
			)
			( pin "U2D1.L36"
				( objectStatus "@baseboard_fab2_lib.baseboard_fab2(sch_1):page57_i172:ddr0_dqs_dp(14)" )
			)
			( pin "U2D1.L30"
				( objectStatus "@baseboard_fab2_lib.baseboard_fab2(sch_1):page57_i172:ddr0_dqs_dp(15)" )
			)
			( pin "U2D1.L24"
				( objectStatus "@baseboard_fab2_lib.baseboard_fab2(sch_1):page57_i172:ddr0_dqs_dp(16)" )
			)
			( pin "U2D1.AD67"
				( objectStatus "@baseboard_fab2_lib.baseboard_fab2(sch_1):page57_i172:ddr0_dqs_dp(17)" )
			)
			( pin "U2D1.AC68"
				( objectStatus "@baseboard_fab2_lib.baseboard_fab2(sch_1):page57_i172:ddr0_ecc(0)" )
			)
			( pin "U2D1.AG68"
				( objectStatus "@baseboard_fab2_lib.baseboard_fab2(sch_1):page57_i172:ddr0_ecc(1)" )
			)
			( pin "U2D1.AD65"
				( objectStatus "@baseboard_fab2_lib.baseboard_fab2(sch_1):page57_i172:ddr0_ecc(2)" )
			)
			( pin "U2D1.AF65"
				( objectStatus "@baseboard_fab2_lib.baseboard_fab2(sch_1):page57_i172:ddr0_ecc(3)" )
			)
			( pin "U2D1.AD69"
				( objectStatus "@baseboard_fab2_lib.baseboard_fab2(sch_1):page57_i172:ddr0_ecc(4)" )
			)
			( pin "U2D1.AF69"
				( objectStatus "@baseboard_fab2_lib.baseboard_fab2(sch_1):page57_i172:ddr0_ecc(5)" )
			)
			( pin "U2D1.AC66"
				( objectStatus "@baseboard_fab2_lib.baseboard_fab2(sch_1):page57_i172:ddr0_ecc(6)" )
			)
			( pin "U2D1.AG66"
				( objectStatus "@baseboard_fab2_lib.baseboard_fab2(sch_1):page57_i172:ddr0_ecc(7)" )
			)
			( pin "U2D1.F53"
				( objectStatus "@baseboard_fab2_lib.baseboard_fab2(sch_1):page57_i172:ddr0_ma(0)" )
			)
			( pin "U2D1.F57"
				( objectStatus "@baseboard_fab2_lib.baseboard_fab2(sch_1):page57_i172:ddr0_ma(1)" )
			)
			( pin "U2D1.D57"
				( objectStatus "@baseboard_fab2_lib.baseboard_fab2(sch_1):page57_i172:ddr0_ma(2)" )
			)
			( pin "U2D1.C58"
				( objectStatus "@baseboard_fab2_lib.baseboard_fab2(sch_1):page57_i172:ddr0_ma(3)" )
			)
			( pin "U2D1.G58"
				( objectStatus "@baseboard_fab2_lib.baseboard_fab2(sch_1):page57_i172:ddr0_ma(4)" )
			)
			( pin "U2D1.F59"
				( objectStatus "@baseboard_fab2_lib.baseboard_fab2(sch_1):page57_i172:ddr0_ma(5)" )
			)
			( pin "U2D1.D59"
				( objectStatus "@baseboard_fab2_lib.baseboard_fab2(sch_1):page57_i172:ddr0_ma(6)" )
			)
			( pin "U2D1.G60"
				( objectStatus "@baseboard_fab2_lib.baseboard_fab2(sch_1):page57_i172:ddr0_ma(7)" )
			)
			( pin "U2D1.C60"
				( objectStatus "@baseboard_fab2_lib.baseboard_fab2(sch_1):page57_i172:ddr0_ma(8)" )
			)
			( pin "U2D1.F61"
				( objectStatus "@baseboard_fab2_lib.baseboard_fab2(sch_1):page57_i172:ddr0_ma(9)" )
			)
			( pin "U2D1.J54"
				( objectStatus "@baseboard_fab2_lib.baseboard_fab2(sch_1):page57_i172:ddr0_ma(10)" )
			)
			( pin "U2D1.G62"
				( objectStatus "@baseboard_fab2_lib.baseboard_fab2(sch_1):page57_i172:ddr0_ma(11)" )
			)
			( pin "U2D1.J64"
				( objectStatus "@baseboard_fab2_lib.baseboard_fab2(sch_1):page57_i172:ddr0_ma(12)" )
			)
			( pin "U2D1.J48"
				( objectStatus "@baseboard_fab2_lib.baseboard_fab2(sch_1):page57_i172:ddr0_ma(13)" )
			)
			( pin "U2D1.F51"
				( objectStatus "@baseboard_fab2_lib.baseboard_fab2(sch_1):page57_i172:ddr0_ma(14)" )
			)
			( pin "U2D1.K49"
				( objectStatus "@baseboard_fab2_lib.baseboard_fab2(sch_1):page57_i172:ddr0_ma(15)" )
			)
			( pin "U2D1.D51"
				( objectStatus "@baseboard_fab2_lib.baseboard_fab2(sch_1):page57_i172:ddr0_ma(16)" )
			)
			( pin "U2D1.K47"
				( objectStatus "@baseboard_fab2_lib.baseboard_fab2(sch_1):page57_i172:ddr0_ma(17)" )
			)
			( pin "U2D1.C50"
				( objectStatus "@baseboard_fab2_lib.baseboard_fab2(sch_1):page57_i172:ddr0_odt(0)" )
			)
			( pin "U2D1.C48"
				( objectStatus "@baseboard_fab2_lib.baseboard_fab2(sch_1):page57_i172:ddr0_odt(1)" )
			)
			( pin "U2D1.G50"
				( objectStatus "@baseboard_fab2_lib.baseboard_fab2(sch_1):page57_i172:ddr0_odt(2)" )
			)
			( pin "U2D1.G48"
				( objectStatus "@baseboard_fab2_lib.baseboard_fab2(sch_1):page57_i172:ddr0_odt(3)" )
			)
			( pin "U2D1.D53"
				( objectStatus "@baseboard_fab2_lib.baseboard_fab2(sch_1):page57_i172:ddr0_par" )
			)
			( pin "U2D1.T63"
				( objectStatus "@baseboard_fab2_lib.baseboard_fab2(sch_1):page58_i172:ddr1_act_n" )
			)
			( pin "U2D1.W62"
				( objectStatus "@baseboard_fab2_lib.baseboard_fab2(sch_1):page58_i172:ddr1_alert_n" )
			)
			( pin "U2D1.T53"
				( objectStatus "@baseboard_fab2_lib.baseboard_fab2(sch_1):page58_i172:ddr1_ba(0)" )
			)
			( pin "U2D1.K55"
				( objectStatus "@baseboard_fab2_lib.baseboard_fab2(sch_1):page58_i172:ddr1_ba(1)" )
			)
			( pin "U2D1.M61"
				( objectStatus "@baseboard_fab2_lib.baseboard_fab2(sch_1):page58_i172:ddr1_bg(0)" )
			)
			( pin "U2D1.N60"
				( objectStatus "@baseboard_fab2_lib.baseboard_fab2(sch_1):page58_i172:ddr1_bg(1)" )
			)
			( pin "U2D1.M47"
				( objectStatus "@baseboard_fab2_lib.baseboard_fab2(sch_1):page58_i172:ddr1_cid(2)" )
			)
			( pin "U2D1.N62"
				( objectStatus "@baseboard_fab2_lib.baseboard_fab2(sch_1):page58_i172:ddr1_cke(0)" )
			)
			( pin "U2D1.R64"
				( objectStatus "@baseboard_fab2_lib.baseboard_fab2(sch_1):page58_i172:ddr1_cke(1)" )
			)
			( pin "U2D1.K63"
				( objectStatus "@baseboard_fab2_lib.baseboard_fab2(sch_1):page58_i172:ddr1_cke(2)" )
			)
			( pin "U2D1.L64"
				( objectStatus "@baseboard_fab2_lib.baseboard_fab2(sch_1):page58_i172:ddr1_cke(3)" )
			)
			( pin "U2D1.M53"
				( objectStatus "@baseboard_fab2_lib.baseboard_fab2(sch_1):page58_i172:ddr1_clk_dn(0)" )
			)
			( pin "U2D1.R54"
				( objectStatus "@baseboard_fab2_lib.baseboard_fab2(sch_1):page58_i172:ddr1_clk_dn(1)" )
			)
			( pin "U2D1.N56"
				( objectStatus "@baseboard_fab2_lib.baseboard_fab2(sch_1):page58_i172:ddr1_clk_dn(2)" )
			)
			( pin "U2D1.R56"
				( objectStatus "@baseboard_fab2_lib.baseboard_fab2(sch_1):page58_i172:ddr1_clk_dn(3)" )
			)
			( pin "U2D1.N54"
				( objectStatus "@baseboard_fab2_lib.baseboard_fab2(sch_1):page58_i172:ddr1_clk_dp(0)" )
			)
			( pin "U2D1.T55"
				( objectStatus "@baseboard_fab2_lib.baseboard_fab2(sch_1):page58_i172:ddr1_clk_dp(1)" )
			)
			( pin "U2D1.M57"
				( objectStatus "@baseboard_fab2_lib.baseboard_fab2(sch_1):page58_i172:ddr1_clk_dp(2)" )
			)
			( pin "U2D1.T57"
				( objectStatus "@baseboard_fab2_lib.baseboard_fab2(sch_1):page58_i172:ddr1_clk_dp(3)" )
			)
			( pin "U2D1.K51"
				( objectStatus "@baseboard_fab2_lib.baseboard_fab2(sch_1):page58_i172:ddr1_cs_n(0)" )
			)
			( pin "U2D1.R50"
				( objectStatus "@baseboard_fab2_lib.baseboard_fab2(sch_1):page58_i172:ddr1_cs_n(1)" )
			)
			( pin "U2D1.N46"
				( objectStatus "@baseboard_fab2_lib.baseboard_fab2(sch_1):page58_i172:ddr1_cs_n(2)" )
			)
			( pin "U2D1.V47"
				( objectStatus "@baseboard_fab2_lib.baseboard_fab2(sch_1):page58_i172:ddr1_cs_n(3)" )
			)
			( pin "U2D1.J50"
				( objectStatus "@baseboard_fab2_lib.baseboard_fab2(sch_1):page58_i172:ddr1_cs_n(4)" )
			)
			( pin "U2D1.T49"
				( objectStatus "@baseboard_fab2_lib.baseboard_fab2(sch_1):page58_i172:ddr1_cs_n(5)" )
			)
			( pin "U2D1.M45"
				( objectStatus "@baseboard_fab2_lib.baseboard_fab2(sch_1):page58_i172:ddr1_cs_n(6)" )
			)
			( pin "U2D1.R46"
				( objectStatus "@baseboard_fab2_lib.baseboard_fab2(sch_1):page58_i172:ddr1_cs_n(7)" )
			)
			( pin "U2D1.AV81"
				( objectStatus "@baseboard_fab2_lib.baseboard_fab2(sch_1):page58_i172:ddr1_dq(0)" )
			)
			( pin "U2D1.AT79"
				( objectStatus "@baseboard_fab2_lib.baseboard_fab2(sch_1):page58_i172:ddr1_dq(1)" )
			)
			( pin "U2D1.AN82"
				( objectStatus "@baseboard_fab2_lib.baseboard_fab2(sch_1):page58_i172:ddr1_dq(2)" )
			)
			( pin "U2D1.AM81"
				( objectStatus "@baseboard_fab2_lib.baseboard_fab2(sch_1):page58_i172:ddr1_dq(3)" )
			)
			( pin "U2D1.AW80"
				( objectStatus "@baseboard_fab2_lib.baseboard_fab2(sch_1):page58_i172:ddr1_dq(4)" )
			)
			( pin "U2D1.AV79"
				( objectStatus "@baseboard_fab2_lib.baseboard_fab2(sch_1):page58_i172:ddr1_dq(5)" )
			)
			( pin "U2D1.AR82"
				( objectStatus "@baseboard_fab2_lib.baseboard_fab2(sch_1):page58_i172:ddr1_dq(6)" )
			)
			( pin "U2D1.AN80"
				( objectStatus "@baseboard_fab2_lib.baseboard_fab2(sch_1):page58_i172:ddr1_dq(7)" )
			)
			( pin "U2D1.AH81"
				( objectStatus "@baseboard_fab2_lib.baseboard_fab2(sch_1):page58_i172:ddr1_dq(8)" )
			)
			( pin "U2D1.AF79"
				( objectStatus "@baseboard_fab2_lib.baseboard_fab2(sch_1):page58_i172:ddr1_dq(9)" )
			)
			( pin "U2D1.AC82"
				( objectStatus "@baseboard_fab2_lib.baseboard_fab2(sch_1):page58_i172:ddr1_dq(10)" )
			)
			( pin "U2D1.AB81"
				( objectStatus "@baseboard_fab2_lib.baseboard_fab2(sch_1):page58_i172:ddr1_dq(11)" )
			)
			( pin "U2D1.AJ80"
				( objectStatus "@baseboard_fab2_lib.baseboard_fab2(sch_1):page58_i172:ddr1_dq(12)" )
			)
			( pin "U2D1.AH79"
				( objectStatus "@baseboard_fab2_lib.baseboard_fab2(sch_1):page58_i172:ddr1_dq(13)" )
			)
			( pin "U2D1.AE82"
				( objectStatus "@baseboard_fab2_lib.baseboard_fab2(sch_1):page58_i172:ddr1_dq(14)" )
			)
			( pin "U2D1.AC80"
				( objectStatus "@baseboard_fab2_lib.baseboard_fab2(sch_1):page58_i172:ddr1_dq(15)" )
			)
			( pin "U2D1.E80"
				( objectStatus "@baseboard_fab2_lib.baseboard_fab2(sch_1):page58_i172:ddr1_dq(16)" )
			)
			( pin "U2D1.J80"
				( objectStatus "@baseboard_fab2_lib.baseboard_fab2(sch_1):page58_i172:ddr1_dq(17)" )
			)
			( pin "U2D1.F77"
				( objectStatus "@baseboard_fab2_lib.baseboard_fab2(sch_1):page58_i172:ddr1_dq(18)" )
			)
			( pin "U2D1.H77"
				( objectStatus "@baseboard_fab2_lib.baseboard_fab2(sch_1):page58_i172:ddr1_dq(19)" )
			)
			( pin "U2D1.F81"
				( objectStatus "@baseboard_fab2_lib.baseboard_fab2(sch_1):page58_i172:ddr1_dq(20)" )
			)
			( pin "U2D1.H81"
				( objectStatus "@baseboard_fab2_lib.baseboard_fab2(sch_1):page58_i172:ddr1_dq(21)" )
			)
			( pin "U2D1.E78"
				( objectStatus "@baseboard_fab2_lib.baseboard_fab2(sch_1):page58_i172:ddr1_dq(22)" )
			)
			( pin "U2D1.J78"
				( objectStatus "@baseboard_fab2_lib.baseboard_fab2(sch_1):page58_i172:ddr1_dq(23)" )
			)
			( pin "U2D1.D75"
				( objectStatus "@baseboard_fab2_lib.baseboard_fab2(sch_1):page58_i172:ddr1_dq(24)" )
			)
			( pin "U2D1.C74"
				( objectStatus "@baseboard_fab2_lib.baseboard_fab2(sch_1):page58_i172:ddr1_dq(25)" )
			)
			( pin "U2D1.D71"
				( objectStatus "@baseboard_fab2_lib.baseboard_fab2(sch_1):page58_i172:ddr1_dq(26)" )
			)
			( pin "U2D1.F71"
				( objectStatus "@baseboard_fab2_lib.baseboard_fab2(sch_1):page58_i172:ddr1_dq(27)" )
			)
			( pin "U2D1.F75"
				( objectStatus "@baseboard_fab2_lib.baseboard_fab2(sch_1):page58_i172:ddr1_dq(28)" )
			)
			( pin "U2D1.G74"
				( objectStatus "@baseboard_fab2_lib.baseboard_fab2(sch_1):page58_i172:ddr1_dq(29)" )
			)
			( pin "U2D1.C72"
				( objectStatus "@baseboard_fab2_lib.baseboard_fab2(sch_1):page58_i172:ddr1_dq(30)" )
			)
			( pin "U2D1.G72"
				( objectStatus "@baseboard_fab2_lib.baseboard_fab2(sch_1):page58_i172:ddr1_dq(31)" )
			)
			( pin "U2D1.K43"
				( objectStatus "@baseboard_fab2_lib.baseboard_fab2(sch_1):page58_i172:ddr1_dq(32)" )
			)
			( pin "U2D1.H43"
				( objectStatus "@baseboard_fab2_lib.baseboard_fab2(sch_1):page58_i172:ddr1_dq(33)" )
			)
			( pin "U2D1.L40"
				( objectStatus "@baseboard_fab2_lib.baseboard_fab2(sch_1):page58_i172:ddr1_dq(34)" )
			)
			( pin "U2D1.N40"
				( objectStatus "@baseboard_fab2_lib.baseboard_fab2(sch_1):page58_i172:ddr1_dq(35)" )
			)
			( pin "U2D1.P43"
				( objectStatus "@baseboard_fab2_lib.baseboard_fab2(sch_1):page58_i172:ddr1_dq(36)" )
			)
			( pin "U2D1.T43"
				( objectStatus "@baseboard_fab2_lib.baseboard_fab2(sch_1):page58_i172:ddr1_dq(37)" )
			)
			( pin "U2D1.K41"
				( objectStatus "@baseboard_fab2_lib.baseboard_fab2(sch_1):page58_i172:ddr1_dq(38)" )
			)
			( pin "U2D1.P41"
				( objectStatus "@baseboard_fab2_lib.baseboard_fab2(sch_1):page58_i172:ddr1_dq(39)" )
			)
			( pin "U2D1.C36"
				( objectStatus "@baseboard_fab2_lib.baseboard_fab2(sch_1):page58_i172:ddr1_dq(40)" )
			)
			( pin "U2D1.B35"
				( objectStatus "@baseboard_fab2_lib.baseboard_fab2(sch_1):page58_i172:ddr1_dq(41)" )
			)
			( pin "U2D1.C32"
				( objectStatus "@baseboard_fab2_lib.baseboard_fab2(sch_1):page58_i172:ddr1_dq(42)" )
			)
			( pin "U2D1.E32"
				( objectStatus "@baseboard_fab2_lib.baseboard_fab2(sch_1):page58_i172:ddr1_dq(43)" )
			)
			( pin "U2D1.E36"
				( objectStatus "@baseboard_fab2_lib.baseboard_fab2(sch_1):page58_i172:ddr1_dq(44)" )
			)
			( pin "U2D1.F35"
				( objectStatus "@baseboard_fab2_lib.baseboard_fab2(sch_1):page58_i172:ddr1_dq(45)" )
			)
			( pin "U2D1.B33"
				( objectStatus "@baseboard_fab2_lib.baseboard_fab2(sch_1):page58_i172:ddr1_dq(46)" )
			)
			( pin "U2D1.F33"
				( objectStatus "@baseboard_fab2_lib.baseboard_fab2(sch_1):page58_i172:ddr1_dq(47)" )
			)
			( pin "U2D1.C30"
				( objectStatus "@baseboard_fab2_lib.baseboard_fab2(sch_1):page58_i172:ddr1_dq(48)" )
			)
			( pin "U2D1.B29"
				( objectStatus "@baseboard_fab2_lib.baseboard_fab2(sch_1):page58_i172:ddr1_dq(49)" )
			)
			( pin "U2D1.C26"
				( objectStatus "@baseboard_fab2_lib.baseboard_fab2(sch_1):page58_i172:ddr1_dq(50)" )
			)
			( pin "U2D1.E26"
				( objectStatus "@baseboard_fab2_lib.baseboard_fab2(sch_1):page58_i172:ddr1_dq(51)" )
			)
			( pin "U2D1.E30"
				( objectStatus "@baseboard_fab2_lib.baseboard_fab2(sch_1):page58_i172:ddr1_dq(52)" )
			)
			( pin "U2D1.F29"
				( objectStatus "@baseboard_fab2_lib.baseboard_fab2(sch_1):page58_i172:ddr1_dq(53)" )
			)
			( pin "U2D1.B27"
				( objectStatus "@baseboard_fab2_lib.baseboard_fab2(sch_1):page58_i172:ddr1_dq(54)" )
			)
			( pin "U2D1.F27"
				( objectStatus "@baseboard_fab2_lib.baseboard_fab2(sch_1):page58_i172:ddr1_dq(55)" )
			)
			( pin "U2D1.U28"
				( objectStatus "@baseboard_fab2_lib.baseboard_fab2(sch_1):page58_i172:ddr1_dq(56)" )
			)
			( pin "U2D1.AA28"
				( objectStatus "@baseboard_fab2_lib.baseboard_fab2(sch_1):page58_i172:ddr1_dq(57)" )
			)
			( pin "U2D1.V25"
				( objectStatus "@baseboard_fab2_lib.baseboard_fab2(sch_1):page58_i172:ddr1_dq(58)" )
			)
			( pin "U2D1.Y25"
				( objectStatus "@baseboard_fab2_lib.baseboard_fab2(sch_1):page58_i172:ddr1_dq(59)" )
			)
			( pin "U2D1.V29"
				( objectStatus "@baseboard_fab2_lib.baseboard_fab2(sch_1):page58_i172:ddr1_dq(60)" )
			)
			( pin "U2D1.Y29"
				( objectStatus "@baseboard_fab2_lib.baseboard_fab2(sch_1):page58_i172:ddr1_dq(61)" )
			)
			( pin "U2D1.U26"
				( objectStatus "@baseboard_fab2_lib.baseboard_fab2(sch_1):page58_i172:ddr1_dq(62)" )
			)
			( pin "U2D1.AA26"
				( objectStatus "@baseboard_fab2_lib.baseboard_fab2(sch_1):page58_i172:ddr1_dq(63)" )
			)
			( pin "U2D1.AP79"
				( objectStatus "@baseboard_fab2_lib.baseboard_fab2(sch_1):page58_i172:ddr1_dqs_dn(0)" )
			)
			( pin "U2D1.AD79"
				( objectStatus "@baseboard_fab2_lib.baseboard_fab2(sch_1):page58_i172:ddr1_dqs_dn(1)" )
			)
			( pin "U2D1.K79"
				( objectStatus "@baseboard_fab2_lib.baseboard_fab2(sch_1):page58_i172:ddr1_dqs_dn(2)" )
			)
			( pin "U2D1.H73"
				( objectStatus "@baseboard_fab2_lib.baseboard_fab2(sch_1):page58_i172:ddr1_dqs_dn(3)" )
			)
			( pin "U2D1.N42"
				( objectStatus "@baseboard_fab2_lib.baseboard_fab2(sch_1):page58_i172:ddr1_dqs_dn(4)" )
			)
			( pin "U2D1.G34"
				( objectStatus "@baseboard_fab2_lib.baseboard_fab2(sch_1):page58_i172:ddr1_dqs_dn(5)" )
			)
			( pin "U2D1.G28"
				( objectStatus "@baseboard_fab2_lib.baseboard_fab2(sch_1):page58_i172:ddr1_dqs_dn(6)" )
			)
			( pin "U2D1.AB27"
				( objectStatus "@baseboard_fab2_lib.baseboard_fab2(sch_1):page58_i172:ddr1_dqs_dn(7)" )
			)
			( pin "U2D1.N68"
				( objectStatus "@baseboard_fab2_lib.baseboard_fab2(sch_1):page58_i172:ddr1_dqs_dn(8)" )
			)
			( pin "U2D1.AU82"
				( objectStatus "@baseboard_fab2_lib.baseboard_fab2(sch_1):page58_i172:ddr1_dqs_dn(9)" )
			)
			( pin "U2D1.AG82"
				( objectStatus "@baseboard_fab2_lib.baseboard_fab2(sch_1):page58_i172:ddr1_dqs_dn(10)" )
			)
			( pin "U2D1.D79"
				( objectStatus "@baseboard_fab2_lib.baseboard_fab2(sch_1):page58_i172:ddr1_dqs_dn(11)" )
			)
			( pin "U2D1.B73"
				( objectStatus "@baseboard_fab2_lib.baseboard_fab2(sch_1):page58_i172:ddr1_dqs_dn(12)" )
			)
			( pin "U2D1.J42"
				( objectStatus "@baseboard_fab2_lib.baseboard_fab2(sch_1):page58_i172:ddr1_dqs_dn(13)" )
			)
			( pin "U2D1.A34"
				( objectStatus "@baseboard_fab2_lib.baseboard_fab2(sch_1):page58_i172:ddr1_dqs_dn(14)" )
			)
			( pin "U2D1.A28"
				( objectStatus "@baseboard_fab2_lib.baseboard_fab2(sch_1):page58_i172:ddr1_dqs_dn(15)" )
			)
			( pin "U2D1.T27"
				( objectStatus "@baseboard_fab2_lib.baseboard_fab2(sch_1):page58_i172:ddr1_dqs_dn(16)" )
			)
			( pin "U2D1.G68"
				( objectStatus "@baseboard_fab2_lib.baseboard_fab2(sch_1):page58_i172:ddr1_dqs_dn(17)" )
			)
			( pin "U2D1.AR80"
				( objectStatus "@baseboard_fab2_lib.baseboard_fab2(sch_1):page58_i172:ddr1_dqs_dp(0)" )
			)
			( pin "U2D1.AE80"
				( objectStatus "@baseboard_fab2_lib.baseboard_fab2(sch_1):page58_i172:ddr1_dqs_dp(1)" )
			)
			( pin "U2D1.H79"
				( objectStatus "@baseboard_fab2_lib.baseboard_fab2(sch_1):page58_i172:ddr1_dqs_dp(2)" )
			)
			( pin "U2D1.F73"
				( objectStatus "@baseboard_fab2_lib.baseboard_fab2(sch_1):page58_i172:ddr1_dqs_dp(3)" )
			)
			( pin "U2D1.R42"
				( objectStatus "@baseboard_fab2_lib.baseboard_fab2(sch_1):page58_i172:ddr1_dqs_dp(4)" )
			)
			( pin "U2D1.E34"
				( objectStatus "@baseboard_fab2_lib.baseboard_fab2(sch_1):page58_i172:ddr1_dqs_dp(5)" )
			)
			( pin "U2D1.E28"
				( objectStatus "@baseboard_fab2_lib.baseboard_fab2(sch_1):page58_i172:ddr1_dqs_dp(6)" )
			)
			( pin "U2D1.Y27"
				( objectStatus "@baseboard_fab2_lib.baseboard_fab2(sch_1):page58_i172:ddr1_dqs_dp(7)" )
			)
			( pin "U2D1.L68"
				( objectStatus "@baseboard_fab2_lib.baseboard_fab2(sch_1):page58_i172:ddr1_dqs_dp(8)" )
			)
			( pin "U2D1.AT81"
				( objectStatus "@baseboard_fab2_lib.baseboard_fab2(sch_1):page58_i172:ddr1_dqs_dp(9)" )
			)
			( pin "U2D1.AF81"
				( objectStatus "@baseboard_fab2_lib.baseboard_fab2(sch_1):page58_i172:ddr1_dqs_dp(10)" )
			)
			( pin "U2D1.F79"
				( objectStatus "@baseboard_fab2_lib.baseboard_fab2(sch_1):page58_i172:ddr1_dqs_dp(11)" )
			)
			( pin "U2D1.D73"
				( objectStatus "@baseboard_fab2_lib.baseboard_fab2(sch_1):page58_i172:ddr1_dqs_dp(12)" )
			)
			( pin "U2D1.L42"
				( objectStatus "@baseboard_fab2_lib.baseboard_fab2(sch_1):page58_i172:ddr1_dqs_dp(13)" )
			)
			( pin "U2D1.C34"
				( objectStatus "@baseboard_fab2_lib.baseboard_fab2(sch_1):page58_i172:ddr1_dqs_dp(14)" )
			)
			( pin "U2D1.C28"
				( objectStatus "@baseboard_fab2_lib.baseboard_fab2(sch_1):page58_i172:ddr1_dqs_dp(15)" )
			)
			( pin "U2D1.V27"
				( objectStatus "@baseboard_fab2_lib.baseboard_fab2(sch_1):page58_i172:ddr1_dqs_dp(16)" )
			)
			( pin "U2D1.J68"
				( objectStatus "@baseboard_fab2_lib.baseboard_fab2(sch_1):page58_i172:ddr1_dqs_dp(17)" )
			)
			( pin "U2D1.J70"
				( objectStatus "@baseboard_fab2_lib.baseboard_fab2(sch_1):page58_i172:ddr1_ecc(0)" )
			)
			( pin "U2D1.H69"
				( objectStatus "@baseboard_fab2_lib.baseboard_fab2(sch_1):page58_i172:ddr1_ecc(1)" )
			)
			( pin "U2D1.J66"
				( objectStatus "@baseboard_fab2_lib.baseboard_fab2(sch_1):page58_i172:ddr1_ecc(2)" )
			)
			( pin "U2D1.L66"
				( objectStatus "@baseboard_fab2_lib.baseboard_fab2(sch_1):page58_i172:ddr1_ecc(3)" )
			)
			( pin "U2D1.L70"
				( objectStatus "@baseboard_fab2_lib.baseboard_fab2(sch_1):page58_i172:ddr1_ecc(4)" )
			)
			( pin "U2D1.M69"
				( objectStatus "@baseboard_fab2_lib.baseboard_fab2(sch_1):page58_i172:ddr1_ecc(5)" )
			)
			( pin "U2D1.H67"
				( objectStatus "@baseboard_fab2_lib.baseboard_fab2(sch_1):page58_i172:ddr1_ecc(6)" )
			)
			( pin "U2D1.M67"
				( objectStatus "@baseboard_fab2_lib.baseboard_fab2(sch_1):page58_i172:ddr1_ecc(7)" )
			)
			( pin "U2D1.J52"
				( objectStatus "@baseboard_fab2_lib.baseboard_fab2(sch_1):page58_i172:ddr1_ma(0)" )
			)
			( pin "U2D1.J58"
				( objectStatus "@baseboard_fab2_lib.baseboard_fab2(sch_1):page58_i172:ddr1_ma(1)" )
			)
			( pin "U2D1.K57"
				( objectStatus "@baseboard_fab2_lib.baseboard_fab2(sch_1):page58_i172:ddr1_ma(2)" )
			)
			( pin "U2D1.N58"
				( objectStatus "@baseboard_fab2_lib.baseboard_fab2(sch_1):page58_i172:ddr1_ma(3)" )
			)
			( pin "U2D1.M59"
				( objectStatus "@baseboard_fab2_lib.baseboard_fab2(sch_1):page58_i172:ddr1_ma(4)" )
			)
			( pin "U2D1.R58"
				( objectStatus "@baseboard_fab2_lib.baseboard_fab2(sch_1):page58_i172:ddr1_ma(5)" )
			)
			( pin "U2D1.T59"
				( objectStatus "@baseboard_fab2_lib.baseboard_fab2(sch_1):page58_i172:ddr1_ma(6)" )
			)
			( pin "U2D1.V61"
				( objectStatus "@baseboard_fab2_lib.baseboard_fab2(sch_1):page58_i172:ddr1_ma(7)" )
			)
			( pin "U2D1.W60"
				( objectStatus "@baseboard_fab2_lib.baseboard_fab2(sch_1):page58_i172:ddr1_ma(8)" )
			)
			( pin "U2D1.K59"
				( objectStatus "@baseboard_fab2_lib.baseboard_fab2(sch_1):page58_i172:ddr1_ma(9)" )
			)
			( pin "U2D1.M55"
				( objectStatus "@baseboard_fab2_lib.baseboard_fab2(sch_1):page58_i172:ddr1_ma(10)" )
			)
			( pin "U2D1.R60"
				( objectStatus "@baseboard_fab2_lib.baseboard_fab2(sch_1):page58_i172:ddr1_ma(11)" )
			)
			( pin "U2D1.T61"
				( objectStatus "@baseboard_fab2_lib.baseboard_fab2(sch_1):page58_i172:ddr1_ma(12)" )
			)
			( pin "U2D1.M51"
				( objectStatus "@baseboard_fab2_lib.baseboard_fab2(sch_1):page58_i172:ddr1_ma(13)" )
			)
			( pin "U2D1.T51"
				( objectStatus "@baseboard_fab2_lib.baseboard_fab2(sch_1):page58_i172:ddr1_ma(14)" )
			)
			( pin "U2D1.N52"
				( objectStatus "@baseboard_fab2_lib.baseboard_fab2(sch_1):page58_i172:ddr1_ma(15)" )
			)
			( pin "U2D1.R52"
				( objectStatus "@baseboard_fab2_lib.baseboard_fab2(sch_1):page58_i172:ddr1_ma(16)" )
			)
			( pin "U2D1.N48"
				( objectStatus "@baseboard_fab2_lib.baseboard_fab2(sch_1):page58_i172:ddr1_ma(17)" )
			)
			( pin "U2D1.N50"
				( objectStatus "@baseboard_fab2_lib.baseboard_fab2(sch_1):page58_i172:ddr1_odt(0)" )
			)
			( pin "U2D1.R48"
				( objectStatus "@baseboard_fab2_lib.baseboard_fab2(sch_1):page58_i172:ddr1_odt(1)" )
			)
			( pin "U2D1.M49"
				( objectStatus "@baseboard_fab2_lib.baseboard_fab2(sch_1):page58_i172:ddr1_odt(2)" )
			)
			( pin "U2D1.T47"
				( objectStatus "@baseboard_fab2_lib.baseboard_fab2(sch_1):page58_i172:ddr1_odt(3)" )
			)
			( pin "U2D1.K53"
				( objectStatus "@baseboard_fab2_lib.baseboard_fab2(sch_1):page58_i172:ddr1_par" )
			)
			( pin "U2D1.AB61"
				( objectStatus "@baseboard_fab2_lib.baseboard_fab2(sch_1):page59_i172:ddr2_act_n" )
			)
			( pin "U2D1.AD61"
				( objectStatus "@baseboard_fab2_lib.baseboard_fab2(sch_1):page59_i172:ddr2_alert_n" )
			)
			( pin "U2D1.W52"
				( objectStatus "@baseboard_fab2_lib.baseboard_fab2(sch_1):page59_i172:ddr2_ba(0)" )
			)
			( pin "U2D1.AE56"
				( objectStatus "@baseboard_fab2_lib.baseboard_fab2(sch_1):page59_i172:ddr2_ba(1)" )
			)
			( pin "U2D1.AA60"
				( objectStatus "@baseboard_fab2_lib.baseboard_fab2(sch_1):page59_i172:ddr2_bg(0)" )
			)
			( pin "U2D1.AE62"
				( objectStatus "@baseboard_fab2_lib.baseboard_fab2(sch_1):page59_i172:ddr2_bg(1)" )
			)
			( pin "U2D1.AB45"
				( objectStatus "@baseboard_fab2_lib.baseboard_fab2(sch_1):page59_i172:ddr2_cid(2)" )
			)
			( pin "U2D1.AA62"
				( objectStatus "@baseboard_fab2_lib.baseboard_fab2(sch_1):page59_i172:ddr2_cke(0)" )
			)
			( pin "U2D1.AD63"
				( objectStatus "@baseboard_fab2_lib.baseboard_fab2(sch_1):page59_i172:ddr2_cke(1)" )
			)
			( pin "U2D1.V63"
				( objectStatus "@baseboard_fab2_lib.baseboard_fab2(sch_1):page59_i172:ddr2_cke(2)" )
			)
			( pin "U2D1.AB63"
				( objectStatus "@baseboard_fab2_lib.baseboard_fab2(sch_1):page59_i172:ddr2_cke(3)" )
			)
			( pin "U2D1.AA54"
				( objectStatus "@baseboard_fab2_lib.baseboard_fab2(sch_1):page59_i172:ddr2_clk_dn(0)" )
			)
			( pin "U2D1.W54"
				( objectStatus "@baseboard_fab2_lib.baseboard_fab2(sch_1):page59_i172:ddr2_clk_dn(1)" )
			)
			( pin "U2D1.AA56"
				( objectStatus "@baseboard_fab2_lib.baseboard_fab2(sch_1):page59_i172:ddr2_clk_dn(2)" )
			)
			( pin "U2D1.W56"
				( objectStatus "@baseboard_fab2_lib.baseboard_fab2(sch_1):page59_i172:ddr2_clk_dn(3)" )
			)
			( pin "U2D1.AB55"
				( objectStatus "@baseboard_fab2_lib.baseboard_fab2(sch_1):page59_i172:ddr2_clk_dp(0)" )
			)
			( pin "U2D1.V55"
				( objectStatus "@baseboard_fab2_lib.baseboard_fab2(sch_1):page59_i172:ddr2_clk_dp(1)" )
			)
			( pin "U2D1.AB57"
				( objectStatus "@baseboard_fab2_lib.baseboard_fab2(sch_1):page59_i172:ddr2_clk_dp(2)" )
			)
			( pin "U2D1.V57"
				( objectStatus "@baseboard_fab2_lib.baseboard_fab2(sch_1):page59_i172:ddr2_clk_dp(3)" )
			)
			( pin "U2D1.V51"
				( objectStatus "@baseboard_fab2_lib.baseboard_fab2(sch_1):page59_i172:ddr2_cs_n(0)" )
			)
			( pin "U2D1.AB49"
				( objectStatus "@baseboard_fab2_lib.baseboard_fab2(sch_1):page59_i172:ddr2_cs_n(1)" )
			)
			( pin "U2D1.W46"
				( objectStatus "@baseboard_fab2_lib.baseboard_fab2(sch_1):page59_i172:ddr2_cs_n(2)" )
			)
			( pin "U2D1.AA46"
				( objectStatus "@baseboard_fab2_lib.baseboard_fab2(sch_1):page59_i172:ddr2_cs_n(3)" )
			)
			( pin "U2D1.AB51"
				( objectStatus "@baseboard_fab2_lib.baseboard_fab2(sch_1):page59_i172:ddr2_cs_n(4)" )
			)
			( pin "U2D1.W48"
				( objectStatus "@baseboard_fab2_lib.baseboard_fab2(sch_1):page59_i172:ddr2_cs_n(5)" )
			)
			( pin "U2D1.T45"
				( objectStatus "@baseboard_fab2_lib.baseboard_fab2(sch_1):page59_i172:ddr2_cs_n(6)" )
			)
			( pin "U2D1.V45"
				( objectStatus "@baseboard_fab2_lib.baseboard_fab2(sch_1):page59_i172:ddr2_cs_n(7)" )
			)
			( pin "U2D1.AR76"
				( objectStatus "@baseboard_fab2_lib.baseboard_fab2(sch_1):page59_i172:ddr2_dq(0)" )
			)
			( pin "U2D1.AN74"
				( objectStatus "@baseboard_fab2_lib.baseboard_fab2(sch_1):page59_i172:ddr2_dq(1)" )
			)
			( pin "U2D1.AK77"
				( objectStatus "@baseboard_fab2_lib.baseboard_fab2(sch_1):page59_i172:ddr2_dq(2)" )
			)
			( pin "U2D1.AJ76"
				( objectStatus "@baseboard_fab2_lib.baseboard_fab2(sch_1):page59_i172:ddr2_dq(3)" )
			)
			( pin "U2D1.AT75"
				( objectStatus "@baseboard_fab2_lib.baseboard_fab2(sch_1):page59_i172:ddr2_dq(4)" )
			)
			( pin "U2D1.AR74"
				( objectStatus "@baseboard_fab2_lib.baseboard_fab2(sch_1):page59_i172:ddr2_dq(5)" )
			)
			( pin "U2D1.AM77"
				( objectStatus "@baseboard_fab2_lib.baseboard_fab2(sch_1):page59_i172:ddr2_dq(6)" )
			)
			( pin "U2D1.AK75"
				( objectStatus "@baseboard_fab2_lib.baseboard_fab2(sch_1):page59_i172:ddr2_dq(7)" )
			)
			( pin "U2D1.AE76"
				( objectStatus "@baseboard_fab2_lib.baseboard_fab2(sch_1):page59_i172:ddr2_dq(8)" )
			)
			( pin "U2D1.AC74"
				( objectStatus "@baseboard_fab2_lib.baseboard_fab2(sch_1):page59_i172:ddr2_dq(9)" )
			)
			( pin "U2D1.Y77"
				( objectStatus "@baseboard_fab2_lib.baseboard_fab2(sch_1):page59_i172:ddr2_dq(10)" )
			)
			( pin "U2D1.W76"
				( objectStatus "@baseboard_fab2_lib.baseboard_fab2(sch_1):page59_i172:ddr2_dq(11)" )
			)
			( pin "U2D1.AF75"
				( objectStatus "@baseboard_fab2_lib.baseboard_fab2(sch_1):page59_i172:ddr2_dq(12)" )
			)
			( pin "U2D1.AE74"
				( objectStatus "@baseboard_fab2_lib.baseboard_fab2(sch_1):page59_i172:ddr2_dq(13)" )
			)
			( pin "U2D1.AB77"
				( objectStatus "@baseboard_fab2_lib.baseboard_fab2(sch_1):page59_i172:ddr2_dq(14)" )
			)
			( pin "U2D1.Y75"
				( objectStatus "@baseboard_fab2_lib.baseboard_fab2(sch_1):page59_i172:ddr2_dq(15)" )
			)
			( pin "U2D1.W72"
				( objectStatus "@baseboard_fab2_lib.baseboard_fab2(sch_1):page59_i172:ddr2_dq(16)" )
			)
			( pin "U2D1.AA70"
				( objectStatus "@baseboard_fab2_lib.baseboard_fab2(sch_1):page59_i172:ddr2_dq(17)" )
			)
			( pin "U2D1.R70"
				( objectStatus "@baseboard_fab2_lib.baseboard_fab2(sch_1):page59_i172:ddr2_dq(18)" )
			)
			( pin "U2D1.T69"
				( objectStatus "@baseboard_fab2_lib.baseboard_fab2(sch_1):page59_i172:ddr2_dq(19)" )
			)
			( pin "U2D1.AA72"
				( objectStatus "@baseboard_fab2_lib.baseboard_fab2(sch_1):page59_i172:ddr2_dq(20)" )
			)
			( pin "U2D1.AB71"
				( objectStatus "@baseboard_fab2_lib.baseboard_fab2(sch_1):page59_i172:ddr2_dq(21)" )
			)
			( pin "U2D1.T71"
				( objectStatus "@baseboard_fab2_lib.baseboard_fab2(sch_1):page59_i172:ddr2_dq(22)" )
			)
			( pin "U2D1.V69"
				( objectStatus "@baseboard_fab2_lib.baseboard_fab2(sch_1):page59_i172:ddr2_dq(23)" )
			)
			( pin "U2D1.AM67"
				( objectStatus "@baseboard_fab2_lib.baseboard_fab2(sch_1):page59_i172:ddr2_dq(24)" )
			)
			( pin "U2D1.AT67"
				( objectStatus "@baseboard_fab2_lib.baseboard_fab2(sch_1):page59_i172:ddr2_dq(25)" )
			)
			( pin "U2D1.AN64"
				( objectStatus "@baseboard_fab2_lib.baseboard_fab2(sch_1):page59_i172:ddr2_dq(26)" )
			)
			( pin "U2D1.AR64"
				( objectStatus "@baseboard_fab2_lib.baseboard_fab2(sch_1):page59_i172:ddr2_dq(27)" )
			)
			( pin "U2D1.AN68"
				( objectStatus "@baseboard_fab2_lib.baseboard_fab2(sch_1):page59_i172:ddr2_dq(28)" )
			)
			( pin "U2D1.AR68"
				( objectStatus "@baseboard_fab2_lib.baseboard_fab2(sch_1):page59_i172:ddr2_dq(29)" )
			)
			( pin "U2D1.AM65"
				( objectStatus "@baseboard_fab2_lib.baseboard_fab2(sch_1):page59_i172:ddr2_dq(30)" )
			)
			( pin "U2D1.AT65"
				( objectStatus "@baseboard_fab2_lib.baseboard_fab2(sch_1):page59_i172:ddr2_dq(31)" )
			)
			( pin "U2D1.U40"
				( objectStatus "@baseboard_fab2_lib.baseboard_fab2(sch_1):page59_i172:ddr2_dq(32)" )
			)
			( pin "U2D1.AA40"
				( objectStatus "@baseboard_fab2_lib.baseboard_fab2(sch_1):page59_i172:ddr2_dq(33)" )
			)
			( pin "U2D1.V37"
				( objectStatus "@baseboard_fab2_lib.baseboard_fab2(sch_1):page59_i172:ddr2_dq(34)" )
			)
			( pin "U2D1.Y37"
				( objectStatus "@baseboard_fab2_lib.baseboard_fab2(sch_1):page59_i172:ddr2_dq(35)" )
			)
			( pin "U2D1.V41"
				( objectStatus "@baseboard_fab2_lib.baseboard_fab2(sch_1):page59_i172:ddr2_dq(36)" )
			)
			( pin "U2D1.Y41"
				( objectStatus "@baseboard_fab2_lib.baseboard_fab2(sch_1):page59_i172:ddr2_dq(37)" )
			)
			( pin "U2D1.U38"
				( objectStatus "@baseboard_fab2_lib.baseboard_fab2(sch_1):page59_i172:ddr2_dq(38)" )
			)
			( pin "U2D1.AA38"
				( objectStatus "@baseboard_fab2_lib.baseboard_fab2(sch_1):page59_i172:ddr2_dq(39)" )
			)
			( pin "U2D1.U34"
				( objectStatus "@baseboard_fab2_lib.baseboard_fab2(sch_1):page59_i172:ddr2_dq(40)" )
			)
			( pin "U2D1.AA34"
				( objectStatus "@baseboard_fab2_lib.baseboard_fab2(sch_1):page59_i172:ddr2_dq(41)" )
			)
			( pin "U2D1.V31"
				( objectStatus "@baseboard_fab2_lib.baseboard_fab2(sch_1):page59_i172:ddr2_dq(42)" )
			)
			( pin "U2D1.Y31"
				( objectStatus "@baseboard_fab2_lib.baseboard_fab2(sch_1):page59_i172:ddr2_dq(43)" )
			)
			( pin "U2D1.V35"
				( objectStatus "@baseboard_fab2_lib.baseboard_fab2(sch_1):page59_i172:ddr2_dq(44)" )
			)
			( pin "U2D1.Y35"
				( objectStatus "@baseboard_fab2_lib.baseboard_fab2(sch_1):page59_i172:ddr2_dq(45)" )
			)
			( pin "U2D1.U32"
				( objectStatus "@baseboard_fab2_lib.baseboard_fab2(sch_1):page59_i172:ddr2_dq(46)" )
			)
			( pin "U2D1.AA32"
				( objectStatus "@baseboard_fab2_lib.baseboard_fab2(sch_1):page59_i172:ddr2_dq(47)" )
			)
			( pin "U2D1.AD31"
				( objectStatus "@baseboard_fab2_lib.baseboard_fab2(sch_1):page59_i172:ddr2_dq(48)" )
			)
			( pin "U2D1.AH31"
				( objectStatus "@baseboard_fab2_lib.baseboard_fab2(sch_1):page59_i172:ddr2_dq(49)" )
			)
			( pin "U2D1.AE28"
				( objectStatus "@baseboard_fab2_lib.baseboard_fab2(sch_1):page59_i172:ddr2_dq(50)" )
			)
			( pin "U2D1.AG28"
				( objectStatus "@baseboard_fab2_lib.baseboard_fab2(sch_1):page59_i172:ddr2_dq(51)" )
			)
			( pin "U2D1.AE32"
				( objectStatus "@baseboard_fab2_lib.baseboard_fab2(sch_1):page59_i172:ddr2_dq(52)" )
			)
			( pin "U2D1.AG32"
				( objectStatus "@baseboard_fab2_lib.baseboard_fab2(sch_1):page59_i172:ddr2_dq(53)" )
			)
			( pin "U2D1.AD29"
				( objectStatus "@baseboard_fab2_lib.baseboard_fab2(sch_1):page59_i172:ddr2_dq(54)" )
			)
			( pin "U2D1.AH29"
				( objectStatus "@baseboard_fab2_lib.baseboard_fab2(sch_1):page59_i172:ddr2_dq(55)" )
			)
			( pin "U2D1.AD25"
				( objectStatus "@baseboard_fab2_lib.baseboard_fab2(sch_1):page59_i172:ddr2_dq(56)" )
			)
			( pin "U2D1.AH25"
				( objectStatus "@baseboard_fab2_lib.baseboard_fab2(sch_1):page59_i172:ddr2_dq(57)" )
			)
			( pin "U2D1.AE22"
				( objectStatus "@baseboard_fab2_lib.baseboard_fab2(sch_1):page59_i172:ddr2_dq(58)" )
			)
			( pin "U2D1.AG22"
				( objectStatus "@baseboard_fab2_lib.baseboard_fab2(sch_1):page59_i172:ddr2_dq(59)" )
			)
			( pin "U2D1.AE26"
				( objectStatus "@baseboard_fab2_lib.baseboard_fab2(sch_1):page59_i172:ddr2_dq(60)" )
			)
			( pin "U2D1.AG26"
				( objectStatus "@baseboard_fab2_lib.baseboard_fab2(sch_1):page59_i172:ddr2_dq(61)" )
			)
			( pin "U2D1.AD23"
				( objectStatus "@baseboard_fab2_lib.baseboard_fab2(sch_1):page59_i172:ddr2_dq(62)" )
			)
			( pin "U2D1.AH23"
				( objectStatus "@baseboard_fab2_lib.baseboard_fab2(sch_1):page59_i172:ddr2_dq(63)" )
			)
			( pin "U2D1.AL74"
				( objectStatus "@baseboard_fab2_lib.baseboard_fab2(sch_1):page59_i172:ddr2_dqs_dn(0)" )
			)
			( pin "U2D1.AA74"
				( objectStatus "@baseboard_fab2_lib.baseboard_fab2(sch_1):page59_i172:ddr2_dqs_dn(1)" )
			)
			( pin "U2D1.Y69"
				( objectStatus "@baseboard_fab2_lib.baseboard_fab2(sch_1):page59_i172:ddr2_dqs_dn(2)" )
			)
			( pin "U2D1.AU66"
				( objectStatus "@baseboard_fab2_lib.baseboard_fab2(sch_1):page59_i172:ddr2_dqs_dn(3)" )
			)
			( pin "U2D1.AB39"
				( objectStatus "@baseboard_fab2_lib.baseboard_fab2(sch_1):page59_i172:ddr2_dqs_dn(4)" )
			)
			( pin "U2D1.AB33"
				( objectStatus "@baseboard_fab2_lib.baseboard_fab2(sch_1):page59_i172:ddr2_dqs_dn(5)" )
			)
			( pin "U2D1.AJ30"
				( objectStatus "@baseboard_fab2_lib.baseboard_fab2(sch_1):page59_i172:ddr2_dqs_dn(6)" )
			)
			( pin "U2D1.AJ24"
				( objectStatus "@baseboard_fab2_lib.baseboard_fab2(sch_1):page59_i172:ddr2_dqs_dn(7)" )
			)
			( pin "U2D1.BB71"
				( objectStatus "@baseboard_fab2_lib.baseboard_fab2(sch_1):page59_i172:ddr2_dqs_dn(8)" )
			)
			( pin "U2D1.AP77"
				( objectStatus "@baseboard_fab2_lib.baseboard_fab2(sch_1):page59_i172:ddr2_dqs_dn(9)" )
			)
			( pin "U2D1.AD77"
				( objectStatus "@baseboard_fab2_lib.baseboard_fab2(sch_1):page59_i172:ddr2_dqs_dn(10)" )
			)
			( pin "U2D1.U72"
				( objectStatus "@baseboard_fab2_lib.baseboard_fab2(sch_1):page59_i172:ddr2_dqs_dn(11)" )
			)
			( pin "U2D1.AL66"
				( objectStatus "@baseboard_fab2_lib.baseboard_fab2(sch_1):page59_i172:ddr2_dqs_dn(12)" )
			)
			( pin "U2D1.T39"
				( objectStatus "@baseboard_fab2_lib.baseboard_fab2(sch_1):page59_i172:ddr2_dqs_dn(13)" )
			)
			( pin "U2D1.T33"
				( objectStatus "@baseboard_fab2_lib.baseboard_fab2(sch_1):page59_i172:ddr2_dqs_dn(14)" )
			)
			( pin "U2D1.AC30"
				( objectStatus "@baseboard_fab2_lib.baseboard_fab2(sch_1):page59_i172:ddr2_dqs_dn(15)" )
			)
			( pin "U2D1.AC24"
				( objectStatus "@baseboard_fab2_lib.baseboard_fab2(sch_1):page59_i172:ddr2_dqs_dn(16)" )
			)
			( pin "U2D1.AT71"
				( objectStatus "@baseboard_fab2_lib.baseboard_fab2(sch_1):page59_i172:ddr2_dqs_dn(17)" )
			)
			( pin "U2D1.AM75"
				( objectStatus "@baseboard_fab2_lib.baseboard_fab2(sch_1):page59_i172:ddr2_dqs_dp(0)" )
			)
			( pin "U2D1.AB75"
				( objectStatus "@baseboard_fab2_lib.baseboard_fab2(sch_1):page59_i172:ddr2_dqs_dp(1)" )
			)
			( pin "U2D1.W70"
				( objectStatus "@baseboard_fab2_lib.baseboard_fab2(sch_1):page59_i172:ddr2_dqs_dp(2)" )
			)
			( pin "U2D1.AR66"
				( objectStatus "@baseboard_fab2_lib.baseboard_fab2(sch_1):page59_i172:ddr2_dqs_dp(3)" )
			)
			( pin "U2D1.Y39"
				( objectStatus "@baseboard_fab2_lib.baseboard_fab2(sch_1):page59_i172:ddr2_dqs_dp(4)" )
			)
			( pin "U2D1.Y33"
				( objectStatus "@baseboard_fab2_lib.baseboard_fab2(sch_1):page59_i172:ddr2_dqs_dp(5)" )
			)
			( pin "U2D1.AG30"
				( objectStatus "@baseboard_fab2_lib.baseboard_fab2(sch_1):page59_i172:ddr2_dqs_dp(6)" )
			)
			( pin "U2D1.AG24"
				( objectStatus "@baseboard_fab2_lib.baseboard_fab2(sch_1):page59_i172:ddr2_dqs_dp(7)" )
			)
			( pin "U2D1.AY71"
				( objectStatus "@baseboard_fab2_lib.baseboard_fab2(sch_1):page59_i172:ddr2_dqs_dp(8)" )
			)
			( pin "U2D1.AN76"
				( objectStatus "@baseboard_fab2_lib.baseboard_fab2(sch_1):page59_i172:ddr2_dqs_dp(9)" )
			)
			( pin "U2D1.AC76"
				( objectStatus "@baseboard_fab2_lib.baseboard_fab2(sch_1):page59_i172:ddr2_dqs_dp(10)" )
			)
			( pin "U2D1.V71"
				( objectStatus "@baseboard_fab2_lib.baseboard_fab2(sch_1):page59_i172:ddr2_dqs_dp(11)" )
			)
			( pin "U2D1.AN66"
				( objectStatus "@baseboard_fab2_lib.baseboard_fab2(sch_1):page59_i172:ddr2_dqs_dp(12)" )
			)
			( pin "U2D1.V39"
				( objectStatus "@baseboard_fab2_lib.baseboard_fab2(sch_1):page59_i172:ddr2_dqs_dp(13)" )
			)
			( pin "U2D1.V33"
				( objectStatus "@baseboard_fab2_lib.baseboard_fab2(sch_1):page59_i172:ddr2_dqs_dp(14)" )
			)
			( pin "U2D1.AE30"
				( objectStatus "@baseboard_fab2_lib.baseboard_fab2(sch_1):page59_i172:ddr2_dqs_dp(15)" )
			)
			( pin "U2D1.AE24"
				( objectStatus "@baseboard_fab2_lib.baseboard_fab2(sch_1):page59_i172:ddr2_dqs_dp(16)" )
			)
			( pin "U2D1.AV71"
				( objectStatus "@baseboard_fab2_lib.baseboard_fab2(sch_1):page59_i172:ddr2_dqs_dp(17)" )
			)
			( pin "U2D1.AU72"
				( objectStatus "@baseboard_fab2_lib.baseboard_fab2(sch_1):page59_i172:ddr2_ecc(0)" )
			)
			( pin "U2D1.BA72"
				( objectStatus "@baseboard_fab2_lib.baseboard_fab2(sch_1):page59_i172:ddr2_ecc(1)" )
			)
			( pin "U2D1.AV69"
				( objectStatus "@baseboard_fab2_lib.baseboard_fab2(sch_1):page59_i172:ddr2_ecc(2)" )
			)
			( pin "U2D1.AY69"
				( objectStatus "@baseboard_fab2_lib.baseboard_fab2(sch_1):page59_i172:ddr2_ecc(3)" )
			)
			( pin "U2D1.AV73"
				( objectStatus "@baseboard_fab2_lib.baseboard_fab2(sch_1):page59_i172:ddr2_ecc(4)" )
			)
			( pin "U2D1.AY73"
				( objectStatus "@baseboard_fab2_lib.baseboard_fab2(sch_1):page59_i172:ddr2_ecc(5)" )
			)
			( pin "U2D1.AU70"
				( objectStatus "@baseboard_fab2_lib.baseboard_fab2(sch_1):page59_i172:ddr2_ecc(6)" )
			)
			( pin "U2D1.BA70"
				( objectStatus "@baseboard_fab2_lib.baseboard_fab2(sch_1):page59_i172:ddr2_ecc(7)" )
			)
			( pin "U2D1.AB53"
				( objectStatus "@baseboard_fab2_lib.baseboard_fab2(sch_1):page59_i172:ddr2_ma(0)" )
			)
			( pin "U2D1.AE58"
				( objectStatus "@baseboard_fab2_lib.baseboard_fab2(sch_1):page59_i172:ddr2_ma(1)" )
			)
			( pin "U2D1.AD57"
				( objectStatus "@baseboard_fab2_lib.baseboard_fab2(sch_1):page59_i172:ddr2_ma(2)" )
			)
			( pin "U2D1.W58"
				( objectStatus "@baseboard_fab2_lib.baseboard_fab2(sch_1):page59_i172:ddr2_ma(3)" )
			)
			( pin "U2D1.AA58"
				( objectStatus "@baseboard_fab2_lib.baseboard_fab2(sch_1):page59_i172:ddr2_ma(4)" )
			)
			( pin "U2D1.V59"
				( objectStatus "@baseboard_fab2_lib.baseboard_fab2(sch_1):page59_i172:ddr2_ma(5)" )
			)
			( pin "U2D1.AB59"
				( objectStatus "@baseboard_fab2_lib.baseboard_fab2(sch_1):page59_i172:ddr2_ma(6)" )
			)
			( pin "U2D1.AE60"
				( objectStatus "@baseboard_fab2_lib.baseboard_fab2(sch_1):page59_i172:ddr2_ma(7)" )
			)
			( pin "U2D1.AD59"
				( objectStatus "@baseboard_fab2_lib.baseboard_fab2(sch_1):page59_i172:ddr2_ma(8)" )
			)
			( pin "U2D1.AG58"
				( objectStatus "@baseboard_fab2_lib.baseboard_fab2(sch_1):page59_i172:ddr2_ma(9)" )
			)
			( pin "U2D1.AD55"
				( objectStatus "@baseboard_fab2_lib.baseboard_fab2(sch_1):page59_i172:ddr2_ma(10)" )
			)
			( pin "U2D1.AG60"
				( objectStatus "@baseboard_fab2_lib.baseboard_fab2(sch_1):page59_i172:ddr2_ma(11)" )
			)
			( pin "U2D1.AG62"
				( objectStatus "@baseboard_fab2_lib.baseboard_fab2(sch_1):page59_i172:ddr2_ma(12)" )
			)
			( pin "U2D1.AD53"
				( objectStatus "@baseboard_fab2_lib.baseboard_fab2(sch_1):page59_i172:ddr2_ma(13)" )
			)
			( pin "U2D1.W50"
				( objectStatus "@baseboard_fab2_lib.baseboard_fab2(sch_1):page59_i172:ddr2_ma(14)" )
			)
			( pin "U2D1.AE54"
				( objectStatus "@baseboard_fab2_lib.baseboard_fab2(sch_1):page59_i172:ddr2_ma(15)" )
			)
			( pin "U2D1.AA52"
				( objectStatus "@baseboard_fab2_lib.baseboard_fab2(sch_1):page59_i172:ddr2_ma(16)" )
			)
			( pin "U2D1.AC46"
				( objectStatus "@baseboard_fab2_lib.baseboard_fab2(sch_1):page59_i172:ddr2_ma(17)" )
			)
			( pin "U2D1.AA50"
				( objectStatus "@baseboard_fab2_lib.baseboard_fab2(sch_1):page59_i172:ddr2_odt(0)" )
			)
			( pin "U2D1.AA48"
				( objectStatus "@baseboard_fab2_lib.baseboard_fab2(sch_1):page59_i172:ddr2_odt(1)" )
			)
			( pin "U2D1.V49"
				( objectStatus "@baseboard_fab2_lib.baseboard_fab2(sch_1):page59_i172:ddr2_odt(2)" )
			)
			( pin "U2D1.AB47"
				( objectStatus "@baseboard_fab2_lib.baseboard_fab2(sch_1):page59_i172:ddr2_odt(3)" )
			)
			( pin "U2D1.V53"
				( objectStatus "@baseboard_fab2_lib.baseboard_fab2(sch_1):page59_i172:ddr2_par" )
			)
			( pin "U2D1.DW60"
				( objectStatus "@baseboard_fab2_lib.baseboard_fab2(sch_1):page60_i172:ddr3_act_n" )
			)
			( pin "U2D1.ED63"
				( objectStatus "@baseboard_fab2_lib.baseboard_fab2(sch_1):page60_i172:ddr3_alert_n" )
			)
			( pin "U2D1.EE52"
				( objectStatus "@baseboard_fab2_lib.baseboard_fab2(sch_1):page60_i172:ddr3_ba(0)" )
			)
			( pin "U2D1.EA54"
				( objectStatus "@baseboard_fab2_lib.baseboard_fab2(sch_1):page60_i172:ddr3_ba(1)" )
			)
			( pin "U2D1.ED61"
				( objectStatus "@baseboard_fab2_lib.baseboard_fab2(sch_1):page60_i172:ddr3_bg(0)" )
			)
			( pin "U2D1.DW62"
				( objectStatus "@baseboard_fab2_lib.baseboard_fab2(sch_1):page60_i172:ddr3_bg(1)" )
			)
			( pin "U2D1.DV47"
				( objectStatus "@baseboard_fab2_lib.baseboard_fab2(sch_1):page60_i172:ddr3_cid(2)" )
			)
			( pin "U2D1.EE62"
				( objectStatus "@baseboard_fab2_lib.baseboard_fab2(sch_1):page60_i172:ddr3_cke(0)" )
			)
			( pin "U2D1.EF63"
				( objectStatus "@baseboard_fab2_lib.baseboard_fab2(sch_1):page60_i172:ddr3_cke(1)" )
			)
			( pin "U2D1.EA62"
				( objectStatus "@baseboard_fab2_lib.baseboard_fab2(sch_1):page60_i172:ddr3_cke(2)" )
			)
			( pin "U2D1.EB63"
				( objectStatus "@baseboard_fab2_lib.baseboard_fab2(sch_1):page60_i172:ddr3_cke(3)" )
			)
			( pin "U2D1.ED55"
				( objectStatus "@baseboard_fab2_lib.baseboard_fab2(sch_1):page60_i172:ddr3_clk_dn(0)" )
			)
			( pin "U2D1.EF55"
				( objectStatus "@baseboard_fab2_lib.baseboard_fab2(sch_1):page60_i172:ddr3_clk_dn(1)" )
			)
			( pin "U2D1.DW56"
				( objectStatus "@baseboard_fab2_lib.baseboard_fab2(sch_1):page60_i172:ddr3_clk_dn(2)" )
			)
			( pin "U2D1.EF57"
				( objectStatus "@baseboard_fab2_lib.baseboard_fab2(sch_1):page60_i172:ddr3_clk_dn(3)" )
			)
			( pin "U2D1.EB55"
				( objectStatus "@baseboard_fab2_lib.baseboard_fab2(sch_1):page60_i172:ddr3_clk_dp(0)" )
			)
			( pin "U2D1.EE54"
				( objectStatus "@baseboard_fab2_lib.baseboard_fab2(sch_1):page60_i172:ddr3_clk_dp(1)" )
			)
			( pin "U2D1.EA56"
				( objectStatus "@baseboard_fab2_lib.baseboard_fab2(sch_1):page60_i172:ddr3_clk_dp(2)" )
			)
			( pin "U2D1.EE56"
				( objectStatus "@baseboard_fab2_lib.baseboard_fab2(sch_1):page60_i172:ddr3_clk_dp(3)" )
			)
			( pin "U2D1.EF51"
				( objectStatus "@baseboard_fab2_lib.baseboard_fab2(sch_1):page60_i172:ddr3_cs_n(0)" )
			)
			( pin "U2D1.ED49"
				( objectStatus "@baseboard_fab2_lib.baseboard_fab2(sch_1):page60_i172:ddr3_cs_n(1)" )
			)
			( pin "U2D1.ED47"
				( objectStatus "@baseboard_fab2_lib.baseboard_fab2(sch_1):page60_i172:ddr3_cs_n(2)" )
			)
			( pin "U2D1.EB47"
				( objectStatus "@baseboard_fab2_lib.baseboard_fab2(sch_1):page60_i172:ddr3_cs_n(3)" )
			)
			( pin "U2D1.EB51"
				( objectStatus "@baseboard_fab2_lib.baseboard_fab2(sch_1):page60_i172:ddr3_cs_n(4)" )
			)
			( pin "U2D1.EB49"
				( objectStatus "@baseboard_fab2_lib.baseboard_fab2(sch_1):page60_i172:ddr3_cs_n(5)" )
			)
			( pin "U2D1.DV45"
				( objectStatus "@baseboard_fab2_lib.baseboard_fab2(sch_1):page60_i172:ddr3_cs_n(6)" )
			)
			( pin "U2D1.EB45"
				( objectStatus "@baseboard_fab2_lib.baseboard_fab2(sch_1):page60_i172:ddr3_cs_n(7)" )
			)
			( pin "U2D1.CN84"
				( objectStatus "@baseboard_fab2_lib.baseboard_fab2(sch_1):page60_i172:ddr3_dq(0)" )
			)
			( pin "U2D1.CN86"
				( objectStatus "@baseboard_fab2_lib.baseboard_fab2(sch_1):page60_i172:ddr3_dq(1)" )
			)
			( pin "U2D1.DA86"
				( objectStatus "@baseboard_fab2_lib.baseboard_fab2(sch_1):page60_i172:ddr3_dq(2)" )
			)
			( pin "U2D1.DA84"
				( objectStatus "@baseboard_fab2_lib.baseboard_fab2(sch_1):page60_i172:ddr3_dq(3)" )
			)
			( pin "U2D1.CL84"
				( objectStatus "@baseboard_fab2_lib.baseboard_fab2(sch_1):page60_i172:ddr3_dq(4)" )
			)
			( pin "U2D1.CL86"
				( objectStatus "@baseboard_fab2_lib.baseboard_fab2(sch_1):page60_i172:ddr3_dq(5)" )
			)
			( pin "U2D1.CW86"
				( objectStatus "@baseboard_fab2_lib.baseboard_fab2(sch_1):page60_i172:ddr3_dq(6)" )
			)
			( pin "U2D1.CW84"
				( objectStatus "@baseboard_fab2_lib.baseboard_fab2(sch_1):page60_i172:ddr3_dq(7)" )
			)
			( pin "U2D1.DG84"
				( objectStatus "@baseboard_fab2_lib.baseboard_fab2(sch_1):page60_i172:ddr3_dq(8)" )
			)
			( pin "U2D1.DH85"
				( objectStatus "@baseboard_fab2_lib.baseboard_fab2(sch_1):page60_i172:ddr3_dq(9)" )
			)
			( pin "U2D1.DV83"
				( objectStatus "@baseboard_fab2_lib.baseboard_fab2(sch_1):page60_i172:ddr3_dq(10)" )
			)
			( pin "U2D1.DY83"
				( objectStatus "@baseboard_fab2_lib.baseboard_fab2(sch_1):page60_i172:ddr3_dq(11)" )
			)
			( pin "U2D1.DD85"
				( objectStatus "@baseboard_fab2_lib.baseboard_fab2(sch_1):page60_i172:ddr3_dq(12)" )
			)
			( pin "U2D1.DE84"
				( objectStatus "@baseboard_fab2_lib.baseboard_fab2(sch_1):page60_i172:ddr3_dq(13)" )
			)
			( pin "U2D1.DR84"
				( objectStatus "@baseboard_fab2_lib.baseboard_fab2(sch_1):page60_i172:ddr3_dq(14)" )
			)
			( pin "U2D1.DV85"
				( objectStatus "@baseboard_fab2_lib.baseboard_fab2(sch_1):page60_i172:ddr3_dq(15)" )
			)
			( pin "U2D1.DM79"
				( objectStatus "@baseboard_fab2_lib.baseboard_fab2(sch_1):page60_i172:ddr3_dq(16)" )
			)
			( pin "U2D1.DK81"
				( objectStatus "@baseboard_fab2_lib.baseboard_fab2(sch_1):page60_i172:ddr3_dq(17)" )
			)
			( pin "U2D1.DT81"
				( objectStatus "@baseboard_fab2_lib.baseboard_fab2(sch_1):page60_i172:ddr3_dq(18)" )
			)
			( pin "U2D1.DR82"
				( objectStatus "@baseboard_fab2_lib.baseboard_fab2(sch_1):page60_i172:ddr3_dq(19)" )
			)
			( pin "U2D1.DK79"
				( objectStatus "@baseboard_fab2_lib.baseboard_fab2(sch_1):page60_i172:ddr3_dq(20)" )
			)
			( pin "U2D1.DJ80"
				( objectStatus "@baseboard_fab2_lib.baseboard_fab2(sch_1):page60_i172:ddr3_dq(21)" )
			)
			( pin "U2D1.DR80"
				( objectStatus "@baseboard_fab2_lib.baseboard_fab2(sch_1):page60_i172:ddr3_dq(22)" )
			)
			( pin "U2D1.DN82"
				( objectStatus "@baseboard_fab2_lib.baseboard_fab2(sch_1):page60_i172:ddr3_dq(23)" )
			)
			( pin "U2D1.DN76"
				( objectStatus "@baseboard_fab2_lib.baseboard_fab2(sch_1):page60_i172:ddr3_dq(24)" )
			)
			( pin "U2D1.DU76"
				( objectStatus "@baseboard_fab2_lib.baseboard_fab2(sch_1):page60_i172:ddr3_dq(25)" )
			)
			( pin "U2D1.DP73"
				( objectStatus "@baseboard_fab2_lib.baseboard_fab2(sch_1):page60_i172:ddr3_dq(26)" )
			)
			( pin "U2D1.DT73"
				( objectStatus "@baseboard_fab2_lib.baseboard_fab2(sch_1):page60_i172:ddr3_dq(27)" )
			)
			( pin "U2D1.DP77"
				( objectStatus "@baseboard_fab2_lib.baseboard_fab2(sch_1):page60_i172:ddr3_dq(28)" )
			)
			( pin "U2D1.DT77"
				( objectStatus "@baseboard_fab2_lib.baseboard_fab2(sch_1):page60_i172:ddr3_dq(29)" )
			)
			( pin "U2D1.DN74"
				( objectStatus "@baseboard_fab2_lib.baseboard_fab2(sch_1):page60_i172:ddr3_dq(30)" )
			)
			( pin "U2D1.DU74"
				( objectStatus "@baseboard_fab2_lib.baseboard_fab2(sch_1):page60_i172:ddr3_dq(31)" )
			)
			( pin "U2D1.EC40"
				( objectStatus "@baseboard_fab2_lib.baseboard_fab2(sch_1):page60_i172:ddr3_dq(32)" )
			)
			( pin "U2D1.ED39"
				( objectStatus "@baseboard_fab2_lib.baseboard_fab2(sch_1):page60_i172:ddr3_dq(33)" )
			)
			( pin "U2D1.EA36"
				( objectStatus "@baseboard_fab2_lib.baseboard_fab2(sch_1):page60_i172:ddr3_dq(34)" )
			)
			( pin "U2D1.EC36"
				( objectStatus "@baseboard_fab2_lib.baseboard_fab2(sch_1):page60_i172:ddr3_dq(35)" )
			)
			( pin "U2D1.DY39"
				( objectStatus "@baseboard_fab2_lib.baseboard_fab2(sch_1):page60_i172:ddr3_dq(36)" )
			)
			( pin "U2D1.EA40"
				( objectStatus "@baseboard_fab2_lib.baseboard_fab2(sch_1):page60_i172:ddr3_dq(37)" )
			)
			( pin "U2D1.DY37"
				( objectStatus "@baseboard_fab2_lib.baseboard_fab2(sch_1):page60_i172:ddr3_dq(38)" )
			)
			( pin "U2D1.ED37"
				( objectStatus "@baseboard_fab2_lib.baseboard_fab2(sch_1):page60_i172:ddr3_dq(39)" )
			)
			( pin "U2D1.DN36"
				( objectStatus "@baseboard_fab2_lib.baseboard_fab2(sch_1):page60_i172:ddr3_dq(40)" )
			)
			( pin "U2D1.DU36"
				( objectStatus "@baseboard_fab2_lib.baseboard_fab2(sch_1):page60_i172:ddr3_dq(41)" )
			)
			( pin "U2D1.DP33"
				( objectStatus "@baseboard_fab2_lib.baseboard_fab2(sch_1):page60_i172:ddr3_dq(42)" )
			)
			( pin "U2D1.DT33"
				( objectStatus "@baseboard_fab2_lib.baseboard_fab2(sch_1):page60_i172:ddr3_dq(43)" )
			)
			( pin "U2D1.DP37"
				( objectStatus "@baseboard_fab2_lib.baseboard_fab2(sch_1):page60_i172:ddr3_dq(44)" )
			)
			( pin "U2D1.DT37"
				( objectStatus "@baseboard_fab2_lib.baseboard_fab2(sch_1):page60_i172:ddr3_dq(45)" )
			)
			( pin "U2D1.DN34"
				( objectStatus "@baseboard_fab2_lib.baseboard_fab2(sch_1):page60_i172:ddr3_dq(46)" )
			)
			( pin "U2D1.DU34"
				( objectStatus "@baseboard_fab2_lib.baseboard_fab2(sch_1):page60_i172:ddr3_dq(47)" )
			)
			( pin "U2D1.DN30"
				( objectStatus "@baseboard_fab2_lib.baseboard_fab2(sch_1):page60_i172:ddr3_dq(48)" )
			)
			( pin "U2D1.DU30"
				( objectStatus "@baseboard_fab2_lib.baseboard_fab2(sch_1):page60_i172:ddr3_dq(49)" )
			)
			( pin "U2D1.DP27"
				( objectStatus "@baseboard_fab2_lib.baseboard_fab2(sch_1):page60_i172:ddr3_dq(50)" )
			)
			( pin "U2D1.DT27"
				( objectStatus "@baseboard_fab2_lib.baseboard_fab2(sch_1):page60_i172:ddr3_dq(51)" )
			)
			( pin "U2D1.DP31"
				( objectStatus "@baseboard_fab2_lib.baseboard_fab2(sch_1):page60_i172:ddr3_dq(52)" )
			)
			( pin "U2D1.DT31"
				( objectStatus "@baseboard_fab2_lib.baseboard_fab2(sch_1):page60_i172:ddr3_dq(53)" )
			)
			( pin "U2D1.DN28"
				( objectStatus "@baseboard_fab2_lib.baseboard_fab2(sch_1):page60_i172:ddr3_dq(54)" )
			)
			( pin "U2D1.DU28"
				( objectStatus "@baseboard_fab2_lib.baseboard_fab2(sch_1):page60_i172:ddr3_dq(55)" )
			)
			( pin "U2D1.DN24"
				( objectStatus "@baseboard_fab2_lib.baseboard_fab2(sch_1):page60_i172:ddr3_dq(56)" )
			)
			( pin "U2D1.DU24"
				( objectStatus "@baseboard_fab2_lib.baseboard_fab2(sch_1):page60_i172:ddr3_dq(57)" )
			)
			( pin "U2D1.DY21"
				( objectStatus "@baseboard_fab2_lib.baseboard_fab2(sch_1):page60_i172:ddr3_dq(58)" )
			)
			( pin "U2D1.EB21"
				( objectStatus "@baseboard_fab2_lib.baseboard_fab2(sch_1):page60_i172:ddr3_dq(59)" )
			)
			( pin "U2D1.DP25"
				( objectStatus "@baseboard_fab2_lib.baseboard_fab2(sch_1):page60_i172:ddr3_dq(60)" )
			)
			( pin "U2D1.DT25"
				( objectStatus "@baseboard_fab2_lib.baseboard_fab2(sch_1):page60_i172:ddr3_dq(61)" )
			)
			( pin "U2D1.EC22"
				( objectStatus "@baseboard_fab2_lib.baseboard_fab2(sch_1):page60_i172:ddr3_dq(62)" )
			)
			( pin "U2D1.DW22"
				( objectStatus "@baseboard_fab2_lib.baseboard_fab2(sch_1):page60_i172:ddr3_dq(63)" )
			)
			( pin "U2D1.CU84"
				( objectStatus "@baseboard_fab2_lib.baseboard_fab2(sch_1):page60_i172:ddr3_dqs_dn(0)" )
			)
			( pin "U2D1.DN84"
				( objectStatus "@baseboard_fab2_lib.baseboard_fab2(sch_1):page60_i172:ddr3_dqs_dn(1)" )
			)
			( pin "U2D1.DL82"
				( objectStatus "@baseboard_fab2_lib.baseboard_fab2(sch_1):page60_i172:ddr3_dqs_dn(2)" )
			)
			( pin "U2D1.DV75"
				( objectStatus "@baseboard_fab2_lib.baseboard_fab2(sch_1):page60_i172:ddr3_dqs_dn(3)" )
			)
			( pin "U2D1.EE38"
				( objectStatus "@baseboard_fab2_lib.baseboard_fab2(sch_1):page60_i172:ddr3_dqs_dn(4)" )
			)
			( pin "U2D1.DV35"
				( objectStatus "@baseboard_fab2_lib.baseboard_fab2(sch_1):page60_i172:ddr3_dqs_dn(5)" )
			)
			( pin "U2D1.DV29"
				( objectStatus "@baseboard_fab2_lib.baseboard_fab2(sch_1):page60_i172:ddr3_dqs_dn(6)" )
			)
			( pin "U2D1.DV23"
				( objectStatus "@baseboard_fab2_lib.baseboard_fab2(sch_1):page60_i172:ddr3_dqs_dn(7)" )
			)
			( pin "U2D1.DF67"
				( objectStatus "@baseboard_fab2_lib.baseboard_fab2(sch_1):page60_i172:ddr3_dqs_dn(8)" )
			)
			( pin "U2D1.CR84"
				( objectStatus "@baseboard_fab2_lib.baseboard_fab2(sch_1):page60_i172:ddr3_dqs_dn(9)" )
			)
			( pin "U2D1.DM85"
				( objectStatus "@baseboard_fab2_lib.baseboard_fab2(sch_1):page60_i172:ddr3_dqs_dn(10)" )
			)
			( pin "U2D1.DN80"
				( objectStatus "@baseboard_fab2_lib.baseboard_fab2(sch_1):page60_i172:ddr3_dqs_dn(11)" )
			)
			( pin "U2D1.DP75"
				( objectStatus "@baseboard_fab2_lib.baseboard_fab2(sch_1):page60_i172:ddr3_dqs_dn(12)" )
			)
			( pin "U2D1.EA38"
				( objectStatus "@baseboard_fab2_lib.baseboard_fab2(sch_1):page60_i172:ddr3_dqs_dn(13)" )
			)
			( pin "U2D1.DP35"
				( objectStatus "@baseboard_fab2_lib.baseboard_fab2(sch_1):page60_i172:ddr3_dqs_dn(14)" )
			)
			( pin "U2D1.DM29"
				( objectStatus "@baseboard_fab2_lib.baseboard_fab2(sch_1):page60_i172:ddr3_dqs_dn(15)" )
			)
			( pin "U2D1.DM23"
				( objectStatus "@baseboard_fab2_lib.baseboard_fab2(sch_1):page60_i172:ddr3_dqs_dn(16)" )
			)
			( pin "U2D1.DB67"
				( objectStatus "@baseboard_fab2_lib.baseboard_fab2(sch_1):page60_i172:ddr3_dqs_dn(17)" )
			)
			( pin "U2D1.CV85"
				( objectStatus "@baseboard_fab2_lib.baseboard_fab2(sch_1):page60_i172:ddr3_dqs_dp(0)" )
			)
			( pin "U2D1.DP85"
				( objectStatus "@baseboard_fab2_lib.baseboard_fab2(sch_1):page60_i172:ddr3_dqs_dp(1)" )
			)
			( pin "U2D1.DM81"
				( objectStatus "@baseboard_fab2_lib.baseboard_fab2(sch_1):page60_i172:ddr3_dqs_dp(2)" )
			)
			( pin "U2D1.DT75"
				( objectStatus "@baseboard_fab2_lib.baseboard_fab2(sch_1):page60_i172:ddr3_dqs_dp(3)" )
			)
			( pin "U2D1.EC38"
				( objectStatus "@baseboard_fab2_lib.baseboard_fab2(sch_1):page60_i172:ddr3_dqs_dp(4)" )
			)
			( pin "U2D1.DT35"
				( objectStatus "@baseboard_fab2_lib.baseboard_fab2(sch_1):page60_i172:ddr3_dqs_dp(5)" )
			)
			( pin "U2D1.DT29"
				( objectStatus "@baseboard_fab2_lib.baseboard_fab2(sch_1):page60_i172:ddr3_dqs_dp(6)" )
			)
			( pin "U2D1.DT23"
				( objectStatus "@baseboard_fab2_lib.baseboard_fab2(sch_1):page60_i172:ddr3_dqs_dp(7)" )
			)
			( pin "U2D1.DD67"
				( objectStatus "@baseboard_fab2_lib.baseboard_fab2(sch_1):page60_i172:ddr3_dqs_dp(8)" )
			)
			( pin "U2D1.CP85"
				( objectStatus "@baseboard_fab2_lib.baseboard_fab2(sch_1):page60_i172:ddr3_dqs_dp(9)" )
			)
			( pin "U2D1.DL84"
				( objectStatus "@baseboard_fab2_lib.baseboard_fab2(sch_1):page60_i172:ddr3_dqs_dp(10)" )
			)
			( pin "U2D1.DP79"
				( objectStatus "@baseboard_fab2_lib.baseboard_fab2(sch_1):page60_i172:ddr3_dqs_dp(11)" )
			)
			( pin "U2D1.DM75"
				( objectStatus "@baseboard_fab2_lib.baseboard_fab2(sch_1):page60_i172:ddr3_dqs_dp(12)" )
			)
			( pin "U2D1.DW38"
				( objectStatus "@baseboard_fab2_lib.baseboard_fab2(sch_1):page60_i172:ddr3_dqs_dp(13)" )
			)
			( pin "U2D1.DM35"
				( objectStatus "@baseboard_fab2_lib.baseboard_fab2(sch_1):page60_i172:ddr3_dqs_dp(14)" )
			)
			( pin "U2D1.DP29"
				( objectStatus "@baseboard_fab2_lib.baseboard_fab2(sch_1):page60_i172:ddr3_dqs_dp(15)" )
			)
			( pin "U2D1.DP23"
				( objectStatus "@baseboard_fab2_lib.baseboard_fab2(sch_1):page60_i172:ddr3_dqs_dp(16)" )
			)
			( pin "U2D1.CY67"
				( objectStatus "@baseboard_fab2_lib.baseboard_fab2(sch_1):page60_i172:ddr3_dqs_dp(17)" )
			)
			( pin "U2D1.DA68"
				( objectStatus "@baseboard_fab2_lib.baseboard_fab2(sch_1):page60_i172:ddr3_ecc(0)" )
			)
			( pin "U2D1.DE68"
				( objectStatus "@baseboard_fab2_lib.baseboard_fab2(sch_1):page60_i172:ddr3_ecc(1)" )
			)
			( pin "U2D1.DB65"
				( objectStatus "@baseboard_fab2_lib.baseboard_fab2(sch_1):page60_i172:ddr3_ecc(2)" )
			)
			( pin "U2D1.DD65"
				( objectStatus "@baseboard_fab2_lib.baseboard_fab2(sch_1):page60_i172:ddr3_ecc(3)" )
			)
			( pin "U2D1.DB69"
				( objectStatus "@baseboard_fab2_lib.baseboard_fab2(sch_1):page60_i172:ddr3_ecc(4)" )
			)
			( pin "U2D1.DD69"
				( objectStatus "@baseboard_fab2_lib.baseboard_fab2(sch_1):page60_i172:ddr3_ecc(5)" )
			)
			( pin "U2D1.DA66"
				( objectStatus "@baseboard_fab2_lib.baseboard_fab2(sch_1):page60_i172:ddr3_ecc(6)" )
			)
			( pin "U2D1.DE66"
				( objectStatus "@baseboard_fab2_lib.baseboard_fab2(sch_1):page60_i172:ddr3_ecc(7)" )
			)
			( pin "U2D1.EB53"
				( objectStatus "@baseboard_fab2_lib.baseboard_fab2(sch_1):page60_i172:ddr3_ma(0)" )
			)
			( pin "U2D1.ED57"
				( objectStatus "@baseboard_fab2_lib.baseboard_fab2(sch_1):page60_i172:ddr3_ma(1)" )
			)
			( pin "U2D1.EE58"
				( objectStatus "@baseboard_fab2_lib.baseboard_fab2(sch_1):page60_i172:ddr3_ma(2)" )
			)
			( pin "U2D1.EB57"
				( objectStatus "@baseboard_fab2_lib.baseboard_fab2(sch_1):page60_i172:ddr3_ma(3)" )
			)
			( pin "U2D1.ED59"
				( objectStatus "@baseboard_fab2_lib.baseboard_fab2(sch_1):page60_i172:ddr3_ma(4)" )
			)
			( pin "U2D1.EA58"
				( objectStatus "@baseboard_fab2_lib.baseboard_fab2(sch_1):page60_i172:ddr3_ma(5)" )
			)
			( pin "U2D1.EE60"
				( objectStatus "@baseboard_fab2_lib.baseboard_fab2(sch_1):page60_i172:ddr3_ma(6)" )
			)
			( pin "U2D1.EA60"
				( objectStatus "@baseboard_fab2_lib.baseboard_fab2(sch_1):page60_i172:ddr3_ma(7)" )
			)
			( pin "U2D1.EB59"
				( objectStatus "@baseboard_fab2_lib.baseboard_fab2(sch_1):page60_i172:ddr3_ma(8)" )
			)
			( pin "U2D1.EF61"
				( objectStatus "@baseboard_fab2_lib.baseboard_fab2(sch_1):page60_i172:ddr3_ma(9)" )
			)
			( pin "U2D1.DW54"
				( objectStatus "@baseboard_fab2_lib.baseboard_fab2(sch_1):page60_i172:ddr3_ma(10)" )
			)
			( pin "U2D1.EB61"
				( objectStatus "@baseboard_fab2_lib.baseboard_fab2(sch_1):page60_i172:ddr3_ma(11)" )
			)
			( pin "U2D1.DT63"
				( objectStatus "@baseboard_fab2_lib.baseboard_fab2(sch_1):page60_i172:ddr3_ma(12)" )
			)
			( pin "U2D1.DW48"
				( objectStatus "@baseboard_fab2_lib.baseboard_fab2(sch_1):page60_i172:ddr3_ma(13)" )
			)
			( pin "U2D1.ED51"
				( objectStatus "@baseboard_fab2_lib.baseboard_fab2(sch_1):page60_i172:ddr3_ma(14)" )
			)
			( pin "U2D1.DV49"
				( objectStatus "@baseboard_fab2_lib.baseboard_fab2(sch_1):page60_i172:ddr3_ma(15)" )
			)
			( pin "U2D1.EA52"
				( objectStatus "@baseboard_fab2_lib.baseboard_fab2(sch_1):page60_i172:ddr3_ma(16)" )
			)
			( pin "U2D1.EA46"
				( objectStatus "@baseboard_fab2_lib.baseboard_fab2(sch_1):page60_i172:ddr3_ma(17)" )
			)
			( pin "U2D1.EE50"
				( objectStatus "@baseboard_fab2_lib.baseboard_fab2(sch_1):page60_i172:ddr3_odt(0)" )
			)
			( pin "U2D1.EE48"
				( objectStatus "@baseboard_fab2_lib.baseboard_fab2(sch_1):page60_i172:ddr3_odt(1)" )
			)
			( pin "U2D1.EA50"
				( objectStatus "@baseboard_fab2_lib.baseboard_fab2(sch_1):page60_i172:ddr3_odt(2)" )
			)
			( pin "U2D1.EA48"
				( objectStatus "@baseboard_fab2_lib.baseboard_fab2(sch_1):page60_i172:ddr3_odt(3)" )
			)
			( pin "U2D1.ED53"
				( objectStatus "@baseboard_fab2_lib.baseboard_fab2(sch_1):page60_i172:ddr3_par" )
			)
			( pin "U2D1.DR62"
				( objectStatus "@baseboard_fab2_lib.baseboard_fab2(sch_1):page61_i172:ddr4_act_n" )
			)
			( pin "U2D1.DT61"
				( objectStatus "@baseboard_fab2_lib.baseboard_fab2(sch_1):page61_i172:ddr4_alert_n" )
			)
			( pin "U2D1.DM53"
				( objectStatus "@baseboard_fab2_lib.baseboard_fab2(sch_1):page61_i172:ddr4_ba(0)" )
			)
			( pin "U2D1.DV55"
				( objectStatus "@baseboard_fab2_lib.baseboard_fab2(sch_1):page61_i172:ddr4_ba(1)" )
			)
			( pin "U2D1.DJ62"
				( objectStatus "@baseboard_fab2_lib.baseboard_fab2(sch_1):page61_i172:ddr4_bg(0)" )
			)
			( pin "U2D1.DM61"
				( objectStatus "@baseboard_fab2_lib.baseboard_fab2(sch_1):page61_i172:ddr4_bg(1)" )
			)
			( pin "U2D1.DT47"
				( objectStatus "@baseboard_fab2_lib.baseboard_fab2(sch_1):page61_i172:ddr4_cid(2)" )
			)
			( pin "U2D1.DM63"
				( objectStatus "@baseboard_fab2_lib.baseboard_fab2(sch_1):page61_i172:ddr4_cke(0)" )
			)
			( pin "U2D1.DN64"
				( objectStatus "@baseboard_fab2_lib.baseboard_fab2(sch_1):page61_i172:ddr4_cke(1)" )
			)
			( pin "U2D1.DL64"
				( objectStatus "@baseboard_fab2_lib.baseboard_fab2(sch_1):page61_i172:ddr4_cke(2)" )
			)
			( pin "U2D1.DR64"
				( objectStatus "@baseboard_fab2_lib.baseboard_fab2(sch_1):page61_i172:ddr4_cke(3)" )
			)
			( pin "U2D1.DM55"
				( objectStatus "@baseboard_fab2_lib.baseboard_fab2(sch_1):page61_i172:ddr4_clk_dn(0)" )
			)
			( pin "U2D1.DR54"
				( objectStatus "@baseboard_fab2_lib.baseboard_fab2(sch_1):page61_i172:ddr4_clk_dn(1)" )
			)
			( pin "U2D1.DM57"
				( objectStatus "@baseboard_fab2_lib.baseboard_fab2(sch_1):page61_i172:ddr4_clk_dn(2)" )
			)
			( pin "U2D1.DT57"
				( objectStatus "@baseboard_fab2_lib.baseboard_fab2(sch_1):page61_i172:ddr4_clk_dn(3)" )
			)
			( pin "U2D1.DN54"
				( objectStatus "@baseboard_fab2_lib.baseboard_fab2(sch_1):page61_i172:ddr4_clk_dp(0)" )
			)
			( pin "U2D1.DT53"
				( objectStatus "@baseboard_fab2_lib.baseboard_fab2(sch_1):page61_i172:ddr4_clk_dp(1)" )
			)
			( pin "U2D1.DN56"
				( objectStatus "@baseboard_fab2_lib.baseboard_fab2(sch_1):page61_i172:ddr4_clk_dp(2)" )
			)
			( pin "U2D1.DR56"
				( objectStatus "@baseboard_fab2_lib.baseboard_fab2(sch_1):page61_i172:ddr4_clk_dp(3)" )
			)
			( pin "U2D1.DV51"
				( objectStatus "@baseboard_fab2_lib.baseboard_fab2(sch_1):page61_i172:ddr4_cs_n(0)" )
			)
			( pin "U2D1.DN50"
				( objectStatus "@baseboard_fab2_lib.baseboard_fab2(sch_1):page61_i172:ddr4_cs_n(1)" )
			)
			( pin "U2D1.DR46"
				( objectStatus "@baseboard_fab2_lib.baseboard_fab2(sch_1):page61_i172:ddr4_cs_n(2)" )
			)
			( pin "U2D1.DK47"
				( objectStatus "@baseboard_fab2_lib.baseboard_fab2(sch_1):page61_i172:ddr4_cs_n(3)" )
			)
			( pin "U2D1.DW50"
				( objectStatus "@baseboard_fab2_lib.baseboard_fab2(sch_1):page61_i172:ddr4_cs_n(4)" )
			)
			( pin "U2D1.DM49"
				( objectStatus "@baseboard_fab2_lib.baseboard_fab2(sch_1):page61_i172:ddr4_cs_n(5)" )
			)
			( pin "U2D1.DT45"
				( objectStatus "@baseboard_fab2_lib.baseboard_fab2(sch_1):page61_i172:ddr4_cs_n(6)" )
			)
			( pin "U2D1.DN46"
				( objectStatus "@baseboard_fab2_lib.baseboard_fab2(sch_1):page61_i172:ddr4_cs_n(7)" )
			)
			( pin "U2D1.CM79"
				( objectStatus "@baseboard_fab2_lib.baseboard_fab2(sch_1):page61_i172:ddr4_dq(0)" )
			)
			( pin "U2D1.CK81"
				( objectStatus "@baseboard_fab2_lib.baseboard_fab2(sch_1):page61_i172:ddr4_dq(1)" )
			)
			( pin "U2D1.CT81"
				( objectStatus "@baseboard_fab2_lib.baseboard_fab2(sch_1):page61_i172:ddr4_dq(2)" )
			)
			( pin "U2D1.CR82"
				( objectStatus "@baseboard_fab2_lib.baseboard_fab2(sch_1):page61_i172:ddr4_dq(3)" )
			)
			( pin "U2D1.CK79"
				( objectStatus "@baseboard_fab2_lib.baseboard_fab2(sch_1):page61_i172:ddr4_dq(4)" )
			)
			( pin "U2D1.CJ80"
				( objectStatus "@baseboard_fab2_lib.baseboard_fab2(sch_1):page61_i172:ddr4_dq(5)" )
			)
			( pin "U2D1.CR80"
				( objectStatus "@baseboard_fab2_lib.baseboard_fab2(sch_1):page61_i172:ddr4_dq(6)" )
			)
			( pin "U2D1.CN82"
				( objectStatus "@baseboard_fab2_lib.baseboard_fab2(sch_1):page61_i172:ddr4_dq(7)" )
			)
			( pin "U2D1.DB79"
				( objectStatus "@baseboard_fab2_lib.baseboard_fab2(sch_1):page61_i172:ddr4_dq(8)" )
			)
			( pin "U2D1.CY81"
				( objectStatus "@baseboard_fab2_lib.baseboard_fab2(sch_1):page61_i172:ddr4_dq(9)" )
			)
			( pin "U2D1.DE80"
				( objectStatus "@baseboard_fab2_lib.baseboard_fab2(sch_1):page61_i172:ddr4_dq(10)" )
			)
			( pin "U2D1.DF81"
				( objectStatus "@baseboard_fab2_lib.baseboard_fab2(sch_1):page61_i172:ddr4_dq(11)" )
			)
			( pin "U2D1.CY79"
				( objectStatus "@baseboard_fab2_lib.baseboard_fab2(sch_1):page61_i172:ddr4_dq(12)" )
			)
			( pin "U2D1.CW80"
				( objectStatus "@baseboard_fab2_lib.baseboard_fab2(sch_1):page61_i172:ddr4_dq(13)" )
			)
			( pin "U2D1.DC82"
				( objectStatus "@baseboard_fab2_lib.baseboard_fab2(sch_1):page61_i172:ddr4_dq(14)" )
			)
			( pin "U2D1.DE82"
				( objectStatus "@baseboard_fab2_lib.baseboard_fab2(sch_1):page61_i172:ddr4_dq(15)" )
			)
			( pin "U2D1.DW80"
				( objectStatus "@baseboard_fab2_lib.baseboard_fab2(sch_1):page61_i172:ddr4_dq(16)" )
			)
			( pin "U2D1.EC80"
				( objectStatus "@baseboard_fab2_lib.baseboard_fab2(sch_1):page61_i172:ddr4_dq(17)" )
			)
			( pin "U2D1.DY77"
				( objectStatus "@baseboard_fab2_lib.baseboard_fab2(sch_1):page61_i172:ddr4_dq(18)" )
			)
			( pin "U2D1.EB77"
				( objectStatus "@baseboard_fab2_lib.baseboard_fab2(sch_1):page61_i172:ddr4_dq(19)" )
			)
			( pin "U2D1.DY81"
				( objectStatus "@baseboard_fab2_lib.baseboard_fab2(sch_1):page61_i172:ddr4_dq(20)" )
			)
			( pin "U2D1.EB81"
				( objectStatus "@baseboard_fab2_lib.baseboard_fab2(sch_1):page61_i172:ddr4_dq(21)" )
			)
			( pin "U2D1.DW78"
				( objectStatus "@baseboard_fab2_lib.baseboard_fab2(sch_1):page61_i172:ddr4_dq(22)" )
			)
			( pin "U2D1.EC78"
				( objectStatus "@baseboard_fab2_lib.baseboard_fab2(sch_1):page61_i172:ddr4_dq(23)" )
			)
			( pin "U2D1.ED75"
				( objectStatus "@baseboard_fab2_lib.baseboard_fab2(sch_1):page61_i172:ddr4_dq(24)" )
			)
			( pin "U2D1.EE74"
				( objectStatus "@baseboard_fab2_lib.baseboard_fab2(sch_1):page61_i172:ddr4_dq(25)" )
			)
			( pin "U2D1.EB71"
				( objectStatus "@baseboard_fab2_lib.baseboard_fab2(sch_1):page61_i172:ddr4_dq(26)" )
			)
			( pin "U2D1.ED71"
				( objectStatus "@baseboard_fab2_lib.baseboard_fab2(sch_1):page61_i172:ddr4_dq(27)" )
			)
			( pin "U2D1.EA74"
				( objectStatus "@baseboard_fab2_lib.baseboard_fab2(sch_1):page61_i172:ddr4_dq(28)" )
			)
			( pin "U2D1.EB75"
				( objectStatus "@baseboard_fab2_lib.baseboard_fab2(sch_1):page61_i172:ddr4_dq(29)" )
			)
			( pin "U2D1.EA72"
				( objectStatus "@baseboard_fab2_lib.baseboard_fab2(sch_1):page61_i172:ddr4_dq(30)" )
			)
			( pin "U2D1.EE72"
				( objectStatus "@baseboard_fab2_lib.baseboard_fab2(sch_1):page61_i172:ddr4_dq(31)" )
			)
			( pin "U2D1.DU42"
				( objectStatus "@baseboard_fab2_lib.baseboard_fab2(sch_1):page61_i172:ddr4_dq(32)" )
			)
			( pin "U2D1.DW42"
				( objectStatus "@baseboard_fab2_lib.baseboard_fab2(sch_1):page61_i172:ddr4_dq(33)" )
			)
			( pin "U2D1.DP39"
				( objectStatus "@baseboard_fab2_lib.baseboard_fab2(sch_1):page61_i172:ddr4_dq(34)" )
			)
			( pin "U2D1.DT39"
				( objectStatus "@baseboard_fab2_lib.baseboard_fab2(sch_1):page61_i172:ddr4_dq(35)" )
			)
			( pin "U2D1.DL42"
				( objectStatus "@baseboard_fab2_lib.baseboard_fab2(sch_1):page61_i172:ddr4_dq(36)" )
			)
			( pin "U2D1.DN42"
				( objectStatus "@baseboard_fab2_lib.baseboard_fab2(sch_1):page61_i172:ddr4_dq(37)" )
			)
			( pin "U2D1.DN40"
				( objectStatus "@baseboard_fab2_lib.baseboard_fab2(sch_1):page61_i172:ddr4_dq(38)" )
			)
			( pin "U2D1.DU40"
				( objectStatus "@baseboard_fab2_lib.baseboard_fab2(sch_1):page61_i172:ddr4_dq(39)" )
			)
			( pin "U2D1.EC34"
				( objectStatus "@baseboard_fab2_lib.baseboard_fab2(sch_1):page61_i172:ddr4_dq(40)" )
			)
			( pin "U2D1.ED33"
				( objectStatus "@baseboard_fab2_lib.baseboard_fab2(sch_1):page61_i172:ddr4_dq(41)" )
			)
			( pin "U2D1.EA30"
				( objectStatus "@baseboard_fab2_lib.baseboard_fab2(sch_1):page61_i172:ddr4_dq(42)" )
			)
			( pin "U2D1.EC30"
				( objectStatus "@baseboard_fab2_lib.baseboard_fab2(sch_1):page61_i172:ddr4_dq(43)" )
			)
			( pin "U2D1.DY33"
				( objectStatus "@baseboard_fab2_lib.baseboard_fab2(sch_1):page61_i172:ddr4_dq(44)" )
			)
			( pin "U2D1.EA34"
				( objectStatus "@baseboard_fab2_lib.baseboard_fab2(sch_1):page61_i172:ddr4_dq(45)" )
			)
			( pin "U2D1.DY31"
				( objectStatus "@baseboard_fab2_lib.baseboard_fab2(sch_1):page61_i172:ddr4_dq(46)" )
			)
			( pin "U2D1.ED31"
				( objectStatus "@baseboard_fab2_lib.baseboard_fab2(sch_1):page61_i172:ddr4_dq(47)" )
			)
			( pin "U2D1.EC28"
				( objectStatus "@baseboard_fab2_lib.baseboard_fab2(sch_1):page61_i172:ddr4_dq(48)" )
			)
			( pin "U2D1.ED27"
				( objectStatus "@baseboard_fab2_lib.baseboard_fab2(sch_1):page61_i172:ddr4_dq(49)" )
			)
			( pin "U2D1.EA24"
				( objectStatus "@baseboard_fab2_lib.baseboard_fab2(sch_1):page61_i172:ddr4_dq(50)" )
			)
			( pin "U2D1.EC24"
				( objectStatus "@baseboard_fab2_lib.baseboard_fab2(sch_1):page61_i172:ddr4_dq(51)" )
			)
			( pin "U2D1.DY27"
				( objectStatus "@baseboard_fab2_lib.baseboard_fab2(sch_1):page61_i172:ddr4_dq(52)" )
			)
			( pin "U2D1.EA28"
				( objectStatus "@baseboard_fab2_lib.baseboard_fab2(sch_1):page61_i172:ddr4_dq(53)" )
			)
			( pin "U2D1.DY25"
				( objectStatus "@baseboard_fab2_lib.baseboard_fab2(sch_1):page61_i172:ddr4_dq(54)" )
			)
			( pin "U2D1.ED25"
				( objectStatus "@baseboard_fab2_lib.baseboard_fab2(sch_1):page61_i172:ddr4_dq(55)" )
			)
			( pin "U2D1.DF27"
				( objectStatus "@baseboard_fab2_lib.baseboard_fab2(sch_1):page61_i172:ddr4_dq(56)" )
			)
			( pin "U2D1.DK27"
				( objectStatus "@baseboard_fab2_lib.baseboard_fab2(sch_1):page61_i172:ddr4_dq(57)" )
			)
			( pin "U2D1.DD25"
				( objectStatus "@baseboard_fab2_lib.baseboard_fab2(sch_1):page61_i172:ddr4_dq(58)" )
			)
			( pin "U2D1.DJ24"
				( objectStatus "@baseboard_fab2_lib.baseboard_fab2(sch_1):page61_i172:ddr4_dq(59)" )
			)
			( pin "U2D1.DG28"
				( objectStatus "@baseboard_fab2_lib.baseboard_fab2(sch_1):page61_i172:ddr4_dq(60)" )
			)
			( pin "U2D1.DJ28"
				( objectStatus "@baseboard_fab2_lib.baseboard_fab2(sch_1):page61_i172:ddr4_dq(61)" )
			)
			( pin "U2D1.DF25"
				( objectStatus "@baseboard_fab2_lib.baseboard_fab2(sch_1):page61_i172:ddr4_dq(62)" )
			)
			( pin "U2D1.DK25"
				( objectStatus "@baseboard_fab2_lib.baseboard_fab2(sch_1):page61_i172:ddr4_dq(63)" )
			)
			( pin "U2D1.CL82"
				( objectStatus "@baseboard_fab2_lib.baseboard_fab2(sch_1):page61_i172:ddr4_dqs_dn(0)" )
			)
			( pin "U2D1.DA82"
				( objectStatus "@baseboard_fab2_lib.baseboard_fab2(sch_1):page61_i172:ddr4_dqs_dn(1)" )
			)
			( pin "U2D1.ED79"
				( objectStatus "@baseboard_fab2_lib.baseboard_fab2(sch_1):page61_i172:ddr4_dqs_dn(2)" )
			)
			( pin "U2D1.EF73"
				( objectStatus "@baseboard_fab2_lib.baseboard_fab2(sch_1):page61_i172:ddr4_dqs_dn(3)" )
			)
			( pin "U2D1.DV41"
				( objectStatus "@baseboard_fab2_lib.baseboard_fab2(sch_1):page61_i172:ddr4_dqs_dn(4)" )
			)
			( pin "U2D1.EE32"
				( objectStatus "@baseboard_fab2_lib.baseboard_fab2(sch_1):page61_i172:ddr4_dqs_dn(5)" )
			)
			( pin "U2D1.EE26"
				( objectStatus "@baseboard_fab2_lib.baseboard_fab2(sch_1):page61_i172:ddr4_dqs_dn(6)" )
			)
			( pin "U2D1.DL26"
				( objectStatus "@baseboard_fab2_lib.baseboard_fab2(sch_1):page61_i172:ddr4_dqs_dn(7)" )
			)
			( pin "U2D1.EB67"
				( objectStatus "@baseboard_fab2_lib.baseboard_fab2(sch_1):page61_i172:ddr4_dqs_dn(8)" )
			)
			( pin "U2D1.CN80"
				( objectStatus "@baseboard_fab2_lib.baseboard_fab2(sch_1):page61_i172:ddr4_dqs_dn(9)" )
			)
			( pin "U2D1.DC80"
				( objectStatus "@baseboard_fab2_lib.baseboard_fab2(sch_1):page61_i172:ddr4_dqs_dn(10)" )
			)
			( pin "U2D1.DY79"
				( objectStatus "@baseboard_fab2_lib.baseboard_fab2(sch_1):page61_i172:ddr4_dqs_dn(11)" )
			)
			( pin "U2D1.EB73"
				( objectStatus "@baseboard_fab2_lib.baseboard_fab2(sch_1):page61_i172:ddr4_dqs_dn(12)" )
			)
			( pin "U2D1.DP41"
				( objectStatus "@baseboard_fab2_lib.baseboard_fab2(sch_1):page61_i172:ddr4_dqs_dn(13)" )
			)
			( pin "U2D1.EA32"
				( objectStatus "@baseboard_fab2_lib.baseboard_fab2(sch_1):page61_i172:ddr4_dqs_dn(14)" )
			)
			( pin "U2D1.EA26"
				( objectStatus "@baseboard_fab2_lib.baseboard_fab2(sch_1):page61_i172:ddr4_dqs_dn(15)" )
			)
			( pin "U2D1.DG26"
				( objectStatus "@baseboard_fab2_lib.baseboard_fab2(sch_1):page61_i172:ddr4_dqs_dn(16)" )
			)
			( pin "U2D1.DV67"
				( objectStatus "@baseboard_fab2_lib.baseboard_fab2(sch_1):page61_i172:ddr4_dqs_dn(17)" )
			)
			( pin "U2D1.CM81"
				( objectStatus "@baseboard_fab2_lib.baseboard_fab2(sch_1):page61_i172:ddr4_dqs_dp(0)" )
			)
			( pin "U2D1.DB81"
				( objectStatus "@baseboard_fab2_lib.baseboard_fab2(sch_1):page61_i172:ddr4_dqs_dp(1)" )
			)
			( pin "U2D1.EB79"
				( objectStatus "@baseboard_fab2_lib.baseboard_fab2(sch_1):page61_i172:ddr4_dqs_dp(2)" )
			)
			( pin "U2D1.ED73"
				( objectStatus "@baseboard_fab2_lib.baseboard_fab2(sch_1):page61_i172:ddr4_dqs_dp(3)" )
			)
			( pin "U2D1.DT41"
				( objectStatus "@baseboard_fab2_lib.baseboard_fab2(sch_1):page61_i172:ddr4_dqs_dp(4)" )
			)
			( pin "U2D1.EC32"
				( objectStatus "@baseboard_fab2_lib.baseboard_fab2(sch_1):page61_i172:ddr4_dqs_dp(5)" )
			)
			( pin "U2D1.EC26"
				( objectStatus "@baseboard_fab2_lib.baseboard_fab2(sch_1):page61_i172:ddr4_dqs_dp(6)" )
			)
			( pin "U2D1.DJ26"
				( objectStatus "@baseboard_fab2_lib.baseboard_fab2(sch_1):page61_i172:ddr4_dqs_dp(7)" )
			)
			( pin "U2D1.DY67"
				( objectStatus "@baseboard_fab2_lib.baseboard_fab2(sch_1):page61_i172:ddr4_dqs_dp(8)" )
			)
			( pin "U2D1.CP79"
				( objectStatus "@baseboard_fab2_lib.baseboard_fab2(sch_1):page61_i172:ddr4_dqs_dp(9)" )
			)
			( pin "U2D1.DD79"
				( objectStatus "@baseboard_fab2_lib.baseboard_fab2(sch_1):page61_i172:ddr4_dqs_dp(10)" )
			)
			( pin "U2D1.DV79"
				( objectStatus "@baseboard_fab2_lib.baseboard_fab2(sch_1):page61_i172:ddr4_dqs_dp(11)" )
			)
			( pin "U2D1.DY73"
				( objectStatus "@baseboard_fab2_lib.baseboard_fab2(sch_1):page61_i172:ddr4_dqs_dp(12)" )
			)
			( pin "U2D1.DM41"
				( objectStatus "@baseboard_fab2_lib.baseboard_fab2(sch_1):page61_i172:ddr4_dqs_dp(13)" )
			)
			( pin "U2D1.DW32"
				( objectStatus "@baseboard_fab2_lib.baseboard_fab2(sch_1):page61_i172:ddr4_dqs_dp(14)" )
			)
			( pin "U2D1.DW26"
				( objectStatus "@baseboard_fab2_lib.baseboard_fab2(sch_1):page61_i172:ddr4_dqs_dp(15)" )
			)
			( pin "U2D1.DE26"
				( objectStatus "@baseboard_fab2_lib.baseboard_fab2(sch_1):page61_i172:ddr4_dqs_dp(16)" )
			)
			( pin "U2D1.DT67"
				( objectStatus "@baseboard_fab2_lib.baseboard_fab2(sch_1):page61_i172:ddr4_dqs_dp(17)" )
			)
			( pin "U2D1.DY69"
				( objectStatus "@baseboard_fab2_lib.baseboard_fab2(sch_1):page61_i172:ddr4_ecc(0)" )
			)
			( pin "U2D1.EA68"
				( objectStatus "@baseboard_fab2_lib.baseboard_fab2(sch_1):page61_i172:ddr4_ecc(1)" )
			)
			( pin "U2D1.DV65"
				( objectStatus "@baseboard_fab2_lib.baseboard_fab2(sch_1):page61_i172:ddr4_ecc(2)" )
			)
			( pin "U2D1.DY65"
				( objectStatus "@baseboard_fab2_lib.baseboard_fab2(sch_1):page61_i172:ddr4_ecc(3)" )
			)
			( pin "U2D1.DU68"
				( objectStatus "@baseboard_fab2_lib.baseboard_fab2(sch_1):page61_i172:ddr4_ecc(4)" )
			)
			( pin "U2D1.DV69"
				( objectStatus "@baseboard_fab2_lib.baseboard_fab2(sch_1):page61_i172:ddr4_ecc(5)" )
			)
			( pin "U2D1.DU66"
				( objectStatus "@baseboard_fab2_lib.baseboard_fab2(sch_1):page61_i172:ddr4_ecc(6)" )
			)
			( pin "U2D1.EA66"
				( objectStatus "@baseboard_fab2_lib.baseboard_fab2(sch_1):page61_i172:ddr4_ecc(7)" )
			)
			( pin "U2D1.DW52"
				( objectStatus "@baseboard_fab2_lib.baseboard_fab2(sch_1):page61_i172:ddr4_ma(0)" )
			)
			( pin "U2D1.DW58"
				( objectStatus "@baseboard_fab2_lib.baseboard_fab2(sch_1):page61_i172:ddr4_ma(1)" )
			)
			( pin "U2D1.DV57"
				( objectStatus "@baseboard_fab2_lib.baseboard_fab2(sch_1):page61_i172:ddr4_ma(2)" )
			)
			( pin "U2D1.DR58"
				( objectStatus "@baseboard_fab2_lib.baseboard_fab2(sch_1):page61_i172:ddr4_ma(3)" )
			)
			( pin "U2D1.DT59"
				( objectStatus "@baseboard_fab2_lib.baseboard_fab2(sch_1):page61_i172:ddr4_ma(4)" )
			)
			( pin "U2D1.DN58"
				( objectStatus "@baseboard_fab2_lib.baseboard_fab2(sch_1):page61_i172:ddr4_ma(5)" )
			)
			( pin "U2D1.DM59"
				( objectStatus "@baseboard_fab2_lib.baseboard_fab2(sch_1):page61_i172:ddr4_ma(6)" )
			)
			( pin "U2D1.DK61"
				( objectStatus "@baseboard_fab2_lib.baseboard_fab2(sch_1):page61_i172:ddr4_ma(7)" )
			)
			( pin "U2D1.DJ60"
				( objectStatus "@baseboard_fab2_lib.baseboard_fab2(sch_1):page61_i172:ddr4_ma(8)" )
			)
			( pin "U2D1.DV59"
				( objectStatus "@baseboard_fab2_lib.baseboard_fab2(sch_1):page61_i172:ddr4_ma(9)" )
			)
			( pin "U2D1.DT55"
				( objectStatus "@baseboard_fab2_lib.baseboard_fab2(sch_1):page61_i172:ddr4_ma(10)" )
			)
			( pin "U2D1.DR60"
				( objectStatus "@baseboard_fab2_lib.baseboard_fab2(sch_1):page61_i172:ddr4_ma(11)" )
			)
			( pin "U2D1.DN60"
				( objectStatus "@baseboard_fab2_lib.baseboard_fab2(sch_1):page61_i172:ddr4_ma(12)" )
			)
			( pin "U2D1.DT51"
				( objectStatus "@baseboard_fab2_lib.baseboard_fab2(sch_1):page61_i172:ddr4_ma(13)" )
			)
			( pin "U2D1.DM51"
				( objectStatus "@baseboard_fab2_lib.baseboard_fab2(sch_1):page61_i172:ddr4_ma(14)" )
			)
			( pin "U2D1.DR52"
				( objectStatus "@baseboard_fab2_lib.baseboard_fab2(sch_1):page61_i172:ddr4_ma(15)" )
			)
			( pin "U2D1.DN52"
				( objectStatus "@baseboard_fab2_lib.baseboard_fab2(sch_1):page61_i172:ddr4_ma(16)" )
			)
			( pin "U2D1.DR48"
				( objectStatus "@baseboard_fab2_lib.baseboard_fab2(sch_1):page61_i172:ddr4_ma(17)" )
			)
			( pin "U2D1.DR50"
				( objectStatus "@baseboard_fab2_lib.baseboard_fab2(sch_1):page61_i172:ddr4_odt(0)" )
			)
			( pin "U2D1.DN48"
				( objectStatus "@baseboard_fab2_lib.baseboard_fab2(sch_1):page61_i172:ddr4_odt(1)" )
			)
			( pin "U2D1.DT49"
				( objectStatus "@baseboard_fab2_lib.baseboard_fab2(sch_1):page61_i172:ddr4_odt(2)" )
			)
			( pin "U2D1.DM47"
				( objectStatus "@baseboard_fab2_lib.baseboard_fab2(sch_1):page61_i172:ddr4_odt(3)" )
			)
			( pin "U2D1.DV53"
				( objectStatus "@baseboard_fab2_lib.baseboard_fab2(sch_1):page61_i172:ddr4_par" )
			)
			( pin "U2D1.DC62"
				( objectStatus "@baseboard_fab2_lib.baseboard_fab2(sch_1):page62_i172:ddr5_act_n" )
			)
			( pin "U2D1.DD61"
				( objectStatus "@baseboard_fab2_lib.baseboard_fab2(sch_1):page62_i172:ddr5_alert_n" )
			)
			( pin "U2D1.DJ52"
				( objectStatus "@baseboard_fab2_lib.baseboard_fab2(sch_1):page62_i172:ddr5_ba(0)" )
			)
			( pin "U2D1.DC56"
				( objectStatus "@baseboard_fab2_lib.baseboard_fab2(sch_1):page62_i172:ddr5_ba(1)" )
			)
			( pin "U2D1.DA62"
				( objectStatus "@baseboard_fab2_lib.baseboard_fab2(sch_1):page62_i172:ddr5_bg(0)" )
			)
			( pin "U2D1.DF61"
				( objectStatus "@baseboard_fab2_lib.baseboard_fab2(sch_1):page62_i172:ddr5_bg(1)" )
			)
			( pin "U2D1.DF45"
				( objectStatus "@baseboard_fab2_lib.baseboard_fab2(sch_1):page62_i172:ddr5_cid(2)" )
			)
			( pin "U2D1.DG62"
				( objectStatus "@baseboard_fab2_lib.baseboard_fab2(sch_1):page62_i172:ddr5_cke(0)" )
			)
			( pin "U2D1.DD63"
				( objectStatus "@baseboard_fab2_lib.baseboard_fab2(sch_1):page62_i172:ddr5_cke(1)" )
			)
			( pin "U2D1.DK63"
				( objectStatus "@baseboard_fab2_lib.baseboard_fab2(sch_1):page62_i172:ddr5_cke(2)" )
			)
			( pin "U2D1.DF63"
				( objectStatus "@baseboard_fab2_lib.baseboard_fab2(sch_1):page62_i172:ddr5_cke(3)" )
			)
			( pin "U2D1.DK55"
				( objectStatus "@baseboard_fab2_lib.baseboard_fab2(sch_1):page62_i172:ddr5_clk_dn(0)" )
			)
			( pin "U2D1.DF55"
				( objectStatus "@baseboard_fab2_lib.baseboard_fab2(sch_1):page62_i172:ddr5_clk_dn(1)" )
			)
			( pin "U2D1.DK57"
				( objectStatus "@baseboard_fab2_lib.baseboard_fab2(sch_1):page62_i172:ddr5_clk_dn(2)" )
			)
			( pin "U2D1.DF57"
				( objectStatus "@baseboard_fab2_lib.baseboard_fab2(sch_1):page62_i172:ddr5_clk_dn(3)" )
			)
			( pin "U2D1.DJ54"
				( objectStatus "@baseboard_fab2_lib.baseboard_fab2(sch_1):page62_i172:ddr5_clk_dp(0)" )
			)
			( pin "U2D1.DG54"
				( objectStatus "@baseboard_fab2_lib.baseboard_fab2(sch_1):page62_i172:ddr5_clk_dp(1)" )
			)
			( pin "U2D1.DJ56"
				( objectStatus "@baseboard_fab2_lib.baseboard_fab2(sch_1):page62_i172:ddr5_clk_dp(2)" )
			)
			( pin "U2D1.DG56"
				( objectStatus "@baseboard_fab2_lib.baseboard_fab2(sch_1):page62_i172:ddr5_clk_dp(3)" )
			)
			( pin "U2D1.DK51"
				( objectStatus "@baseboard_fab2_lib.baseboard_fab2(sch_1):page62_i172:ddr5_cs_n(0)" )
			)
			( pin "U2D1.DF49"
				( objectStatus "@baseboard_fab2_lib.baseboard_fab2(sch_1):page62_i172:ddr5_cs_n(1)" )
			)
			( pin "U2D1.DJ46"
				( objectStatus "@baseboard_fab2_lib.baseboard_fab2(sch_1):page62_i172:ddr5_cs_n(2)" )
			)
			( pin "U2D1.DG46"
				( objectStatus "@baseboard_fab2_lib.baseboard_fab2(sch_1):page62_i172:ddr5_cs_n(3)" )
			)
			( pin "U2D1.DF51"
				( objectStatus "@baseboard_fab2_lib.baseboard_fab2(sch_1):page62_i172:ddr5_cs_n(4)" )
			)
			( pin "U2D1.DJ48"
				( objectStatus "@baseboard_fab2_lib.baseboard_fab2(sch_1):page62_i172:ddr5_cs_n(5)" )
			)
			( pin "U2D1.DM45"
				( objectStatus "@baseboard_fab2_lib.baseboard_fab2(sch_1):page62_i172:ddr5_cs_n(6)" )
			)
			( pin "U2D1.DK45"
				( objectStatus "@baseboard_fab2_lib.baseboard_fab2(sch_1):page62_i172:ddr5_cs_n(7)" )
			)
			( pin "U2D1.CR74"
				( objectStatus "@baseboard_fab2_lib.baseboard_fab2(sch_1):page62_i172:ddr5_dq(0)" )
			)
			( pin "U2D1.CN76"
				( objectStatus "@baseboard_fab2_lib.baseboard_fab2(sch_1):page62_i172:ddr5_dq(1)" )
			)
			( pin "U2D1.CW76"
				( objectStatus "@baseboard_fab2_lib.baseboard_fab2(sch_1):page62_i172:ddr5_dq(2)" )
			)
			( pin "U2D1.CV77"
				( objectStatus "@baseboard_fab2_lib.baseboard_fab2(sch_1):page62_i172:ddr5_dq(3)" )
			)
			( pin "U2D1.CN74"
				( objectStatus "@baseboard_fab2_lib.baseboard_fab2(sch_1):page62_i172:ddr5_dq(4)" )
			)
			( pin "U2D1.CM75"
				( objectStatus "@baseboard_fab2_lib.baseboard_fab2(sch_1):page62_i172:ddr5_dq(5)" )
			)
			( pin "U2D1.CV75"
				( objectStatus "@baseboard_fab2_lib.baseboard_fab2(sch_1):page62_i172:ddr5_dq(6)" )
			)
			( pin "U2D1.CT77"
				( objectStatus "@baseboard_fab2_lib.baseboard_fab2(sch_1):page62_i172:ddr5_dq(7)" )
			)
			( pin "U2D1.DE74"
				( objectStatus "@baseboard_fab2_lib.baseboard_fab2(sch_1):page62_i172:ddr5_dq(8)" )
			)
			( pin "U2D1.DC76"
				( objectStatus "@baseboard_fab2_lib.baseboard_fab2(sch_1):page62_i172:ddr5_dq(9)" )
			)
			( pin "U2D1.DH75"
				( objectStatus "@baseboard_fab2_lib.baseboard_fab2(sch_1):page62_i172:ddr5_dq(10)" )
			)
			( pin "U2D1.DJ76"
				( objectStatus "@baseboard_fab2_lib.baseboard_fab2(sch_1):page62_i172:ddr5_dq(11)" )
			)
			( pin "U2D1.DC74"
				( objectStatus "@baseboard_fab2_lib.baseboard_fab2(sch_1):page62_i172:ddr5_dq(12)" )
			)
			( pin "U2D1.DB75"
				( objectStatus "@baseboard_fab2_lib.baseboard_fab2(sch_1):page62_i172:ddr5_dq(13)" )
			)
			( pin "U2D1.DF77"
				( objectStatus "@baseboard_fab2_lib.baseboard_fab2(sch_1):page62_i172:ddr5_dq(14)" )
			)
			( pin "U2D1.DH77"
				( objectStatus "@baseboard_fab2_lib.baseboard_fab2(sch_1):page62_i172:ddr5_dq(15)" )
			)
			( pin "U2D1.DG70"
				( objectStatus "@baseboard_fab2_lib.baseboard_fab2(sch_1):page62_i172:ddr5_dq(16)" )
			)
			( pin "U2D1.DJ72"
				( objectStatus "@baseboard_fab2_lib.baseboard_fab2(sch_1):page62_i172:ddr5_dq(17)" )
			)
			( pin "U2D1.DM69"
				( objectStatus "@baseboard_fab2_lib.baseboard_fab2(sch_1):page62_i172:ddr5_dq(18)" )
			)
			( pin "U2D1.DN70"
				( objectStatus "@baseboard_fab2_lib.baseboard_fab2(sch_1):page62_i172:ddr5_dq(19)" )
			)
			( pin "U2D1.DF71"
				( objectStatus "@baseboard_fab2_lib.baseboard_fab2(sch_1):page62_i172:ddr5_dq(20)" )
			)
			( pin "U2D1.DG72"
				( objectStatus "@baseboard_fab2_lib.baseboard_fab2(sch_1):page62_i172:ddr5_dq(21)" )
			)
			( pin "U2D1.DK69"
				( objectStatus "@baseboard_fab2_lib.baseboard_fab2(sch_1):page62_i172:ddr5_dq(22)" )
			)
			( pin "U2D1.DM71"
				( objectStatus "@baseboard_fab2_lib.baseboard_fab2(sch_1):page62_i172:ddr5_dq(23)" )
			)
			( pin "U2D1.CN66"
				( objectStatus "@baseboard_fab2_lib.baseboard_fab2(sch_1):page62_i172:ddr5_dq(24)" )
			)
			( pin "U2D1.CU66"
				( objectStatus "@baseboard_fab2_lib.baseboard_fab2(sch_1):page62_i172:ddr5_dq(25)" )
			)
			( pin "U2D1.CP63"
				( objectStatus "@baseboard_fab2_lib.baseboard_fab2(sch_1):page62_i172:ddr5_dq(26)" )
			)
			( pin "U2D1.CT63"
				( objectStatus "@baseboard_fab2_lib.baseboard_fab2(sch_1):page62_i172:ddr5_dq(27)" )
			)
			( pin "U2D1.CP67"
				( objectStatus "@baseboard_fab2_lib.baseboard_fab2(sch_1):page62_i172:ddr5_dq(28)" )
			)
			( pin "U2D1.CT67"
				( objectStatus "@baseboard_fab2_lib.baseboard_fab2(sch_1):page62_i172:ddr5_dq(29)" )
			)
			( pin "U2D1.CN64"
				( objectStatus "@baseboard_fab2_lib.baseboard_fab2(sch_1):page62_i172:ddr5_dq(30)" )
			)
			( pin "U2D1.CU64"
				( objectStatus "@baseboard_fab2_lib.baseboard_fab2(sch_1):page62_i172:ddr5_dq(31)" )
			)
			( pin "U2D1.DD41"
				( objectStatus "@baseboard_fab2_lib.baseboard_fab2(sch_1):page62_i172:ddr5_dq(32)" )
			)
			( pin "U2D1.DG42"
				( objectStatus "@baseboard_fab2_lib.baseboard_fab2(sch_1):page62_i172:ddr5_dq(33)" )
			)
			( pin "U2D1.DE38"
				( objectStatus "@baseboard_fab2_lib.baseboard_fab2(sch_1):page62_i172:ddr5_dq(34)" )
			)
			( pin "U2D1.DG38"
				( objectStatus "@baseboard_fab2_lib.baseboard_fab2(sch_1):page62_i172:ddr5_dq(35)" )
			)
			( pin "U2D1.DA42"
				( objectStatus "@baseboard_fab2_lib.baseboard_fab2(sch_1):page62_i172:ddr5_dq(36)" )
			)
			( pin "U2D1.DE42"
				( objectStatus "@baseboard_fab2_lib.baseboard_fab2(sch_1):page62_i172:ddr5_dq(37)" )
			)
			( pin "U2D1.DD39"
				( objectStatus "@baseboard_fab2_lib.baseboard_fab2(sch_1):page62_i172:ddr5_dq(38)" )
			)
			( pin "U2D1.DH39"
				( objectStatus "@baseboard_fab2_lib.baseboard_fab2(sch_1):page62_i172:ddr5_dq(39)" )
			)
			( pin "U2D1.DF33"
				( objectStatus "@baseboard_fab2_lib.baseboard_fab2(sch_1):page62_i172:ddr5_dq(40)" )
			)
			( pin "U2D1.DK33"
				( objectStatus "@baseboard_fab2_lib.baseboard_fab2(sch_1):page62_i172:ddr5_dq(41)" )
			)
			( pin "U2D1.DG30"
				( objectStatus "@baseboard_fab2_lib.baseboard_fab2(sch_1):page62_i172:ddr5_dq(42)" )
			)
			( pin "U2D1.DJ30"
				( objectStatus "@baseboard_fab2_lib.baseboard_fab2(sch_1):page62_i172:ddr5_dq(43)" )
			)
			( pin "U2D1.DG34"
				( objectStatus "@baseboard_fab2_lib.baseboard_fab2(sch_1):page62_i172:ddr5_dq(44)" )
			)
			( pin "U2D1.DJ34"
				( objectStatus "@baseboard_fab2_lib.baseboard_fab2(sch_1):page62_i172:ddr5_dq(45)" )
			)
			( pin "U2D1.DF31"
				( objectStatus "@baseboard_fab2_lib.baseboard_fab2(sch_1):page62_i172:ddr5_dq(46)" )
			)
			( pin "U2D1.DK31"
				( objectStatus "@baseboard_fab2_lib.baseboard_fab2(sch_1):page62_i172:ddr5_dq(47)" )
			)
			( pin "U2D1.CW36"
				( objectStatus "@baseboard_fab2_lib.baseboard_fab2(sch_1):page62_i172:ddr5_dq(48)" )
			)
			( pin "U2D1.DC36"
				( objectStatus "@baseboard_fab2_lib.baseboard_fab2(sch_1):page62_i172:ddr5_dq(49)" )
			)
			( pin "U2D1.CY33"
				( objectStatus "@baseboard_fab2_lib.baseboard_fab2(sch_1):page62_i172:ddr5_dq(50)" )
			)
			( pin "U2D1.DB33"
				( objectStatus "@baseboard_fab2_lib.baseboard_fab2(sch_1):page62_i172:ddr5_dq(51)" )
			)
			( pin "U2D1.CY37"
				( objectStatus "@baseboard_fab2_lib.baseboard_fab2(sch_1):page62_i172:ddr5_dq(52)" )
			)
			( pin "U2D1.DB37"
				( objectStatus "@baseboard_fab2_lib.baseboard_fab2(sch_1):page62_i172:ddr5_dq(53)" )
			)
			( pin "U2D1.CW34"
				( objectStatus "@baseboard_fab2_lib.baseboard_fab2(sch_1):page62_i172:ddr5_dq(54)" )
			)
			( pin "U2D1.DC34"
				( objectStatus "@baseboard_fab2_lib.baseboard_fab2(sch_1):page62_i172:ddr5_dq(55)" )
			)
			( pin "U2D1.CW30"
				( objectStatus "@baseboard_fab2_lib.baseboard_fab2(sch_1):page62_i172:ddr5_dq(56)" )
			)
			( pin "U2D1.DC30"
				( objectStatus "@baseboard_fab2_lib.baseboard_fab2(sch_1):page62_i172:ddr5_dq(57)" )
			)
			( pin "U2D1.CY27"
				( objectStatus "@baseboard_fab2_lib.baseboard_fab2(sch_1):page62_i172:ddr5_dq(58)" )
			)
			( pin "U2D1.DB27"
				( objectStatus "@baseboard_fab2_lib.baseboard_fab2(sch_1):page62_i172:ddr5_dq(59)" )
			)
			( pin "U2D1.CY31"
				( objectStatus "@baseboard_fab2_lib.baseboard_fab2(sch_1):page62_i172:ddr5_dq(60)" )
			)
			( pin "U2D1.DB31"
				( objectStatus "@baseboard_fab2_lib.baseboard_fab2(sch_1):page62_i172:ddr5_dq(61)" )
			)
			( pin "U2D1.CW28"
				( objectStatus "@baseboard_fab2_lib.baseboard_fab2(sch_1):page62_i172:ddr5_dq(62)" )
			)
			( pin "U2D1.DC28"
				( objectStatus "@baseboard_fab2_lib.baseboard_fab2(sch_1):page62_i172:ddr5_dq(63)" )
			)
			( pin "U2D1.CP77"
				( objectStatus "@baseboard_fab2_lib.baseboard_fab2(sch_1):page62_i172:ddr5_dqs_dn(0)" )
			)
			( pin "U2D1.DD77"
				( objectStatus "@baseboard_fab2_lib.baseboard_fab2(sch_1):page62_i172:ddr5_dqs_dn(1)" )
			)
			( pin "U2D1.DL72"
				( objectStatus "@baseboard_fab2_lib.baseboard_fab2(sch_1):page62_i172:ddr5_dqs_dn(2)" )
			)
			( pin "U2D1.CV65"
				( objectStatus "@baseboard_fab2_lib.baseboard_fab2(sch_1):page62_i172:ddr5_dqs_dn(3)" )
			)
			( pin "U2D1.DG40"
				( objectStatus "@baseboard_fab2_lib.baseboard_fab2(sch_1):page62_i172:ddr5_dqs_dn(4)" )
			)
			( pin "U2D1.DL32"
				( objectStatus "@baseboard_fab2_lib.baseboard_fab2(sch_1):page62_i172:ddr5_dqs_dn(5)" )
			)
			( pin "U2D1.DD35"
				( objectStatus "@baseboard_fab2_lib.baseboard_fab2(sch_1):page62_i172:ddr5_dqs_dn(6)" )
			)
			( pin "U2D1.DD29"
				( objectStatus "@baseboard_fab2_lib.baseboard_fab2(sch_1):page62_i172:ddr5_dqs_dn(7)" )
			)
			( pin "U2D1.CN70"
				( objectStatus "@baseboard_fab2_lib.baseboard_fab2(sch_1):page62_i172:ddr5_dqs_dn(8)" )
			)
			( pin "U2D1.CT75"
				( objectStatus "@baseboard_fab2_lib.baseboard_fab2(sch_1):page62_i172:ddr5_dqs_dn(9)" )
			)
			( pin "U2D1.DF75"
				( objectStatus "@baseboard_fab2_lib.baseboard_fab2(sch_1):page62_i172:ddr5_dqs_dn(10)" )
			)
			( pin "U2D1.DJ70"
				( objectStatus "@baseboard_fab2_lib.baseboard_fab2(sch_1):page62_i172:ddr5_dqs_dn(11)" )
			)
			( pin "U2D1.CP65"
				( objectStatus "@baseboard_fab2_lib.baseboard_fab2(sch_1):page62_i172:ddr5_dqs_dn(12)" )
			)
			( pin "U2D1.DE40"
				( objectStatus "@baseboard_fab2_lib.baseboard_fab2(sch_1):page62_i172:ddr5_dqs_dn(13)" )
			)
			( pin "U2D1.DG32"
				( objectStatus "@baseboard_fab2_lib.baseboard_fab2(sch_1):page62_i172:ddr5_dqs_dn(14)" )
			)
			( pin "U2D1.CY35"
				( objectStatus "@baseboard_fab2_lib.baseboard_fab2(sch_1):page62_i172:ddr5_dqs_dn(15)" )
			)
			( pin "U2D1.CY29"
				( objectStatus "@baseboard_fab2_lib.baseboard_fab2(sch_1):page62_i172:ddr5_dqs_dn(16)" )
			)
			( pin "U2D1.CJ70"
				( objectStatus "@baseboard_fab2_lib.baseboard_fab2(sch_1):page62_i172:ddr5_dqs_dn(17)" )
			)
			( pin "U2D1.CR76"
				( objectStatus "@baseboard_fab2_lib.baseboard_fab2(sch_1):page62_i172:ddr5_dqs_dp(0)" )
			)
			( pin "U2D1.DE76"
				( objectStatus "@baseboard_fab2_lib.baseboard_fab2(sch_1):page62_i172:ddr5_dqs_dp(1)" )
			)
			( pin "U2D1.DK71"
				( objectStatus "@baseboard_fab2_lib.baseboard_fab2(sch_1):page62_i172:ddr5_dqs_dp(2)" )
			)
			( pin "U2D1.CT65"
				( objectStatus "@baseboard_fab2_lib.baseboard_fab2(sch_1):page62_i172:ddr5_dqs_dp(3)" )
			)
			( pin "U2D1.DJ40"
				( objectStatus "@baseboard_fab2_lib.baseboard_fab2(sch_1):page62_i172:ddr5_dqs_dp(4)" )
			)
			( pin "U2D1.DJ32"
				( objectStatus "@baseboard_fab2_lib.baseboard_fab2(sch_1):page62_i172:ddr5_dqs_dp(5)" )
			)
			( pin "U2D1.DB35"
				( objectStatus "@baseboard_fab2_lib.baseboard_fab2(sch_1):page62_i172:ddr5_dqs_dp(6)" )
			)
			( pin "U2D1.DB29"
				( objectStatus "@baseboard_fab2_lib.baseboard_fab2(sch_1):page62_i172:ddr5_dqs_dp(7)" )
			)
			( pin "U2D1.CL70"
				( objectStatus "@baseboard_fab2_lib.baseboard_fab2(sch_1):page62_i172:ddr5_dqs_dp(8)" )
			)
			( pin "U2D1.CU74"
				( objectStatus "@baseboard_fab2_lib.baseboard_fab2(sch_1):page62_i172:ddr5_dqs_dp(9)" )
			)
			( pin "U2D1.DG74"
				( objectStatus "@baseboard_fab2_lib.baseboard_fab2(sch_1):page62_i172:ddr5_dqs_dp(10)" )
			)
			( pin "U2D1.DH69"
				( objectStatus "@baseboard_fab2_lib.baseboard_fab2(sch_1):page62_i172:ddr5_dqs_dp(11)" )
			)
			( pin "U2D1.CM65"
				( objectStatus "@baseboard_fab2_lib.baseboard_fab2(sch_1):page62_i172:ddr5_dqs_dp(12)" )
			)
			( pin "U2D1.DC40"
				( objectStatus "@baseboard_fab2_lib.baseboard_fab2(sch_1):page62_i172:ddr5_dqs_dp(13)" )
			)
			( pin "U2D1.DE32"
				( objectStatus "@baseboard_fab2_lib.baseboard_fab2(sch_1):page62_i172:ddr5_dqs_dp(14)" )
			)
			( pin "U2D1.CV35"
				( objectStatus "@baseboard_fab2_lib.baseboard_fab2(sch_1):page62_i172:ddr5_dqs_dp(15)" )
			)
			( pin "U2D1.CV29"
				( objectStatus "@baseboard_fab2_lib.baseboard_fab2(sch_1):page62_i172:ddr5_dqs_dp(16)" )
			)
			( pin "U2D1.CG70"
				( objectStatus "@baseboard_fab2_lib.baseboard_fab2(sch_1):page62_i172:ddr5_dqs_dp(17)" )
			)
			( pin "U2D1.CH71"
				( objectStatus "@baseboard_fab2_lib.baseboard_fab2(sch_1):page62_i172:ddr5_ecc(0)" )
			)
			( pin "U2D1.CM71"
				( objectStatus "@baseboard_fab2_lib.baseboard_fab2(sch_1):page62_i172:ddr5_ecc(1)" )
			)
			( pin "U2D1.CJ68"
				( objectStatus "@baseboard_fab2_lib.baseboard_fab2(sch_1):page62_i172:ddr5_ecc(2)" )
			)
			( pin "U2D1.CL68"
				( objectStatus "@baseboard_fab2_lib.baseboard_fab2(sch_1):page62_i172:ddr5_ecc(3)" )
			)
			( pin "U2D1.CJ72"
				( objectStatus "@baseboard_fab2_lib.baseboard_fab2(sch_1):page62_i172:ddr5_ecc(4)" )
			)
			( pin "U2D1.CL72"
				( objectStatus "@baseboard_fab2_lib.baseboard_fab2(sch_1):page62_i172:ddr5_ecc(5)" )
			)
			( pin "U2D1.CH69"
				( objectStatus "@baseboard_fab2_lib.baseboard_fab2(sch_1):page62_i172:ddr5_ecc(6)" )
			)
			( pin "U2D1.CM69"
				( objectStatus "@baseboard_fab2_lib.baseboard_fab2(sch_1):page62_i172:ddr5_ecc(7)" )
			)
			( pin "U2D1.DF53"
				( objectStatus "@baseboard_fab2_lib.baseboard_fab2(sch_1):page62_i172:ddr5_ma(0)" )
			)
			( pin "U2D1.DC58"
				( objectStatus "@baseboard_fab2_lib.baseboard_fab2(sch_1):page62_i172:ddr5_ma(1)" )
			)
			( pin "U2D1.DD57"
				( objectStatus "@baseboard_fab2_lib.baseboard_fab2(sch_1):page62_i172:ddr5_ma(2)" )
			)
			( pin "U2D1.DG58"
				( objectStatus "@baseboard_fab2_lib.baseboard_fab2(sch_1):page62_i172:ddr5_ma(3)" )
			)
			( pin "U2D1.DJ58"
				( objectStatus "@baseboard_fab2_lib.baseboard_fab2(sch_1):page62_i172:ddr5_ma(4)" )
			)
			( pin "U2D1.DF59"
				( objectStatus "@baseboard_fab2_lib.baseboard_fab2(sch_1):page62_i172:ddr5_ma(5)" )
			)
			( pin "U2D1.DK59"
				( objectStatus "@baseboard_fab2_lib.baseboard_fab2(sch_1):page62_i172:ddr5_ma(6)" )
			)
			( pin "U2D1.DC60"
				( objectStatus "@baseboard_fab2_lib.baseboard_fab2(sch_1):page62_i172:ddr5_ma(7)" )
			)
			( pin "U2D1.DD59"
				( objectStatus "@baseboard_fab2_lib.baseboard_fab2(sch_1):page62_i172:ddr5_ma(8)" )
			)
			( pin "U2D1.DA58"
				( objectStatus "@baseboard_fab2_lib.baseboard_fab2(sch_1):page62_i172:ddr5_ma(9)" )
			)
			( pin "U2D1.DD55"
				( objectStatus "@baseboard_fab2_lib.baseboard_fab2(sch_1):page62_i172:ddr5_ma(10)" )
			)
			( pin "U2D1.DA60"
				( objectStatus "@baseboard_fab2_lib.baseboard_fab2(sch_1):page62_i172:ddr5_ma(11)" )
			)
			( pin "U2D1.DG60"
				( objectStatus "@baseboard_fab2_lib.baseboard_fab2(sch_1):page62_i172:ddr5_ma(12)" )
			)
			( pin "U2D1.DD53"
				( objectStatus "@baseboard_fab2_lib.baseboard_fab2(sch_1):page62_i172:ddr5_ma(13)" )
			)
			( pin "U2D1.DJ50"
				( objectStatus "@baseboard_fab2_lib.baseboard_fab2(sch_1):page62_i172:ddr5_ma(14)" )
			)
			( pin "U2D1.DC54"
				( objectStatus "@baseboard_fab2_lib.baseboard_fab2(sch_1):page62_i172:ddr5_ma(15)" )
			)
			( pin "U2D1.DG52"
				( objectStatus "@baseboard_fab2_lib.baseboard_fab2(sch_1):page62_i172:ddr5_ma(16)" )
			)
			( pin "U2D1.DE46"
				( objectStatus "@baseboard_fab2_lib.baseboard_fab2(sch_1):page62_i172:ddr5_ma(17)" )
			)
			( pin "U2D1.DG50"
				( objectStatus "@baseboard_fab2_lib.baseboard_fab2(sch_1):page62_i172:ddr5_odt(0)" )
			)
			( pin "U2D1.DG48"
				( objectStatus "@baseboard_fab2_lib.baseboard_fab2(sch_1):page62_i172:ddr5_odt(1)" )
			)
			( pin "U2D1.DK49"
				( objectStatus "@baseboard_fab2_lib.baseboard_fab2(sch_1):page62_i172:ddr5_odt(2)" )
			)
			( pin "U2D1.DF47"
				( objectStatus "@baseboard_fab2_lib.baseboard_fab2(sch_1):page62_i172:ddr5_odt(3)" )
			)
			( pin "U2D1.DK53"
				( objectStatus "@baseboard_fab2_lib.baseboard_fab2(sch_1):page62_i172:ddr5_par" )
			)
			( pin "U2D1.BN22"
				( objectStatus "@baseboard_fab2_lib.baseboard_fab2(sch_1):page63_i23:cd_hfi0_i2cclk" )
			)
			( pin "U2D1.BP23"
				( objectStatus "@baseboard_fab2_lib.baseboard_fab2(sch_1):page63_i23:cd_hfi0_i2cdat" )
			)
			( pin "U2D1.BP19"
				( objectStatus "@baseboard_fab2_lib.baseboard_fab2(sch_1):page63_i23:cd_hfi0_int_n" )
			)
			( pin "U2D1.BK21"
				( objectStatus "@baseboard_fab2_lib.baseboard_fab2(sch_1):page63_i23:cd_hfi0_led_n" )
			)
			( pin "U2D1.BR20"
				( objectStatus "@baseboard_fab2_lib.baseboard_fab2(sch_1):page63_i23:cd_hfi0_modprst_n" )
			)
			( pin "U2D1.BN24"
				( objectStatus "@baseboard_fab2_lib.baseboard_fab2(sch_1):page63_i23:cd_hfi0_reset_n" )
			)
			( pin "U2D1.BJ22"
				( objectStatus "@baseboard_fab2_lib.baseboard_fab2(sch_1):page63_i23:cd_hfi1_i2cclk" )
			)
			( pin "U2D1.BH23"
				( objectStatus "@baseboard_fab2_lib.baseboard_fab2(sch_1):page63_i23:cd_hfi1_i2cdat" )
			)
			( pin "U2D1.BM21"
				( objectStatus "@baseboard_fab2_lib.baseboard_fab2(sch_1):page63_i23:cd_hfi1_int_n" )
			)
			( pin "U2D1.BM23"
				( objectStatus "@baseboard_fab2_lib.baseboard_fab2(sch_1):page63_i23:cd_hfi1_led_n" )
			)
			( pin "U2D1.BT19"
				( objectStatus "@baseboard_fab2_lib.baseboard_fab2(sch_1):page63_i23:cd_hfi1_modprst_n" )
			)
			( pin "U2D1.BK23"
				( objectStatus "@baseboard_fab2_lib.baseboard_fab2(sch_1):page63_i23:cd_hfi1_reset_n" )
			)
			( pin "U2D1.BE16"
				( objectStatus "@baseboard_fab2_lib.baseboard_fab2(sch_1):page63_i23:cd_hfi_refclk_dn" )
			)
			( pin "U2D1.BG16"
				( objectStatus "@baseboard_fab2_lib.baseboard_fab2(sch_1):page63_i23:cd_hfi_refclk_dp" )
			)
			( pin "U2D1.BU24"
				( objectStatus "@baseboard_fab2_lib.baseboard_fab2(sch_1):page63_i23:cd_pe_refclk_dn" )
			)
			( pin "U2D1.BW24"
				( objectStatus "@baseboard_fab2_lib.baseboard_fab2(sch_1):page63_i23:cd_pe_refclk_dp" )
			)
			( pin "U2D1.CF25"
				( objectStatus "@baseboard_fab2_lib.baseboard_fab2(sch_1):page63_i23:cd_por_n" )
			)
			( pin "U2D1.CB23"
				( objectStatus "@baseboard_fab2_lib.baseboard_fab2(sch_1):page63_i23:cd_tclk" )
			)
			( pin "U2D1.BY21"
				( objectStatus "@baseboard_fab2_lib.baseboard_fab2(sch_1):page63_i23:cd_tdi" )
			)
			( pin "U2D1.CC22"
				( objectStatus "@baseboard_fab2_lib.baseboard_fab2(sch_1):page63_i23:cd_tdo" )
			)
			( pin "U2D1.CE24"
				( objectStatus "@baseboard_fab2_lib.baseboard_fab2(sch_1):page63_i23:cd_tms" )
			)
			( pin "U2D1.CD23"
				( objectStatus "@baseboard_fab2_lib.baseboard_fab2(sch_1):page63_i23:cd_trst_n" )
			)
			( pin "U2D1.CK9"
				( objectStatus "@baseboard_fab2_lib.baseboard_fab2(sch_1):page63_i23:dmi_rx_dn(0)" )
			)
			( pin "U2D1.CM11"
				( objectStatus "@baseboard_fab2_lib.baseboard_fab2(sch_1):page63_i23:dmi_rx_dn(1)" )
			)
			( pin "U2D1.CR12"
				( objectStatus "@baseboard_fab2_lib.baseboard_fab2(sch_1):page63_i23:dmi_rx_dn(2)" )
			)
			( pin "U2D1.CT11"
				( objectStatus "@baseboard_fab2_lib.baseboard_fab2(sch_1):page63_i23:dmi_rx_dn(3)" )
			)
			( pin "U2D1.CL10"
				( objectStatus "@baseboard_fab2_lib.baseboard_fab2(sch_1):page63_i23:dmi_rx_dp(0)" )
			)
			( pin "U2D1.CN10"
				( objectStatus "@baseboard_fab2_lib.baseboard_fab2(sch_1):page63_i23:dmi_rx_dp(1)" )
			)
			( pin "U2D1.CP11"
				( objectStatus "@baseboard_fab2_lib.baseboard_fab2(sch_1):page63_i23:dmi_rx_dp(2)" )
			)
			( pin "U2D1.CV11"
				( objectStatus "@baseboard_fab2_lib.baseboard_fab2(sch_1):page63_i23:dmi_rx_dp(3)" )
			)
			( pin "U2D1.CG4"
				( objectStatus "@baseboard_fab2_lib.baseboard_fab2(sch_1):page63_i23:dmi_tx_dn(0)" )
			)
			( pin "U2D1.CJ4"
				( objectStatus "@baseboard_fab2_lib.baseboard_fab2(sch_1):page63_i23:dmi_tx_dn(1)" )
			)
			( pin "U2D1.CN4"
				( objectStatus "@baseboard_fab2_lib.baseboard_fab2(sch_1):page63_i23:dmi_tx_dn(2)" )
			)
			( pin "U2D1.CP5"
				( objectStatus "@baseboard_fab2_lib.baseboard_fab2(sch_1):page63_i23:dmi_tx_dn(3)" )
			)
			( pin "U2D1.CH5"
				( objectStatus "@baseboard_fab2_lib.baseboard_fab2(sch_1):page63_i23:dmi_tx_dp(0)" )
			)
			( pin "U2D1.CL4"
				( objectStatus "@baseboard_fab2_lib.baseboard_fab2(sch_1):page63_i23:dmi_tx_dp(1)" )
			)
			( pin "U2D1.CM3"
				( objectStatus "@baseboard_fab2_lib.baseboard_fab2(sch_1):page63_i23:dmi_tx_dp(2)" )
			)
			( pin "U2D1.CR4"
				( objectStatus "@baseboard_fab2_lib.baseboard_fab2(sch_1):page63_i23:dmi_tx_dp(3)" )
			)
			( pin "U2D1.BA76"
				( objectStatus "@baseboard_fab2_lib.baseboard_fab2(sch_1):page63_i23:rsvd(172)" )
			)
			( pin "U2D1.BA66"
				( objectStatus "@baseboard_fab2_lib.baseboard_fab2(sch_1):page63_i23:rsvd(173)" )
			)
			( pin "U2D1.BA64"
				( objectStatus "@baseboard_fab2_lib.baseboard_fab2(sch_1):page63_i23:rsvd(174)" )
			)
			( pin "U2D1.BA22"
				( objectStatus "@baseboard_fab2_lib.baseboard_fab2(sch_1):page63_i23:rsvd(175)" )
			)
			( pin "U2D1.BA18"
				( objectStatus "@baseboard_fab2_lib.baseboard_fab2(sch_1):page63_i23:rsvd(176)" )
			)
			( pin "U2D1.BA16"
				( objectStatus "@baseboard_fab2_lib.baseboard_fab2(sch_1):page63_i23:rsvd(177)" )
			)
			( pin "U2D1.BA14"
				( objectStatus "@baseboard_fab2_lib.baseboard_fab2(sch_1):page63_i23:rsvd(178)" )
			)
			( pin "U2D1.AY77"
				( objectStatus "@baseboard_fab2_lib.baseboard_fab2(sch_1):page63_i23:rsvd(179)" )
			)
			( pin "U2D1.AY75"
				( objectStatus "@baseboard_fab2_lib.baseboard_fab2(sch_1):page63_i23:rsvd(180)" )
			)
			( pin "U2D1.AY67"
				( objectStatus "@baseboard_fab2_lib.baseboard_fab2(sch_1):page63_i23:rsvd(181)" )
			)
			( pin "U2D1.AY65"
				( objectStatus "@baseboard_fab2_lib.baseboard_fab2(sch_1):page63_i23:rsvd(182)" )
			)
			( pin "U2D1.AW76"
				( objectStatus "@baseboard_fab2_lib.baseboard_fab2(sch_1):page63_i23:rsvd(183)" )
			)
			( pin "U2D1.AW64"
				( objectStatus "@baseboard_fab2_lib.baseboard_fab2(sch_1):page63_i23:rsvd(184)" )
			)
			( pin "U2D1.AV77"
				( objectStatus "@baseboard_fab2_lib.baseboard_fab2(sch_1):page63_i23:rsvd(186)" )
			)
			( pin "U2D1.AT25"
				( objectStatus "@baseboard_fab2_lib.baseboard_fab2(sch_1):page63_i23:rsvd(187)" )
			)
			( pin "U2D1.AT23"
				( objectStatus "@baseboard_fab2_lib.baseboard_fab2(sch_1):page63_i23:rsvd(188)" )
			)
			( pin "U2D1.AT13"
				( objectStatus "@baseboard_fab2_lib.baseboard_fab2(sch_1):page63_i23:rsvd(189)" )
			)
			( pin "U2D1.AR62"
				( objectStatus "@baseboard_fab2_lib.baseboard_fab2(sch_1):page63_i23:rsvd(190)" )
			)
			( pin "U2D1.AR26"
				( objectStatus "@baseboard_fab2_lib.baseboard_fab2(sch_1):page63_i23:rsvd(191)" )
			)
			( pin "U2D1.AR22"
				( objectStatus "@baseboard_fab2_lib.baseboard_fab2(sch_1):page63_i23:rsvd(192)" )
			)
			( pin "U2D1.AR20"
				( objectStatus "@baseboard_fab2_lib.baseboard_fab2(sch_1):page63_i23:rsvd(193)" )
			)
			( pin "U2D1.CW8"
				( objectStatus "@baseboard_fab2_lib.baseboard_fab2(sch_1):page64_i68:pe1_rx_dn(0)" )
			)
			( pin "U2D1.DA8"
				( objectStatus "@baseboard_fab2_lib.baseboard_fab2(sch_1):page64_i68:pe1_rx_dn(1)" )
			)
			( pin "U2D1.DC8"
				( objectStatus "@baseboard_fab2_lib.baseboard_fab2(sch_1):page64_i68:pe1_rx_dn(2)" )
			)
			( pin "U2D1.DC10"
				( objectStatus "@baseboard_fab2_lib.baseboard_fab2(sch_1):page64_i68:pe1_rx_dn(3)" )
			)
			( pin "U2D1.DE10"
				( objectStatus "@baseboard_fab2_lib.baseboard_fab2(sch_1):page64_i68:pe1_rx_dn(4)" )
			)
			( pin "U2D1.DH9"
				( objectStatus "@baseboard_fab2_lib.baseboard_fab2(sch_1):page64_i68:pe1_rx_dn(5)" )
			)
			( pin "U2D1.DK9"
				( objectStatus "@baseboard_fab2_lib.baseboard_fab2(sch_1):page64_i68:pe1_rx_dn(6)" )
			)
			( pin "U2D1.DM9"
				( objectStatus "@baseboard_fab2_lib.baseboard_fab2(sch_1):page64_i68:pe1_rx_dn(7)" )
			)
			( pin "U2D1.DM11"
				( objectStatus "@baseboard_fab2_lib.baseboard_fab2(sch_1):page64_i68:pe1_rx_dn(8)" )
			)
			( pin "U2D1.DP11"
				( objectStatus "@baseboard_fab2_lib.baseboard_fab2(sch_1):page64_i68:pe1_rx_dn(9)" )
			)
			( pin "U2D1.DT11"
				( objectStatus "@baseboard_fab2_lib.baseboard_fab2(sch_1):page64_i68:pe1_rx_dn(10)" )
			)
			( pin "U2D1.DT13"
				( objectStatus "@baseboard_fab2_lib.baseboard_fab2(sch_1):page64_i68:pe1_rx_dn(11)" )
			)
			( pin "U2D1.DV13"
				( objectStatus "@baseboard_fab2_lib.baseboard_fab2(sch_1):page64_i68:pe1_rx_dn(12)" )
			)
			( pin "U2D1.DW14"
				( objectStatus "@baseboard_fab2_lib.baseboard_fab2(sch_1):page64_i68:pe1_rx_dn(13)" )
			)
			( pin "U2D1.DY15"
				( objectStatus "@baseboard_fab2_lib.baseboard_fab2(sch_1):page64_i68:pe1_rx_dn(14)" )
			)
			( pin "U2D1.DU16"
				( objectStatus "@baseboard_fab2_lib.baseboard_fab2(sch_1):page64_i68:pe1_rx_dn(15)" )
			)
			( pin "U2D1.CU8"
				( objectStatus "@baseboard_fab2_lib.baseboard_fab2(sch_1):page64_i68:pe1_rx_dp(0)" )
			)
			( pin "U2D1.CY7"
				( objectStatus "@baseboard_fab2_lib.baseboard_fab2(sch_1):page64_i68:pe1_rx_dp(1)" )
			)
			( pin "U2D1.DB9"
				( objectStatus "@baseboard_fab2_lib.baseboard_fab2(sch_1):page64_i68:pe1_rx_dp(2)" )
			)
			( pin "U2D1.DA10"
				( objectStatus "@baseboard_fab2_lib.baseboard_fab2(sch_1):page64_i68:pe1_rx_dp(3)" )
			)
			( pin "U2D1.DD9"
				( objectStatus "@baseboard_fab2_lib.baseboard_fab2(sch_1):page64_i68:pe1_rx_dp(4)" )
			)
			( pin "U2D1.DF9"
				( objectStatus "@baseboard_fab2_lib.baseboard_fab2(sch_1):page64_i68:pe1_rx_dp(5)" )
			)
			( pin "U2D1.DJ8"
				( objectStatus "@baseboard_fab2_lib.baseboard_fab2(sch_1):page64_i68:pe1_rx_dp(6)" )
			)
			( pin "U2D1.DL10"
				( objectStatus "@baseboard_fab2_lib.baseboard_fab2(sch_1):page64_i68:pe1_rx_dp(7)" )
			)
			( pin "U2D1.DK11"
				( objectStatus "@baseboard_fab2_lib.baseboard_fab2(sch_1):page64_i68:pe1_rx_dp(8)" )
			)
			( pin "U2D1.DN10"
				( objectStatus "@baseboard_fab2_lib.baseboard_fab2(sch_1):page64_i68:pe1_rx_dp(9)" )
			)
			( pin "U2D1.DR12"
				( objectStatus "@baseboard_fab2_lib.baseboard_fab2(sch_1):page64_i68:pe1_rx_dp(10)" )
			)
			( pin "U2D1.DP13"
				( objectStatus "@baseboard_fab2_lib.baseboard_fab2(sch_1):page64_i68:pe1_rx_dp(11)" )
			)
			( pin "U2D1.DU12"
				( objectStatus "@baseboard_fab2_lib.baseboard_fab2(sch_1):page64_i68:pe1_rx_dp(12)" )
			)
			( pin "U2D1.DY13"
				( objectStatus "@baseboard_fab2_lib.baseboard_fab2(sch_1):page64_i68:pe1_rx_dp(13)" )
			)
			( pin "U2D1.DV15"
				( objectStatus "@baseboard_fab2_lib.baseboard_fab2(sch_1):page64_i68:pe1_rx_dp(14)" )
			)
			( pin "U2D1.DT15"
				( objectStatus "@baseboard_fab2_lib.baseboard_fab2(sch_1):page64_i68:pe1_rx_dp(15)" )
			)
			( pin "U2D1.DA2"
				( objectStatus "@baseboard_fab2_lib.baseboard_fab2(sch_1):page64_i68:pe1_tx_dn(0)" )
			)
			( pin "U2D1.DC2"
				( objectStatus "@baseboard_fab2_lib.baseboard_fab2(sch_1):page64_i68:pe1_tx_dn(1)" )
			)
			( pin "U2D1.DE2"
				( objectStatus "@baseboard_fab2_lib.baseboard_fab2(sch_1):page64_i68:pe1_tx_dn(2)" )
			)
			( pin "U2D1.DE4"
				( objectStatus "@baseboard_fab2_lib.baseboard_fab2(sch_1):page64_i68:pe1_tx_dn(3)" )
			)
			( pin "U2D1.DG4"
				( objectStatus "@baseboard_fab2_lib.baseboard_fab2(sch_1):page64_i68:pe1_tx_dn(4)" )
			)
			( pin "U2D1.DK3"
				( objectStatus "@baseboard_fab2_lib.baseboard_fab2(sch_1):page64_i68:pe1_tx_dn(5)" )
			)
			( pin "U2D1.DM3"
				( objectStatus "@baseboard_fab2_lib.baseboard_fab2(sch_1):page64_i68:pe1_tx_dn(6)" )
			)
			( pin "U2D1.DN4"
				( objectStatus "@baseboard_fab2_lib.baseboard_fab2(sch_1):page64_i68:pe1_tx_dn(7)" )
			)
			( pin "U2D1.DT5"
				( objectStatus "@baseboard_fab2_lib.baseboard_fab2(sch_1):page64_i68:pe1_tx_dn(8)" )
			)
			( pin "U2D1.DV3"
				( objectStatus "@baseboard_fab2_lib.baseboard_fab2(sch_1):page64_i68:pe1_tx_dn(9)" )
			)
			( pin "U2D1.DW4"
				( objectStatus "@baseboard_fab2_lib.baseboard_fab2(sch_1):page64_i68:pe1_tx_dn(10)" )
			)
			( pin "U2D1.DU6"
				( objectStatus "@baseboard_fab2_lib.baseboard_fab2(sch_1):page64_i68:pe1_tx_dn(11)" )
			)
			( pin "U2D1.DV7"
				( objectStatus "@baseboard_fab2_lib.baseboard_fab2(sch_1):page64_i68:pe1_tx_dn(12)" )
			)
			( pin "U2D1.DY7"
				( objectStatus "@baseboard_fab2_lib.baseboard_fab2(sch_1):page64_i68:pe1_tx_dn(13)" )
			)
			( pin "U2D1.EA8"
				( objectStatus "@baseboard_fab2_lib.baseboard_fab2(sch_1):page64_i68:pe1_tx_dn(14)" )
			)
			( pin "U2D1.ED9"
				( objectStatus "@baseboard_fab2_lib.baseboard_fab2(sch_1):page64_i68:pe1_tx_dn(15)" )
			)
			( pin "U2D1.CW2"
				( objectStatus "@baseboard_fab2_lib.baseboard_fab2(sch_1):page64_i68:pe1_tx_dp(0)" )
			)
			( pin "U2D1.DB1"
				( objectStatus "@baseboard_fab2_lib.baseboard_fab2(sch_1):page64_i68:pe1_tx_dp(1)" )
			)
			( pin "U2D1.DD3"
				( objectStatus "@baseboard_fab2_lib.baseboard_fab2(sch_1):page64_i68:pe1_tx_dp(2)" )
			)
			( pin "U2D1.DC4"
				( objectStatus "@baseboard_fab2_lib.baseboard_fab2(sch_1):page64_i68:pe1_tx_dp(3)" )
			)
			( pin "U2D1.DF3"
				( objectStatus "@baseboard_fab2_lib.baseboard_fab2(sch_1):page64_i68:pe1_tx_dp(4)" )
			)
			( pin "U2D1.DH3"
				( objectStatus "@baseboard_fab2_lib.baseboard_fab2(sch_1):page64_i68:pe1_tx_dp(5)" )
			)
			( pin "U2D1.DL2"
				( objectStatus "@baseboard_fab2_lib.baseboard_fab2(sch_1):page64_i68:pe1_tx_dp(6)" )
			)
			( pin "U2D1.DP3"
				( objectStatus "@baseboard_fab2_lib.baseboard_fab2(sch_1):page64_i68:pe1_tx_dp(7)" )
			)
			( pin "U2D1.DR4"
				( objectStatus "@baseboard_fab2_lib.baseboard_fab2(sch_1):page64_i68:pe1_tx_dp(8)" )
			)
			( pin "U2D1.DU2"
				( objectStatus "@baseboard_fab2_lib.baseboard_fab2(sch_1):page64_i68:pe1_tx_dp(9)" )
			)
			( pin "U2D1.DU4"
				( objectStatus "@baseboard_fab2_lib.baseboard_fab2(sch_1):page64_i68:pe1_tx_dp(10)" )
			)
			( pin "U2D1.DV5"
				( objectStatus "@baseboard_fab2_lib.baseboard_fab2(sch_1):page64_i68:pe1_tx_dp(11)" )
			)
			( pin "U2D1.DT7"
				( objectStatus "@baseboard_fab2_lib.baseboard_fab2(sch_1):page64_i68:pe1_tx_dp(12)" )
			)
			( pin "U2D1.DW6"
				( objectStatus "@baseboard_fab2_lib.baseboard_fab2(sch_1):page64_i68:pe1_tx_dp(13)" )
			)
			( pin "U2D1.EB7"
				( objectStatus "@baseboard_fab2_lib.baseboard_fab2(sch_1):page64_i68:pe1_tx_dp(14)" )
			)
			( pin "U2D1.EC8"
				( objectStatus "@baseboard_fab2_lib.baseboard_fab2(sch_1):page64_i68:pe1_tx_dp(15)" )
			)
			( pin "U2D1.CT9"
				( objectStatus "@baseboard_fab2_lib.baseboard_fab2(sch_1):page65_i68:pe2_rx_dn(0)" )
			)
			( pin "U2D1.CP9"
				( objectStatus "@baseboard_fab2_lib.baseboard_fab2(sch_1):page65_i68:pe2_rx_dn(1)" )
			)
			( pin "U2D1.CP7"
				( objectStatus "@baseboard_fab2_lib.baseboard_fab2(sch_1):page65_i68:pe2_rx_dn(2)" )
			)
			( pin "U2D1.CM7"
				( objectStatus "@baseboard_fab2_lib.baseboard_fab2(sch_1):page65_i68:pe2_rx_dn(3)" )
			)
			( pin "U2D1.CK7"
				( objectStatus "@baseboard_fab2_lib.baseboard_fab2(sch_1):page65_i68:pe2_rx_dn(4)" )
			)
			( pin "U2D1.CG8"
				( objectStatus "@baseboard_fab2_lib.baseboard_fab2(sch_1):page65_i68:pe2_rx_dn(5)" )
			)
			( pin "U2D1.CE6"
				( objectStatus "@baseboard_fab2_lib.baseboard_fab2(sch_1):page65_i68:pe2_rx_dn(6)" )
			)
			( pin "U2D1.CE8"
				( objectStatus "@baseboard_fab2_lib.baseboard_fab2(sch_1):page65_i68:pe2_rx_dn(7)" )
			)
			( pin "U2D1.BY9"
				( objectStatus "@baseboard_fab2_lib.baseboard_fab2(sch_1):page65_i68:pe2_rx_dn(8)" )
			)
			( pin "U2D1.BY7"
				( objectStatus "@baseboard_fab2_lib.baseboard_fab2(sch_1):page65_i68:pe2_rx_dn(9)" )
			)
			( pin "U2D1.BV7"
				( objectStatus "@baseboard_fab2_lib.baseboard_fab2(sch_1):page65_i68:pe2_rx_dn(10)" )
			)
			( pin "U2D1.BT7"
				( objectStatus "@baseboard_fab2_lib.baseboard_fab2(sch_1):page65_i68:pe2_rx_dn(11)" )
			)
			( pin "U2D1.BR8"
				( objectStatus "@baseboard_fab2_lib.baseboard_fab2(sch_1):page65_i68:pe2_rx_dn(12)" )
			)
			( pin "U2D1.BN8"
				( objectStatus "@baseboard_fab2_lib.baseboard_fab2(sch_1):page65_i68:pe2_rx_dn(13)" )
			)
			( pin "U2D1.BL8"
				( objectStatus "@baseboard_fab2_lib.baseboard_fab2(sch_1):page65_i68:pe2_rx_dn(14)" )
			)
			( pin "U2D1.BK9"
				( objectStatus "@baseboard_fab2_lib.baseboard_fab2(sch_1):page65_i68:pe2_rx_dn(15)" )
			)
			( pin "U2D1.CR8"
				( objectStatus "@baseboard_fab2_lib.baseboard_fab2(sch_1):page65_i68:pe2_rx_dp(0)" )
			)
			( pin "U2D1.CM9"
				( objectStatus "@baseboard_fab2_lib.baseboard_fab2(sch_1):page65_i68:pe2_rx_dp(1)" )
			)
			( pin "U2D1.CN8"
				( objectStatus "@baseboard_fab2_lib.baseboard_fab2(sch_1):page65_i68:pe2_rx_dp(2)" )
			)
			( pin "U2D1.CL6"
				( objectStatus "@baseboard_fab2_lib.baseboard_fab2(sch_1):page65_i68:pe2_rx_dp(3)" )
			)
			( pin "U2D1.CH7"
				( objectStatus "@baseboard_fab2_lib.baseboard_fab2(sch_1):page65_i68:pe2_rx_dp(4)" )
			)
			( pin "U2D1.CF7"
				( objectStatus "@baseboard_fab2_lib.baseboard_fab2(sch_1):page65_i68:pe2_rx_dp(5)" )
			)
			( pin "U2D1.CD7"
				( objectStatus "@baseboard_fab2_lib.baseboard_fab2(sch_1):page65_i68:pe2_rx_dp(6)" )
			)
			( pin "U2D1.CC8"
				( objectStatus "@baseboard_fab2_lib.baseboard_fab2(sch_1):page65_i68:pe2_rx_dp(7)" )
			)
			( pin "U2D1.BV9"
				( objectStatus "@baseboard_fab2_lib.baseboard_fab2(sch_1):page65_i68:pe2_rx_dp(8)" )
			)
			( pin "U2D1.BW8"
				( objectStatus "@baseboard_fab2_lib.baseboard_fab2(sch_1):page65_i68:pe2_rx_dp(9)" )
			)
			( pin "U2D1.BU6"
				( objectStatus "@baseboard_fab2_lib.baseboard_fab2(sch_1):page65_i68:pe2_rx_dp(10)" )
			)
			( pin "U2D1.BP7"
				( objectStatus "@baseboard_fab2_lib.baseboard_fab2(sch_1):page65_i68:pe2_rx_dp(11)" )
			)
			( pin "U2D1.BP9"
				( objectStatus "@baseboard_fab2_lib.baseboard_fab2(sch_1):page65_i68:pe2_rx_dp(12)" )
			)
			( pin "U2D1.BM7"
				( objectStatus "@baseboard_fab2_lib.baseboard_fab2(sch_1):page65_i68:pe2_rx_dp(13)" )
			)
			( pin "U2D1.BJ8"
				( objectStatus "@baseboard_fab2_lib.baseboard_fab2(sch_1):page65_i68:pe2_rx_dp(14)" )
			)
			( pin "U2D1.BJ10"
				( objectStatus "@baseboard_fab2_lib.baseboard_fab2(sch_1):page65_i68:pe2_rx_dp(15)" )
			)
			( pin "U2D1.CY3"
				( objectStatus "@baseboard_fab2_lib.baseboard_fab2(sch_1):page65_i68:pe2_tx_dn(0)" )
			)
			( pin "U2D1.CV3"
				( objectStatus "@baseboard_fab2_lib.baseboard_fab2(sch_1):page65_i68:pe2_tx_dn(1)" )
			)
			( pin "U2D1.CT1"
				( objectStatus "@baseboard_fab2_lib.baseboard_fab2(sch_1):page65_i68:pe2_tx_dn(2)" )
			)
			( pin "U2D1.CT3"
				( objectStatus "@baseboard_fab2_lib.baseboard_fab2(sch_1):page65_i68:pe2_tx_dn(3)" )
			)
			( pin "U2D1.CM1"
				( objectStatus "@baseboard_fab2_lib.baseboard_fab2(sch_1):page65_i68:pe2_tx_dn(4)" )
			)
			( pin "U2D1.CL2"
				( objectStatus "@baseboard_fab2_lib.baseboard_fab2(sch_1):page65_i68:pe2_tx_dn(5)" )
			)
			( pin "U2D1.CG2"
				( objectStatus "@baseboard_fab2_lib.baseboard_fab2(sch_1):page65_i68:pe2_tx_dn(6)" )
			)
			( pin "U2D1.CF3"
				( objectStatus "@baseboard_fab2_lib.baseboard_fab2(sch_1):page65_i68:pe2_tx_dn(7)" )
			)
			( pin "U2D1.CC2"
				( objectStatus "@baseboard_fab2_lib.baseboard_fab2(sch_1):page65_i68:pe2_tx_dn(8)" )
			)
			( pin "U2D1.CB3"
				( objectStatus "@baseboard_fab2_lib.baseboard_fab2(sch_1):page65_i68:pe2_tx_dn(9)" )
			)
			( pin "U2D1.CA4"
				( objectStatus "@baseboard_fab2_lib.baseboard_fab2(sch_1):page65_i68:pe2_tx_dn(10)" )
			)
			( pin "U2D1.BW4"
				( objectStatus "@baseboard_fab2_lib.baseboard_fab2(sch_1):page65_i68:pe2_tx_dn(11)" )
			)
			( pin "U2D1.BU4"
				( objectStatus "@baseboard_fab2_lib.baseboard_fab2(sch_1):page65_i68:pe2_tx_dn(12)" )
			)
			( pin "U2D1.BP5"
				( objectStatus "@baseboard_fab2_lib.baseboard_fab2(sch_1):page65_i68:pe2_tx_dn(13)" )
			)
			( pin "U2D1.BL4"
				( objectStatus "@baseboard_fab2_lib.baseboard_fab2(sch_1):page65_i68:pe2_tx_dn(14)" )
			)
			( pin "U2D1.BM5"
				( objectStatus "@baseboard_fab2_lib.baseboard_fab2(sch_1):page65_i68:pe2_tx_dn(15)" )
			)
			( pin "U2D1.CW4"
				( objectStatus "@baseboard_fab2_lib.baseboard_fab2(sch_1):page65_i68:pe2_tx_dp(0)" )
			)
			( pin "U2D1.CU2"
				( objectStatus "@baseboard_fab2_lib.baseboard_fab2(sch_1):page65_i68:pe2_tx_dp(1)" )
			)
			( pin "U2D1.CR2"
				( objectStatus "@baseboard_fab2_lib.baseboard_fab2(sch_1):page65_i68:pe2_tx_dp(2)" )
			)
			( pin "U2D1.CP3"
				( objectStatus "@baseboard_fab2_lib.baseboard_fab2(sch_1):page65_i68:pe2_tx_dp(3)" )
			)
			( pin "U2D1.CK1"
				( objectStatus "@baseboard_fab2_lib.baseboard_fab2(sch_1):page65_i68:pe2_tx_dp(4)" )
			)
			( pin "U2D1.CK3"
				( objectStatus "@baseboard_fab2_lib.baseboard_fab2(sch_1):page65_i68:pe2_tx_dp(5)" )
			)
			( pin "U2D1.CE2"
				( objectStatus "@baseboard_fab2_lib.baseboard_fab2(sch_1):page65_i68:pe2_tx_dp(6)" )
			)
			( pin "U2D1.CE4"
				( objectStatus "@baseboard_fab2_lib.baseboard_fab2(sch_1):page65_i68:pe2_tx_dp(7)" )
			)
			( pin "U2D1.CD3"
				( objectStatus "@baseboard_fab2_lib.baseboard_fab2(sch_1):page65_i68:pe2_tx_dp(8)" )
			)
			( pin "U2D1.BY3"
				( objectStatus "@baseboard_fab2_lib.baseboard_fab2(sch_1):page65_i68:pe2_tx_dp(9)" )
			)
			( pin "U2D1.BY5"
				( objectStatus "@baseboard_fab2_lib.baseboard_fab2(sch_1):page65_i68:pe2_tx_dp(10)" )
			)
			( pin "U2D1.BV3"
				( objectStatus "@baseboard_fab2_lib.baseboard_fab2(sch_1):page65_i68:pe2_tx_dp(11)" )
			)
			( pin "U2D1.BR4"
				( objectStatus "@baseboard_fab2_lib.baseboard_fab2(sch_1):page65_i68:pe2_tx_dp(12)" )
			)
			( pin "U2D1.BN4"
				( objectStatus "@baseboard_fab2_lib.baseboard_fab2(sch_1):page65_i68:pe2_tx_dp(13)" )
			)
			( pin "U2D1.BM3"
				( objectStatus "@baseboard_fab2_lib.baseboard_fab2(sch_1):page65_i68:pe2_tx_dp(14)" )
			)
			( pin "U2D1.BK5"
				( objectStatus "@baseboard_fab2_lib.baseboard_fab2(sch_1):page65_i68:pe2_tx_dp(15)" )
			)
			( pin "U2D1.EA18"
				( objectStatus "@baseboard_fab2_lib.baseboard_fab2(sch_1):page66_i84:pe3_rx_dn(0)" )
			)
			( pin "U2D1.DW18"
				( objectStatus "@baseboard_fab2_lib.baseboard_fab2(sch_1):page66_i84:pe3_rx_dn(1)" )
			)
			( pin "U2D1.DW16"
				( objectStatus "@baseboard_fab2_lib.baseboard_fab2(sch_1):page66_i84:pe3_rx_dn(2)" )
			)
			( pin "U2D1.DT19"
				( objectStatus "@baseboard_fab2_lib.baseboard_fab2(sch_1):page66_i84:pe3_rx_dn(3)" )
			)
			( pin "U2D1.DR16"
				( objectStatus "@baseboard_fab2_lib.baseboard_fab2(sch_1):page66_i84:pe3_rx_dn(4)" )
			)
			( pin "U2D1.DR14"
				( objectStatus "@baseboard_fab2_lib.baseboard_fab2(sch_1):page66_i84:pe3_rx_dn(5)" )
			)
			( pin "U2D1.DN14"
				( objectStatus "@baseboard_fab2_lib.baseboard_fab2(sch_1):page66_i84:pe3_rx_dn(6)" )
			)
			( pin "U2D1.DL14"
				( objectStatus "@baseboard_fab2_lib.baseboard_fab2(sch_1):page66_i84:pe3_rx_dn(7)" )
			)
			( pin "U2D1.DL12"
				( objectStatus "@baseboard_fab2_lib.baseboard_fab2(sch_1):page66_i84:pe3_rx_dn(8)" )
			)
			( pin "U2D1.DJ12"
				( objectStatus "@baseboard_fab2_lib.baseboard_fab2(sch_1):page66_i84:pe3_rx_dn(9)" )
			)
			( pin "U2D1.DG12"
				( objectStatus "@baseboard_fab2_lib.baseboard_fab2(sch_1):page66_i84:pe3_rx_dn(10)" )
			)
			( pin "U2D1.DG10"
				( objectStatus "@baseboard_fab2_lib.baseboard_fab2(sch_1):page66_i84:pe3_rx_dn(11)" )
			)
			( pin "U2D1.DD13"
				( objectStatus "@baseboard_fab2_lib.baseboard_fab2(sch_1):page66_i84:pe3_rx_dn(12)" )
			)
			( pin "U2D1.DB11"
				( objectStatus "@baseboard_fab2_lib.baseboard_fab2(sch_1):page66_i84:pe3_rx_dn(13)" )
			)
			( pin "U2D1.CY11"
				( objectStatus "@baseboard_fab2_lib.baseboard_fab2(sch_1):page66_i84:pe3_rx_dn(14)" )
			)
			( pin "U2D1.CV9"
				( objectStatus "@baseboard_fab2_lib.baseboard_fab2(sch_1):page66_i84:pe3_rx_dn(15)" )
			)
			( pin "U2D1.DY17"
				( objectStatus "@baseboard_fab2_lib.baseboard_fab2(sch_1):page66_i84:pe3_rx_dp(0)" )
			)
			( pin "U2D1.DU18"
				( objectStatus "@baseboard_fab2_lib.baseboard_fab2(sch_1):page66_i84:pe3_rx_dp(1)" )
			)
			( pin "U2D1.DV17"
				( objectStatus "@baseboard_fab2_lib.baseboard_fab2(sch_1):page66_i84:pe3_rx_dp(2)" )
			)
			( pin "U2D1.DR18"
				( objectStatus "@baseboard_fab2_lib.baseboard_fab2(sch_1):page66_i84:pe3_rx_dp(3)" )
			)
			( pin "U2D1.DN16"
				( objectStatus "@baseboard_fab2_lib.baseboard_fab2(sch_1):page66_i84:pe3_rx_dp(4)" )
			)
			( pin "U2D1.DP15"
				( objectStatus "@baseboard_fab2_lib.baseboard_fab2(sch_1):page66_i84:pe3_rx_dp(5)" )
			)
			( pin "U2D1.DM13"
				( objectStatus "@baseboard_fab2_lib.baseboard_fab2(sch_1):page66_i84:pe3_rx_dp(6)" )
			)
			( pin "U2D1.DJ14"
				( objectStatus "@baseboard_fab2_lib.baseboard_fab2(sch_1):page66_i84:pe3_rx_dp(7)" )
			)
			( pin "U2D1.DK13"
				( objectStatus "@baseboard_fab2_lib.baseboard_fab2(sch_1):page66_i84:pe3_rx_dp(8)" )
			)
			( pin "U2D1.DH11"
				( objectStatus "@baseboard_fab2_lib.baseboard_fab2(sch_1):page66_i84:pe3_rx_dp(9)" )
			)
			( pin "U2D1.DE12"
				( objectStatus "@baseboard_fab2_lib.baseboard_fab2(sch_1):page66_i84:pe3_rx_dp(10)" )
			)
			( pin "U2D1.DF11"
				( objectStatus "@baseboard_fab2_lib.baseboard_fab2(sch_1):page66_i84:pe3_rx_dp(11)" )
			)
			( pin "U2D1.DC12"
				( objectStatus "@baseboard_fab2_lib.baseboard_fab2(sch_1):page66_i84:pe3_rx_dp(12)" )
			)
			( pin "U2D1.DA12"
				( objectStatus "@baseboard_fab2_lib.baseboard_fab2(sch_1):page66_i84:pe3_rx_dp(13)" )
			)
			( pin "U2D1.CW10"
				( objectStatus "@baseboard_fab2_lib.baseboard_fab2(sch_1):page66_i84:pe3_rx_dp(14)" )
			)
			( pin "U2D1.CU10"
				( objectStatus "@baseboard_fab2_lib.baseboard_fab2(sch_1):page66_i84:pe3_rx_dp(15)" )
			)
			( pin "U2D1.EE14"
				( objectStatus "@baseboard_fab2_lib.baseboard_fab2(sch_1):page66_i84:pe3_tx_dn(0)" )
			)
			( pin "U2D1.EE12"
				( objectStatus "@baseboard_fab2_lib.baseboard_fab2(sch_1):page66_i84:pe3_tx_dn(1)" )
			)
			( pin "U2D1.EC12"
				( objectStatus "@baseboard_fab2_lib.baseboard_fab2(sch_1):page66_i84:pe3_tx_dn(2)" )
			)
			( pin "U2D1.DY11"
				( objectStatus "@baseboard_fab2_lib.baseboard_fab2(sch_1):page66_i84:pe3_tx_dn(3)" )
			)
			( pin "U2D1.EB9"
				( objectStatus "@baseboard_fab2_lib.baseboard_fab2(sch_1):page66_i84:pe3_tx_dn(4)" )
			)
			( pin "U2D1.DW10"
				( objectStatus "@baseboard_fab2_lib.baseboard_fab2(sch_1):page66_i84:pe3_tx_dn(5)" )
			)
			( pin "U2D1.DU8"
				( objectStatus "@baseboard_fab2_lib.baseboard_fab2(sch_1):page66_i84:pe3_tx_dn(6)" )
			)
			( pin "U2D1.DR8"
				( objectStatus "@baseboard_fab2_lib.baseboard_fab2(sch_1):page66_i84:pe3_tx_dn(7)" )
			)
			( pin "U2D1.DM7"
				( objectStatus "@baseboard_fab2_lib.baseboard_fab2(sch_1):page66_i84:pe3_tx_dn(8)" )
			)
			( pin "U2D1.DP5"
				( objectStatus "@baseboard_fab2_lib.baseboard_fab2(sch_1):page66_i84:pe3_tx_dn(9)" )
			)
			( pin "U2D1.DL6"
				( objectStatus "@baseboard_fab2_lib.baseboard_fab2(sch_1):page66_i84:pe3_tx_dn(10)" )
			)
			( pin "U2D1.DJ4"
				( objectStatus "@baseboard_fab2_lib.baseboard_fab2(sch_1):page66_i84:pe3_tx_dn(11)" )
			)
			( pin "U2D1.DJ6"
				( objectStatus "@baseboard_fab2_lib.baseboard_fab2(sch_1):page66_i84:pe3_tx_dn(12)" )
			)
			( pin "U2D1.DD5"
				( objectStatus "@baseboard_fab2_lib.baseboard_fab2(sch_1):page66_i84:pe3_tx_dn(13)" )
			)
			( pin "U2D1.DB5"
				( objectStatus "@baseboard_fab2_lib.baseboard_fab2(sch_1):page66_i84:pe3_tx_dn(14)" )
			)
			( pin "U2D1.CY5"
				( objectStatus "@baseboard_fab2_lib.baseboard_fab2(sch_1):page66_i84:pe3_tx_dn(15)" )
			)
			( pin "U2D1.EC14"
				( objectStatus "@baseboard_fab2_lib.baseboard_fab2(sch_1):page66_i84:pe3_tx_dp(0)" )
			)
			( pin "U2D1.ED13"
				( objectStatus "@baseboard_fab2_lib.baseboard_fab2(sch_1):page66_i84:pe3_tx_dp(1)" )
			)
			( pin "U2D1.EB11"
				( objectStatus "@baseboard_fab2_lib.baseboard_fab2(sch_1):page66_i84:pe3_tx_dp(2)" )
			)
			( pin "U2D1.EA10"
				( objectStatus "@baseboard_fab2_lib.baseboard_fab2(sch_1):page66_i84:pe3_tx_dp(3)" )
			)
			( pin "U2D1.DY9"
				( objectStatus "@baseboard_fab2_lib.baseboard_fab2(sch_1):page66_i84:pe3_tx_dp(4)" )
			)
			( pin "U2D1.DV9"
				( objectStatus "@baseboard_fab2_lib.baseboard_fab2(sch_1):page66_i84:pe3_tx_dp(5)" )
			)
			( pin "U2D1.DT9"
				( objectStatus "@baseboard_fab2_lib.baseboard_fab2(sch_1):page66_i84:pe3_tx_dp(6)" )
			)
			( pin "U2D1.DP7"
				( objectStatus "@baseboard_fab2_lib.baseboard_fab2(sch_1):page66_i84:pe3_tx_dp(7)" )
			)
			( pin "U2D1.DN6"
				( objectStatus "@baseboard_fab2_lib.baseboard_fab2(sch_1):page66_i84:pe3_tx_dp(8)" )
			)
			( pin "U2D1.DM5"
				( objectStatus "@baseboard_fab2_lib.baseboard_fab2(sch_1):page66_i84:pe3_tx_dp(9)" )
			)
			( pin "U2D1.DK5"
				( objectStatus "@baseboard_fab2_lib.baseboard_fab2(sch_1):page66_i84:pe3_tx_dp(10)" )
			)
			( pin "U2D1.DH5"
				( objectStatus "@baseboard_fab2_lib.baseboard_fab2(sch_1):page66_i84:pe3_tx_dp(11)" )
			)
			( pin "U2D1.DG6"
				( objectStatus "@baseboard_fab2_lib.baseboard_fab2(sch_1):page66_i84:pe3_tx_dp(12)" )
			)
			( pin "U2D1.DC6"
				( objectStatus "@baseboard_fab2_lib.baseboard_fab2(sch_1):page66_i84:pe3_tx_dp(13)" )
			)
			( pin "U2D1.DA4"
				( objectStatus "@baseboard_fab2_lib.baseboard_fab2(sch_1):page66_i84:pe3_tx_dp(14)" )
			)
			( pin "U2D1.CV5"
				( objectStatus "@baseboard_fab2_lib.baseboard_fab2(sch_1):page66_i84:pe3_tx_dp(15)" )
			)
			( pin "U2D1.AC10"
				( objectStatus "@baseboard_fab2_lib.baseboard_fab2(sch_1):page67_i132:upi0_rx_dn(0)" )
			)
			( pin "U2D1.AA8"
				( objectStatus "@baseboard_fab2_lib.baseboard_fab2(sch_1):page67_i132:upi0_rx_dn(1)" )
			)
			( pin "U2D1.AB7"
				( objectStatus "@baseboard_fab2_lib.baseboard_fab2(sch_1):page67_i132:upi0_rx_dn(2)" )
			)
			( pin "U2D1.AD5"
				( objectStatus "@baseboard_fab2_lib.baseboard_fab2(sch_1):page67_i132:upi0_rx_dn(3)" )
			)
			( pin "U2D1.AE6"
				( objectStatus "@baseboard_fab2_lib.baseboard_fab2(sch_1):page67_i132:upi0_rx_dn(4)" )
			)
			( pin "U2D1.AG8"
				( objectStatus "@baseboard_fab2_lib.baseboard_fab2(sch_1):page67_i132:upi0_rx_dn(5)" )
			)
			( pin "U2D1.AJ6"
				( objectStatus "@baseboard_fab2_lib.baseboard_fab2(sch_1):page67_i132:upi0_rx_dn(6)" )
			)
			( pin "U2D1.AL6"
				( objectStatus "@baseboard_fab2_lib.baseboard_fab2(sch_1):page67_i132:upi0_rx_dn(7)" )
			)
			( pin "U2D1.AK7"
				( objectStatus "@baseboard_fab2_lib.baseboard_fab2(sch_1):page67_i132:upi0_rx_dn(8)" )
			)
			( pin "U2D1.AM9"
				( objectStatus "@baseboard_fab2_lib.baseboard_fab2(sch_1):page67_i132:upi0_rx_dn(9)" )
			)
			( pin "U2D1.AP7"
				( objectStatus "@baseboard_fab2_lib.baseboard_fab2(sch_1):page67_i132:upi0_rx_dn(10)" )
			)
			( pin "U2D1.AR8"
				( objectStatus "@baseboard_fab2_lib.baseboard_fab2(sch_1):page67_i132:upi0_rx_dn(11)" )
			)
			( pin "U2D1.AU10"
				( objectStatus "@baseboard_fab2_lib.baseboard_fab2(sch_1):page67_i132:upi0_rx_dn(12)" )
			)
			( pin "U2D1.BA8"
				( objectStatus "@baseboard_fab2_lib.baseboard_fab2(sch_1):page67_i132:upi0_rx_dn(13)" )
			)
			( pin "U2D1.BC6"
				( objectStatus "@baseboard_fab2_lib.baseboard_fab2(sch_1):page67_i132:upi0_rx_dn(14)" )
			)
			( pin "U2D1.BD7"
				( objectStatus "@baseboard_fab2_lib.baseboard_fab2(sch_1):page67_i132:upi0_rx_dn(15)" )
			)
			( pin "U2D1.AW8"
				( objectStatus "@baseboard_fab2_lib.baseboard_fab2(sch_1):page67_i132:upi0_rx_dn(16)" )
			)
			( pin "U2D1.AY9"
				( objectStatus "@baseboard_fab2_lib.baseboard_fab2(sch_1):page67_i132:upi0_rx_dn(17)" )
			)
			( pin "U2D1.BD9"
				( objectStatus "@baseboard_fab2_lib.baseboard_fab2(sch_1):page67_i132:upi0_rx_dn(18)" )
			)
			( pin "U2D1.BB11"
				( objectStatus "@baseboard_fab2_lib.baseboard_fab2(sch_1):page67_i132:upi0_rx_dn(19)" )
			)
			( pin "U2D1.AB9"
				( objectStatus "@baseboard_fab2_lib.baseboard_fab2(sch_1):page67_i132:upi0_rx_dp(0)" )
			)
			( pin "U2D1.AC8"
				( objectStatus "@baseboard_fab2_lib.baseboard_fab2(sch_1):page67_i132:upi0_rx_dp(1)" )
			)
			( pin "U2D1.AA6"
				( objectStatus "@baseboard_fab2_lib.baseboard_fab2(sch_1):page67_i132:upi0_rx_dp(2)" )
			)
			( pin "U2D1.AC6"
				( objectStatus "@baseboard_fab2_lib.baseboard_fab2(sch_1):page67_i132:upi0_rx_dp(3)" )
			)
			( pin "U2D1.AG6"
				( objectStatus "@baseboard_fab2_lib.baseboard_fab2(sch_1):page67_i132:upi0_rx_dp(4)" )
			)
			( pin "U2D1.AF7"
				( objectStatus "@baseboard_fab2_lib.baseboard_fab2(sch_1):page67_i132:upi0_rx_dp(5)" )
			)
			( pin "U2D1.AH7"
				( objectStatus "@baseboard_fab2_lib.baseboard_fab2(sch_1):page67_i132:upi0_rx_dp(6)" )
			)
			( pin "U2D1.AK5"
				( objectStatus "@baseboard_fab2_lib.baseboard_fab2(sch_1):page67_i132:upi0_rx_dp(7)" )
			)
			( pin "U2D1.AM7"
				( objectStatus "@baseboard_fab2_lib.baseboard_fab2(sch_1):page67_i132:upi0_rx_dp(8)" )
			)
			( pin "U2D1.AL8"
				( objectStatus "@baseboard_fab2_lib.baseboard_fab2(sch_1):page67_i132:upi0_rx_dp(9)" )
			)
			( pin "U2D1.AN8"
				( objectStatus "@baseboard_fab2_lib.baseboard_fab2(sch_1):page67_i132:upi0_rx_dp(10)" )
			)
			( pin "U2D1.AU8"
				( objectStatus "@baseboard_fab2_lib.baseboard_fab2(sch_1):page67_i132:upi0_rx_dp(11)" )
			)
			( pin "U2D1.AT9"
				( objectStatus "@baseboard_fab2_lib.baseboard_fab2(sch_1):page67_i132:upi0_rx_dp(12)" )
			)
			( pin "U2D1.AY7"
				( objectStatus "@baseboard_fab2_lib.baseboard_fab2(sch_1):page67_i132:upi0_rx_dp(13)" )
			)
			( pin "U2D1.BB7"
				( objectStatus "@baseboard_fab2_lib.baseboard_fab2(sch_1):page67_i132:upi0_rx_dp(14)" )
			)
			( pin "U2D1.BF7"
				( objectStatus "@baseboard_fab2_lib.baseboard_fab2(sch_1):page67_i132:upi0_rx_dp(15)" )
			)
			( pin "U2D1.AV9"
				( objectStatus "@baseboard_fab2_lib.baseboard_fab2(sch_1):page67_i132:upi0_rx_dp(16)" )
			)
			( pin "U2D1.BB9"
				( objectStatus "@baseboard_fab2_lib.baseboard_fab2(sch_1):page67_i132:upi0_rx_dp(17)" )
			)
			( pin "U2D1.BC10"
				( objectStatus "@baseboard_fab2_lib.baseboard_fab2(sch_1):page67_i132:upi0_rx_dp(18)" )
			)
			( pin "U2D1.BA10"
				( objectStatus "@baseboard_fab2_lib.baseboard_fab2(sch_1):page67_i132:upi0_rx_dp(19)" )
			)
			( pin "U2D1.N2"
				( objectStatus "@baseboard_fab2_lib.baseboard_fab2(sch_1):page67_i132:upi0_tx_dn(0)" )
			)
			( pin "U2D1.P1"
				( objectStatus "@baseboard_fab2_lib.baseboard_fab2(sch_1):page67_i132:upi0_tx_dn(1)" )
			)
			( pin "U2D1.V3"
				( objectStatus "@baseboard_fab2_lib.baseboard_fab2(sch_1):page67_i132:upi0_tx_dn(2)" )
			)
			( pin "U2D1.Y1"
				( objectStatus "@baseboard_fab2_lib.baseboard_fab2(sch_1):page67_i132:upi0_tx_dn(3)" )
			)
			( pin "U2D1.AB3"
				( objectStatus "@baseboard_fab2_lib.baseboard_fab2(sch_1):page67_i132:upi0_tx_dn(4)" )
			)
			( pin "U2D1.AC2"
				( objectStatus "@baseboard_fab2_lib.baseboard_fab2(sch_1):page67_i132:upi0_tx_dn(5)" )
			)
			( pin "U2D1.AG4"
				( objectStatus "@baseboard_fab2_lib.baseboard_fab2(sch_1):page67_i132:upi0_tx_dn(6)" )
			)
			( pin "U2D1.AE2"
				( objectStatus "@baseboard_fab2_lib.baseboard_fab2(sch_1):page67_i132:upi0_tx_dn(7)" )
			)
			( pin "U2D1.AH3"
				( objectStatus "@baseboard_fab2_lib.baseboard_fab2(sch_1):page67_i132:upi0_tx_dn(8)" )
			)
			( pin "U2D1.AL2"
				( objectStatus "@baseboard_fab2_lib.baseboard_fab2(sch_1):page67_i132:upi0_tx_dn(9)" )
			)
			( pin "U2D1.AM3"
				( objectStatus "@baseboard_fab2_lib.baseboard_fab2(sch_1):page67_i132:upi0_tx_dn(10)" )
			)
			( pin "U2D1.AN4"
				( objectStatus "@baseboard_fab2_lib.baseboard_fab2(sch_1):page67_i132:upi0_tx_dn(11)" )
			)
			( pin "U2D1.AT1"
				( objectStatus "@baseboard_fab2_lib.baseboard_fab2(sch_1):page67_i132:upi0_tx_dn(12)" )
			)
			( pin "U2D1.AT3"
				( objectStatus "@baseboard_fab2_lib.baseboard_fab2(sch_1):page67_i132:upi0_tx_dn(13)" )
			)
			( pin "U2D1.AU4"
				( objectStatus "@baseboard_fab2_lib.baseboard_fab2(sch_1):page67_i132:upi0_tx_dn(14)" )
			)
			( pin "U2D1.AV5"
				( objectStatus "@baseboard_fab2_lib.baseboard_fab2(sch_1):page67_i132:upi0_tx_dn(15)" )
			)
			( pin "U2D1.BA4"
				( objectStatus "@baseboard_fab2_lib.baseboard_fab2(sch_1):page67_i132:upi0_tx_dn(16)" )
			)
			( pin "U2D1.BB3"
				( objectStatus "@baseboard_fab2_lib.baseboard_fab2(sch_1):page67_i132:upi0_tx_dn(17)" )
			)
			( pin "U2D1.BF3"
				( objectStatus "@baseboard_fab2_lib.baseboard_fab2(sch_1):page67_i132:upi0_tx_dn(18)" )
			)
			( pin "U2D1.BG4"
				( objectStatus "@baseboard_fab2_lib.baseboard_fab2(sch_1):page67_i132:upi0_tx_dn(19)" )
			)
			( pin "U2D1.M1"
				( objectStatus "@baseboard_fab2_lib.baseboard_fab2(sch_1):page67_i132:upi0_tx_dp(0)" )
			)
			( pin "U2D1.T1"
				( objectStatus "@baseboard_fab2_lib.baseboard_fab2(sch_1):page67_i132:upi0_tx_dp(1)" )
			)
			( pin "U2D1.Y3"
				( objectStatus "@baseboard_fab2_lib.baseboard_fab2(sch_1):page67_i132:upi0_tx_dp(2)" )
			)
			( pin "U2D1.W2"
				( objectStatus "@baseboard_fab2_lib.baseboard_fab2(sch_1):page67_i132:upi0_tx_dp(3)" )
			)
			( pin "U2D1.AA2"
				( objectStatus "@baseboard_fab2_lib.baseboard_fab2(sch_1):page67_i132:upi0_tx_dp(4)" )
			)
			( pin "U2D1.AD1"
				( objectStatus "@baseboard_fab2_lib.baseboard_fab2(sch_1):page67_i132:upi0_tx_dp(5)" )
			)
			( pin "U2D1.AF3"
				( objectStatus "@baseboard_fab2_lib.baseboard_fab2(sch_1):page67_i132:upi0_tx_dp(6)" )
			)
			( pin "U2D1.AG2"
				( objectStatus "@baseboard_fab2_lib.baseboard_fab2(sch_1):page67_i132:upi0_tx_dp(7)" )
			)
			( pin "U2D1.AJ2"
				( objectStatus "@baseboard_fab2_lib.baseboard_fab2(sch_1):page67_i132:upi0_tx_dp(8)" )
			)
			( pin "U2D1.AK1"
				( objectStatus "@baseboard_fab2_lib.baseboard_fab2(sch_1):page67_i132:upi0_tx_dp(9)" )
			)
			( pin "U2D1.AK3"
				( objectStatus "@baseboard_fab2_lib.baseboard_fab2(sch_1):page67_i132:upi0_tx_dp(10)" )
			)
			( pin "U2D1.AP3"
				( objectStatus "@baseboard_fab2_lib.baseboard_fab2(sch_1):page67_i132:upi0_tx_dp(11)" )
			)
			( pin "U2D1.AP1"
				( objectStatus "@baseboard_fab2_lib.baseboard_fab2(sch_1):page67_i132:upi0_tx_dp(12)" )
			)
			( pin "U2D1.AR2"
				( objectStatus "@baseboard_fab2_lib.baseboard_fab2(sch_1):page67_i132:upi0_tx_dp(13)" )
			)
			( pin "U2D1.AR4"
				( objectStatus "@baseboard_fab2_lib.baseboard_fab2(sch_1):page67_i132:upi0_tx_dp(14)" )
			)
			( pin "U2D1.AW4"
				( objectStatus "@baseboard_fab2_lib.baseboard_fab2(sch_1):page67_i132:upi0_tx_dp(15)" )
			)
			( pin "U2D1.AY3"
				( objectStatus "@baseboard_fab2_lib.baseboard_fab2(sch_1):page67_i132:upi0_tx_dp(16)" )
			)
			( pin "U2D1.BC2"
				( objectStatus "@baseboard_fab2_lib.baseboard_fab2(sch_1):page67_i132:upi0_tx_dp(17)" )
			)
			( pin "U2D1.BD3"
				( objectStatus "@baseboard_fab2_lib.baseboard_fab2(sch_1):page67_i132:upi0_tx_dp(18)" )
			)
			( pin "U2D1.BH3"
				( objectStatus "@baseboard_fab2_lib.baseboard_fab2(sch_1):page67_i132:upi0_tx_dp(19)" )
			)
			( pin "U2D1.T5"
				( objectStatus "@baseboard_fab2_lib.baseboard_fab2(sch_1):page68_i125:upi1_rx_dn(0)" )
			)
			( pin "U2D1.P7"
				( objectStatus "@baseboard_fab2_lib.baseboard_fab2(sch_1):page68_i125:upi1_rx_dn(1)" )
			)
			( pin "U2D1.V7"
				( objectStatus "@baseboard_fab2_lib.baseboard_fab2(sch_1):page68_i125:upi1_rx_dn(2)" )
			)
			( pin "U2D1.T9"
				( objectStatus "@baseboard_fab2_lib.baseboard_fab2(sch_1):page68_i125:upi1_rx_dn(3)" )
			)
			( pin "U2D1.P9"
				( objectStatus "@baseboard_fab2_lib.baseboard_fab2(sch_1):page68_i125:upi1_rx_dn(4)" )
			)
			( pin "U2D1.R10"
				( objectStatus "@baseboard_fab2_lib.baseboard_fab2(sch_1):page68_i125:upi1_rx_dn(5)" )
			)
			( pin "U2D1.U12"
				( objectStatus "@baseboard_fab2_lib.baseboard_fab2(sch_1):page68_i125:upi1_rx_dn(6)" )
			)
			( pin "U2D1.L12"
				( objectStatus "@baseboard_fab2_lib.baseboard_fab2(sch_1):page68_i125:upi1_rx_dn(7)" )
			)
			( pin "U2D1.N14"
				( objectStatus "@baseboard_fab2_lib.baseboard_fab2(sch_1):page68_i125:upi1_rx_dn(8)" )
			)
			( pin "U2D1.R12"
				( objectStatus "@baseboard_fab2_lib.baseboard_fab2(sch_1):page68_i125:upi1_rx_dn(9)" )
			)
			( pin "U2D1.R16"
				( objectStatus "@baseboard_fab2_lib.baseboard_fab2(sch_1):page68_i125:upi1_rx_dn(10)" )
			)
			( pin "U2D1.P17"
				( objectStatus "@baseboard_fab2_lib.baseboard_fab2(sch_1):page68_i125:upi1_rx_dn(11)" )
			)
			( pin "U2D1.U16"
				( objectStatus "@baseboard_fab2_lib.baseboard_fab2(sch_1):page68_i125:upi1_rx_dn(12)" )
			)
			( pin "U2D1.W18"
				( objectStatus "@baseboard_fab2_lib.baseboard_fab2(sch_1):page68_i125:upi1_rx_dn(13)" )
			)
			( pin "U2D1.R20"
				( objectStatus "@baseboard_fab2_lib.baseboard_fab2(sch_1):page68_i125:upi1_rx_dn(14)" )
			)
			( pin "U2D1.U18"
				( objectStatus "@baseboard_fab2_lib.baseboard_fab2(sch_1):page68_i125:upi1_rx_dn(15)" )
			)
			( pin "U2D1.P21"
				( objectStatus "@baseboard_fab2_lib.baseboard_fab2(sch_1):page68_i125:upi1_rx_dn(16)" )
			)
			( pin "U2D1.V19"
				( objectStatus "@baseboard_fab2_lib.baseboard_fab2(sch_1):page68_i125:upi1_rx_dn(17)" )
			)
			( pin "U2D1.Y21"
				( objectStatus "@baseboard_fab2_lib.baseboard_fab2(sch_1):page68_i125:upi1_rx_dn(18)" )
			)
			( pin "U2D1.AB19"
				( objectStatus "@baseboard_fab2_lib.baseboard_fab2(sch_1):page68_i125:upi1_rx_dn(19)" )
			)
			( pin "U2D1.R6"
				( objectStatus "@baseboard_fab2_lib.baseboard_fab2(sch_1):page68_i125:upi1_rx_dp(0)" )
			)
			( pin "U2D1.T7"
				( objectStatus "@baseboard_fab2_lib.baseboard_fab2(sch_1):page68_i125:upi1_rx_dp(1)" )
			)
			( pin "U2D1.U8"
				( objectStatus "@baseboard_fab2_lib.baseboard_fab2(sch_1):page68_i125:upi1_rx_dp(2)" )
			)
			( pin "U2D1.R8"
				( objectStatus "@baseboard_fab2_lib.baseboard_fab2(sch_1):page68_i125:upi1_rx_dp(3)" )
			)
			( pin "U2D1.N10"
				( objectStatus "@baseboard_fab2_lib.baseboard_fab2(sch_1):page68_i125:upi1_rx_dp(4)" )
			)
			( pin "U2D1.U10"
				( objectStatus "@baseboard_fab2_lib.baseboard_fab2(sch_1):page68_i125:upi1_rx_dp(5)" )
			)
			( pin "U2D1.T11"
				( objectStatus "@baseboard_fab2_lib.baseboard_fab2(sch_1):page68_i125:upi1_rx_dp(6)" )
			)
			( pin "U2D1.N12"
				( objectStatus "@baseboard_fab2_lib.baseboard_fab2(sch_1):page68_i125:upi1_rx_dp(7)" )
			)
			( pin "U2D1.M13"
				( objectStatus "@baseboard_fab2_lib.baseboard_fab2(sch_1):page68_i125:upi1_rx_dp(8)" )
			)
			( pin "U2D1.P13"
				( objectStatus "@baseboard_fab2_lib.baseboard_fab2(sch_1):page68_i125:upi1_rx_dp(9)" )
			)
			( pin "U2D1.T15"
				( objectStatus "@baseboard_fab2_lib.baseboard_fab2(sch_1):page68_i125:upi1_rx_dp(10)" )
			)
			( pin "U2D1.N16"
				( objectStatus "@baseboard_fab2_lib.baseboard_fab2(sch_1):page68_i125:upi1_rx_dp(11)" )
			)
			( pin "U2D1.W16"
				( objectStatus "@baseboard_fab2_lib.baseboard_fab2(sch_1):page68_i125:upi1_rx_dp(12)" )
			)
			( pin "U2D1.V17"
				( objectStatus "@baseboard_fab2_lib.baseboard_fab2(sch_1):page68_i125:upi1_rx_dp(13)" )
			)
			( pin "U2D1.P19"
				( objectStatus "@baseboard_fab2_lib.baseboard_fab2(sch_1):page68_i125:upi1_rx_dp(14)" )
			)
			( pin "U2D1.T19"
				( objectStatus "@baseboard_fab2_lib.baseboard_fab2(sch_1):page68_i125:upi1_rx_dp(15)" )
			)
			( pin "U2D1.T21"
				( objectStatus "@baseboard_fab2_lib.baseboard_fab2(sch_1):page68_i125:upi1_rx_dp(16)" )
			)
			( pin "U2D1.Y19"
				( objectStatus "@baseboard_fab2_lib.baseboard_fab2(sch_1):page68_i125:upi1_rx_dp(17)" )
			)
			( pin "U2D1.W20"
				( objectStatus "@baseboard_fab2_lib.baseboard_fab2(sch_1):page68_i125:upi1_rx_dp(18)" )
			)
			( pin "U2D1.AA20"
				( objectStatus "@baseboard_fab2_lib.baseboard_fab2(sch_1):page68_i125:upi1_rx_dp(19)" )
			)
			( pin "U2D1.M3"
				( objectStatus "@baseboard_fab2_lib.baseboard_fab2(sch_1):page68_i125:upi1_tx_dn(0)" )
			)
			( pin "U2D1.L4"
				( objectStatus "@baseboard_fab2_lib.baseboard_fab2(sch_1):page68_i125:upi1_tx_dn(1)" )
			)
			( pin "U2D1.K5"
				( objectStatus "@baseboard_fab2_lib.baseboard_fab2(sch_1):page68_i125:upi1_tx_dn(2)" )
			)
			( pin "U2D1.J6"
				( objectStatus "@baseboard_fab2_lib.baseboard_fab2(sch_1):page68_i125:upi1_tx_dn(3)" )
			)
			( pin "U2D1.G6"
				( objectStatus "@baseboard_fab2_lib.baseboard_fab2(sch_1):page68_i125:upi1_tx_dn(4)" )
			)
			( pin "U2D1.H7"
				( objectStatus "@baseboard_fab2_lib.baseboard_fab2(sch_1):page68_i125:upi1_tx_dn(5)" )
			)
			( pin "U2D1.K9"
				( objectStatus "@baseboard_fab2_lib.baseboard_fab2(sch_1):page68_i125:upi1_tx_dn(6)" )
			)
			( pin "U2D1.D9"
				( objectStatus "@baseboard_fab2_lib.baseboard_fab2(sch_1):page68_i125:upi1_tx_dn(7)" )
			)
			( pin "U2D1.F11"
				( objectStatus "@baseboard_fab2_lib.baseboard_fab2(sch_1):page68_i125:upi1_tx_dn(8)" )
			)
			( pin "U2D1.G10"
				( objectStatus "@baseboard_fab2_lib.baseboard_fab2(sch_1):page68_i125:upi1_tx_dn(9)" )
			)
			( pin "U2D1.E12"
				( objectStatus "@baseboard_fab2_lib.baseboard_fab2(sch_1):page68_i125:upi1_tx_dn(10)" )
			)
			( pin "U2D1.G14"
				( objectStatus "@baseboard_fab2_lib.baseboard_fab2(sch_1):page68_i125:upi1_tx_dn(11)" )
			)
			( pin "U2D1.D15"
				( objectStatus "@baseboard_fab2_lib.baseboard_fab2(sch_1):page68_i125:upi1_tx_dn(12)" )
			)
			( pin "U2D1.F15"
				( objectStatus "@baseboard_fab2_lib.baseboard_fab2(sch_1):page68_i125:upi1_tx_dn(13)" )
			)
			( pin "U2D1.H17"
				( objectStatus "@baseboard_fab2_lib.baseboard_fab2(sch_1):page68_i125:upi1_tx_dn(14)" )
			)
			( pin "U2D1.K19"
				( objectStatus "@baseboard_fab2_lib.baseboard_fab2(sch_1):page68_i125:upi1_tx_dn(15)" )
			)
			( pin "U2D1.G18"
				( objectStatus "@baseboard_fab2_lib.baseboard_fab2(sch_1):page68_i125:upi1_tx_dn(16)" )
			)
			( pin "U2D1.J20"
				( objectStatus "@baseboard_fab2_lib.baseboard_fab2(sch_1):page68_i125:upi1_tx_dn(17)" )
			)
			( pin "U2D1.F21"
				( objectStatus "@baseboard_fab2_lib.baseboard_fab2(sch_1):page68_i125:upi1_tx_dn(18)" )
			)
			( pin "U2D1.H21"
				( objectStatus "@baseboard_fab2_lib.baseboard_fab2(sch_1):page68_i125:upi1_tx_dn(19)" )
			)
			( pin "U2D1.P3"
				( objectStatus "@baseboard_fab2_lib.baseboard_fab2(sch_1):page68_i125:upi1_tx_dp(0)" )
			)
			( pin "U2D1.K3"
				( objectStatus "@baseboard_fab2_lib.baseboard_fab2(sch_1):page68_i125:upi1_tx_dp(1)" )
			)
			( pin "U2D1.M5"
				( objectStatus "@baseboard_fab2_lib.baseboard_fab2(sch_1):page68_i125:upi1_tx_dp(2)" )
			)
			( pin "U2D1.H5"
				( objectStatus "@baseboard_fab2_lib.baseboard_fab2(sch_1):page68_i125:upi1_tx_dp(3)" )
			)
			( pin "U2D1.F7"
				( objectStatus "@baseboard_fab2_lib.baseboard_fab2(sch_1):page68_i125:upi1_tx_dp(4)" )
			)
			( pin "U2D1.K7"
				( objectStatus "@baseboard_fab2_lib.baseboard_fab2(sch_1):page68_i125:upi1_tx_dp(5)" )
			)
			( pin "U2D1.J8"
				( objectStatus "@baseboard_fab2_lib.baseboard_fab2(sch_1):page68_i125:upi1_tx_dp(6)" )
			)
			( pin "U2D1.F9"
				( objectStatus "@baseboard_fab2_lib.baseboard_fab2(sch_1):page68_i125:upi1_tx_dp(7)" )
			)
			( pin "U2D1.E10"
				( objectStatus "@baseboard_fab2_lib.baseboard_fab2(sch_1):page68_i125:upi1_tx_dp(8)" )
			)
			( pin "U2D1.H9"
				( objectStatus "@baseboard_fab2_lib.baseboard_fab2(sch_1):page68_i125:upi1_tx_dp(9)" )
			)
			( pin "U2D1.G12"
				( objectStatus "@baseboard_fab2_lib.baseboard_fab2(sch_1):page68_i125:upi1_tx_dp(10)" )
			)
			( pin "U2D1.F13"
				( objectStatus "@baseboard_fab2_lib.baseboard_fab2(sch_1):page68_i125:upi1_tx_dp(11)" )
			)
			( pin "U2D1.E14"
				( objectStatus "@baseboard_fab2_lib.baseboard_fab2(sch_1):page68_i125:upi1_tx_dp(12)" )
			)
			( pin "U2D1.H15"
				( objectStatus "@baseboard_fab2_lib.baseboard_fab2(sch_1):page68_i125:upi1_tx_dp(13)" )
			)
			( pin "U2D1.G16"
				( objectStatus "@baseboard_fab2_lib.baseboard_fab2(sch_1):page68_i125:upi1_tx_dp(14)" )
			)
			( pin "U2D1.L18"
				( objectStatus "@baseboard_fab2_lib.baseboard_fab2(sch_1):page68_i125:upi1_tx_dp(15)" )
			)
			( pin "U2D1.J18"
				( objectStatus "@baseboard_fab2_lib.baseboard_fab2(sch_1):page68_i125:upi1_tx_dp(16)" )
			)
			( pin "U2D1.H19"
				( objectStatus "@baseboard_fab2_lib.baseboard_fab2(sch_1):page68_i125:upi1_tx_dp(17)" )
			)
			( pin "U2D1.G20"
				( objectStatus "@baseboard_fab2_lib.baseboard_fab2(sch_1):page68_i125:upi1_tx_dp(18)" )
			)
			( pin "U2D1.K21"
				( objectStatus "@baseboard_fab2_lib.baseboard_fab2(sch_1):page68_i125:upi1_tx_dp(19)" )
			)
			( pin "U2D1.DF23"
				( objectStatus "@baseboard_fab2_lib.baseboard_fab2(sch_1):page69_i1:upi2_rx_dn(0)" )
			)
			( pin "U2D1.DE22"
				( objectStatus "@baseboard_fab2_lib.baseboard_fab2(sch_1):page69_i1:upi2_rx_dn(1)" )
			)
			( pin "U2D1.DC22"
				( objectStatus "@baseboard_fab2_lib.baseboard_fab2(sch_1):page69_i1:upi2_rx_dn(2)" )
			)
			( pin "U2D1.DB21"
				( objectStatus "@baseboard_fab2_lib.baseboard_fab2(sch_1):page69_i1:upi2_rx_dn(3)" )
			)
			( pin "U2D1.DD19"
				( objectStatus "@baseboard_fab2_lib.baseboard_fab2(sch_1):page69_i1:upi2_rx_dn(4)" )
			)
			( pin "U2D1.DA20"
				( objectStatus "@baseboard_fab2_lib.baseboard_fab2(sch_1):page69_i1:upi2_rx_dn(5)" )
			)
			( pin "U2D1.CW20"
				( objectStatus "@baseboard_fab2_lib.baseboard_fab2(sch_1):page69_i1:upi2_rx_dn(6)" )
			)
			( pin "U2D1.CV19"
				( objectStatus "@baseboard_fab2_lib.baseboard_fab2(sch_1):page69_i1:upi2_rx_dn(7)" )
			)
			( pin "U2D1.CT21"
				( objectStatus "@baseboard_fab2_lib.baseboard_fab2(sch_1):page69_i1:upi2_rx_dn(8)" )
			)
			( pin "U2D1.CR18"
				( objectStatus "@baseboard_fab2_lib.baseboard_fab2(sch_1):page69_i1:upi2_rx_dn(9)" )
			)
			( pin "U2D1.CN20"
				( objectStatus "@baseboard_fab2_lib.baseboard_fab2(sch_1):page69_i1:upi2_rx_dn(10)" )
			)
			( pin "U2D1.CP21"
				( objectStatus "@baseboard_fab2_lib.baseboard_fab2(sch_1):page69_i1:upi2_rx_dn(11)" )
			)
			( pin "U2D1.CL16"
				( objectStatus "@baseboard_fab2_lib.baseboard_fab2(sch_1):page69_i1:upi2_rx_dn(12)" )
			)
			( pin "U2D1.CJ18"
				( objectStatus "@baseboard_fab2_lib.baseboard_fab2(sch_1):page69_i1:upi2_rx_dn(13)" )
			)
			( pin "U2D1.CH17"
				( objectStatus "@baseboard_fab2_lib.baseboard_fab2(sch_1):page69_i1:upi2_rx_dn(14)" )
			)
			( pin "U2D1.CE16"
				( objectStatus "@baseboard_fab2_lib.baseboard_fab2(sch_1):page69_i1:upi2_rx_dn(15)" )
			)
			( pin "U2D1.CD15"
				( objectStatus "@baseboard_fab2_lib.baseboard_fab2(sch_1):page69_i1:upi2_rx_dn(16)" )
			)
			( pin "U2D1.CF17"
				( objectStatus "@baseboard_fab2_lib.baseboard_fab2(sch_1):page69_i1:upi2_rx_dn(17)" )
			)
			( pin "U2D1.CB15"
				( objectStatus "@baseboard_fab2_lib.baseboard_fab2(sch_1):page69_i1:upi2_rx_dn(18)" )
			)
			( pin "U2D1.BY17"
				( objectStatus "@baseboard_fab2_lib.baseboard_fab2(sch_1):page69_i1:upi2_rx_dn(19)" )
			)
			( pin "U2D1.DG22"
				( objectStatus "@baseboard_fab2_lib.baseboard_fab2(sch_1):page69_i1:upi2_rx_dp(0)" )
			)
			( pin "U2D1.DD21"
				( objectStatus "@baseboard_fab2_lib.baseboard_fab2(sch_1):page69_i1:upi2_rx_dp(1)" )
			)
			( pin "U2D1.DA22"
				( objectStatus "@baseboard_fab2_lib.baseboard_fab2(sch_1):page69_i1:upi2_rx_dp(2)" )
			)
			( pin "U2D1.DC20"
				( objectStatus "@baseboard_fab2_lib.baseboard_fab2(sch_1):page69_i1:upi2_rx_dp(3)" )
			)
			( pin "U2D1.DB19"
				( objectStatus "@baseboard_fab2_lib.baseboard_fab2(sch_1):page69_i1:upi2_rx_dp(4)" )
			)
			( pin "U2D1.CY19"
				( objectStatus "@baseboard_fab2_lib.baseboard_fab2(sch_1):page69_i1:upi2_rx_dp(5)" )
			)
			( pin "U2D1.CU20"
				( objectStatus "@baseboard_fab2_lib.baseboard_fab2(sch_1):page69_i1:upi2_rx_dp(6)" )
			)
			( pin "U2D1.CW18"
				( objectStatus "@baseboard_fab2_lib.baseboard_fab2(sch_1):page69_i1:upi2_rx_dp(7)" )
			)
			( pin "U2D1.CR20"
				( objectStatus "@baseboard_fab2_lib.baseboard_fab2(sch_1):page69_i1:upi2_rx_dp(8)" )
			)
			( pin "U2D1.CN18"
				( objectStatus "@baseboard_fab2_lib.baseboard_fab2(sch_1):page69_i1:upi2_rx_dp(9)" )
			)
			( pin "U2D1.CP19"
				( objectStatus "@baseboard_fab2_lib.baseboard_fab2(sch_1):page69_i1:upi2_rx_dp(10)" )
			)
			( pin "U2D1.CM21"
				( objectStatus "@baseboard_fab2_lib.baseboard_fab2(sch_1):page69_i1:upi2_rx_dp(11)" )
			)
			( pin "U2D1.CJ16"
				( objectStatus "@baseboard_fab2_lib.baseboard_fab2(sch_1):page69_i1:upi2_rx_dp(12)" )
			)
			( pin "U2D1.CK17"
				( objectStatus "@baseboard_fab2_lib.baseboard_fab2(sch_1):page69_i1:upi2_rx_dp(13)" )
			)
			( pin "U2D1.CG16"
				( objectStatus "@baseboard_fab2_lib.baseboard_fab2(sch_1):page69_i1:upi2_rx_dp(14)" )
			)
			( pin "U2D1.CF15"
				( objectStatus "@baseboard_fab2_lib.baseboard_fab2(sch_1):page69_i1:upi2_rx_dp(15)" )
			)
			( pin "U2D1.CC14"
				( objectStatus "@baseboard_fab2_lib.baseboard_fab2(sch_1):page69_i1:upi2_rx_dp(16)" )
			)
			( pin "U2D1.CD17"
				( objectStatus "@baseboard_fab2_lib.baseboard_fab2(sch_1):page69_i1:upi2_rx_dp(17)" )
			)
			( pin "U2D1.BY15"
				( objectStatus "@baseboard_fab2_lib.baseboard_fab2(sch_1):page69_i1:upi2_rx_dp(18)" )
			)
			( pin "U2D1.CA16"
				( objectStatus "@baseboard_fab2_lib.baseboard_fab2(sch_1):page69_i1:upi2_rx_dp(19)" )
			)
			( pin "U2D1.DT21"
				( objectStatus "@baseboard_fab2_lib.baseboard_fab2(sch_1):page69_i1:upi2_tx_dn(0)" )
			)
			( pin "U2D1.DM21"
				( objectStatus "@baseboard_fab2_lib.baseboard_fab2(sch_1):page69_i1:upi2_tx_dn(1)" )
			)
			( pin "U2D1.DL20"
				( objectStatus "@baseboard_fab2_lib.baseboard_fab2(sch_1):page69_i1:upi2_tx_dn(2)" )
			)
			( pin "U2D1.DG20"
				( objectStatus "@baseboard_fab2_lib.baseboard_fab2(sch_1):page69_i1:upi2_tx_dn(3)" )
			)
			( pin "U2D1.DH19"
				( objectStatus "@baseboard_fab2_lib.baseboard_fab2(sch_1):page69_i1:upi2_tx_dn(4)" )
			)
			( pin "U2D1.DK17"
				( objectStatus "@baseboard_fab2_lib.baseboard_fab2(sch_1):page69_i1:upi2_tx_dn(5)" )
			)
			( pin "U2D1.DG18"
				( objectStatus "@baseboard_fab2_lib.baseboard_fab2(sch_1):page69_i1:upi2_tx_dn(6)" )
			)
			( pin "U2D1.DD17"
				( objectStatus "@baseboard_fab2_lib.baseboard_fab2(sch_1):page69_i1:upi2_tx_dn(7)" )
			)
			( pin "U2D1.DF15"
				( objectStatus "@baseboard_fab2_lib.baseboard_fab2(sch_1):page69_i1:upi2_tx_dn(8)" )
			)
			( pin "U2D1.DC16"
				( objectStatus "@baseboard_fab2_lib.baseboard_fab2(sch_1):page69_i1:upi2_tx_dn(9)" )
			)
			( pin "U2D1.DA16"
				( objectStatus "@baseboard_fab2_lib.baseboard_fab2(sch_1):page69_i1:upi2_tx_dn(10)" )
			)
			( pin "U2D1.CW14"
				( objectStatus "@baseboard_fab2_lib.baseboard_fab2(sch_1):page69_i1:upi2_tx_dn(11)" )
			)
			( pin "U2D1.CU14"
				( objectStatus "@baseboard_fab2_lib.baseboard_fab2(sch_1):page69_i1:upi2_tx_dn(12)" )
			)
			( pin "U2D1.CM13"
				( objectStatus "@baseboard_fab2_lib.baseboard_fab2(sch_1):page69_i1:upi2_tx_dn(13)" )
			)
			( pin "U2D1.CJ14"
				( objectStatus "@baseboard_fab2_lib.baseboard_fab2(sch_1):page69_i1:upi2_tx_dn(14)" )
			)
			( pin "U2D1.CF13"
				( objectStatus "@baseboard_fab2_lib.baseboard_fab2(sch_1):page69_i1:upi2_tx_dn(15)" )
			)
			( pin "U2D1.CH11"
				( objectStatus "@baseboard_fab2_lib.baseboard_fab2(sch_1):page69_i1:upi2_tx_dn(16)" )
			)
			( pin "U2D1.CE12"
				( objectStatus "@baseboard_fab2_lib.baseboard_fab2(sch_1):page69_i1:upi2_tx_dn(17)" )
			)
			( pin "U2D1.CC10"
				( objectStatus "@baseboard_fab2_lib.baseboard_fab2(sch_1):page69_i1:upi2_tx_dn(18)" )
			)
			( pin "U2D1.CC12"
				( objectStatus "@baseboard_fab2_lib.baseboard_fab2(sch_1):page69_i1:upi2_tx_dn(19)" )
			)
			( pin "U2D1.DP21"
				( objectStatus "@baseboard_fab2_lib.baseboard_fab2(sch_1):page69_i1:upi2_tx_dp(0)" )
			)
			( pin "U2D1.DN20"
				( objectStatus "@baseboard_fab2_lib.baseboard_fab2(sch_1):page69_i1:upi2_tx_dp(1)" )
			)
			( pin "U2D1.DK19"
				( objectStatus "@baseboard_fab2_lib.baseboard_fab2(sch_1):page69_i1:upi2_tx_dp(2)" )
			)
			( pin "U2D1.DJ20"
				( objectStatus "@baseboard_fab2_lib.baseboard_fab2(sch_1):page69_i1:upi2_tx_dp(3)" )
			)
			( pin "U2D1.DJ18"
				( objectStatus "@baseboard_fab2_lib.baseboard_fab2(sch_1):page69_i1:upi2_tx_dp(4)" )
			)
			( pin "U2D1.DH17"
				( objectStatus "@baseboard_fab2_lib.baseboard_fab2(sch_1):page69_i1:upi2_tx_dp(5)" )
			)
			( pin "U2D1.DF17"
				( objectStatus "@baseboard_fab2_lib.baseboard_fab2(sch_1):page69_i1:upi2_tx_dp(6)" )
			)
			( pin "U2D1.DE16"
				( objectStatus "@baseboard_fab2_lib.baseboard_fab2(sch_1):page69_i1:upi2_tx_dp(7)" )
			)
			( pin "U2D1.DD15"
				( objectStatus "@baseboard_fab2_lib.baseboard_fab2(sch_1):page69_i1:upi2_tx_dp(8)" )
			)
			( pin "U2D1.DB15"
				( objectStatus "@baseboard_fab2_lib.baseboard_fab2(sch_1):page69_i1:upi2_tx_dp(9)" )
			)
			( pin "U2D1.CW16"
				( objectStatus "@baseboard_fab2_lib.baseboard_fab2(sch_1):page69_i1:upi2_tx_dp(10)" )
			)
			( pin "U2D1.CV13"
				( objectStatus "@baseboard_fab2_lib.baseboard_fab2(sch_1):page69_i1:upi2_tx_dp(11)" )
			)
			( pin "U2D1.CR14"
				( objectStatus "@baseboard_fab2_lib.baseboard_fab2(sch_1):page69_i1:upi2_tx_dp(12)" )
			)
			( pin "U2D1.CK13"
				( objectStatus "@baseboard_fab2_lib.baseboard_fab2(sch_1):page69_i1:upi2_tx_dp(13)" )
			)
			( pin "U2D1.CH13"
				( objectStatus "@baseboard_fab2_lib.baseboard_fab2(sch_1):page69_i1:upi2_tx_dp(14)" )
			)
			( pin "U2D1.CG12"
				( objectStatus "@baseboard_fab2_lib.baseboard_fab2(sch_1):page69_i1:upi2_tx_dp(15)" )
			)
			( pin "U2D1.CF11"
				( objectStatus "@baseboard_fab2_lib.baseboard_fab2(sch_1):page69_i1:upi2_tx_dp(16)" )
			)
			( pin "U2D1.CD11"
				( objectStatus "@baseboard_fab2_lib.baseboard_fab2(sch_1):page69_i1:upi2_tx_dp(17)" )
			)
			( pin "U2D1.CB11"
				( objectStatus "@baseboard_fab2_lib.baseboard_fab2(sch_1):page69_i1:upi2_tx_dp(18)" )
			)
			( pin "U2D1.CA12"
				( objectStatus "@baseboard_fab2_lib.baseboard_fab2(sch_1):page69_i1:upi2_tx_dp(19)" )
			)
			( pin "U2D1.CH23"
				( objectStatus "@baseboard_fab2_lib.baseboard_fab2(sch_1):page70_i9:rsvd(92)" )
			)
			( pin "U2D1.CH21"
				( objectStatus "@baseboard_fab2_lib.baseboard_fab2(sch_1):page70_i9:rsvd(93)" )
			)
			( pin "U2D1.CG82"
				( objectStatus "@baseboard_fab2_lib.baseboard_fab2(sch_1):page70_i9:rsvd(94)" )
			)
			( pin "U2D1.CG78"
				( objectStatus "@baseboard_fab2_lib.baseboard_fab2(sch_1):page70_i9:rsvd(95)" )
			)
			( pin "U2D1.CG26"
				( objectStatus "@baseboard_fab2_lib.baseboard_fab2(sch_1):page70_i9:rsvd(96)" )
			)
			( pin "U2D1.CG24"
				( objectStatus "@baseboard_fab2_lib.baseboard_fab2(sch_1):page70_i9:rsvd(97)" )
			)
			( pin "U2D1.CG20"
				( objectStatus "@baseboard_fab2_lib.baseboard_fab2(sch_1):page70_i9:rsvd(98)" )
			)
			( pin "U2D1.CG10"
				( objectStatus "@baseboard_fab2_lib.baseboard_fab2(sch_1):page70_i9:rsvd(99)" )
			)
			( pin "U2D1.CF81"
				( objectStatus "@baseboard_fab2_lib.baseboard_fab2(sch_1):page70_i9:rsvd(100)" )
			)
			( pin "U2D1.CF79"
				( objectStatus "@baseboard_fab2_lib.baseboard_fab2(sch_1):page70_i9:rsvd(101)" )
			)
			( pin "U2D1.CF23"
				( objectStatus "@baseboard_fab2_lib.baseboard_fab2(sch_1):page70_i9:rsvd(102)" )
			)
			( pin "U2D1.CF21"
				( objectStatus "@baseboard_fab2_lib.baseboard_fab2(sch_1):page70_i9:rsvd(103)" )
			)
			( pin "U2D1.CF19"
				( objectStatus "@baseboard_fab2_lib.baseboard_fab2(sch_1):page70_i9:rsvd(104)" )
			)
			( pin "U2D1.CE80"
				( objectStatus "@baseboard_fab2_lib.baseboard_fab2(sch_1):page70_i9:rsvd(105)" )
			)
			( pin "U2D1.CE78"
				( objectStatus "@baseboard_fab2_lib.baseboard_fab2(sch_1):page70_i9:rsvd(106)" )
			)
			( pin "U2D1.CE22"
				( objectStatus "@baseboard_fab2_lib.baseboard_fab2(sch_1):page70_i9:rsvd(107)" )
			)
			( pin "U2D1.CD25"
				( objectStatus "@baseboard_fab2_lib.baseboard_fab2(sch_1):page70_i9:rsvd(108)" )
			)
			( pin "U2D1.CD21"
				( objectStatus "@baseboard_fab2_lib.baseboard_fab2(sch_1):page70_i9:rsvd(109)" )
			)
			( pin "U2D1.CD19"
				( objectStatus "@baseboard_fab2_lib.baseboard_fab2(sch_1):page70_i9:rsvd(110)" )
			)
			( pin "U2D1.CC6"
				( objectStatus "@baseboard_fab2_lib.baseboard_fab2(sch_1):page70_i9:rsvd(111)" )
			)
			( pin "U2D1.CC20"
				( objectStatus "@baseboard_fab2_lib.baseboard_fab2(sch_1):page70_i9:rsvd(112)" )
			)
			( pin "U2D1.CB5"
				( objectStatus "@baseboard_fab2_lib.baseboard_fab2(sch_1):page70_i9:rsvd(113)" )
			)
			( pin "U2D1.CB25"
				( objectStatus "@baseboard_fab2_lib.baseboard_fab2(sch_1):page70_i9:rsvd(114)" )
			)
			( pin "U2D1.CB21"
				( objectStatus "@baseboard_fab2_lib.baseboard_fab2(sch_1):page70_i9:rsvd(115)" )
			)
			( pin "U2D1.CB19"
				( objectStatus "@baseboard_fab2_lib.baseboard_fab2(sch_1):page70_i9:rsvd(116)" )
			)
			( pin "U2D1.CA24"
				( objectStatus "@baseboard_fab2_lib.baseboard_fab2(sch_1):page70_i9:rsvd(117)" )
			)
			( pin "U2D1.CA22"
				( objectStatus "@baseboard_fab2_lib.baseboard_fab2(sch_1):page70_i9:rsvd(118)" )
			)
			( pin "U2D1.BY25"
				( objectStatus "@baseboard_fab2_lib.baseboard_fab2(sch_1):page70_i9:rsvd(119)" )
			)
			( pin "U2D1.BY19"
				( objectStatus "@baseboard_fab2_lib.baseboard_fab2(sch_1):page70_i9:rsvd(120)" )
			)
			( pin "U2D1.BW22"
				( objectStatus "@baseboard_fab2_lib.baseboard_fab2(sch_1):page70_i9:rsvd(121)" )
			)
			( pin "U2D1.BW20"
				( objectStatus "@baseboard_fab2_lib.baseboard_fab2(sch_1):page70_i9:rsvd(122)" )
			)
			( pin "U2D1.BW10"
				( objectStatus "@baseboard_fab2_lib.baseboard_fab2(sch_1):page70_i9:rsvd(123)" )
			)
			( pin "U2D1.BV23"
				( objectStatus "@baseboard_fab2_lib.baseboard_fab2(sch_1):page70_i9:rsvd(124)" )
			)
			( pin "U2D1.BV21"
				( objectStatus "@baseboard_fab2_lib.baseboard_fab2(sch_1):page70_i9:rsvd(125)" )
			)
			( pin "U2D1.BV19"
				( objectStatus "@baseboard_fab2_lib.baseboard_fab2(sch_1):page70_i9:rsvd(126)" )
			)
			( pin "U2D1.BU22"
				( objectStatus "@baseboard_fab2_lib.baseboard_fab2(sch_1):page70_i9:rsvd(127)" )
			)
			( pin "U2D1.BU20"
				( objectStatus "@baseboard_fab2_lib.baseboard_fab2(sch_1):page70_i9:rsvd(128)" )
			)
			( pin "U2D1.BU18"
				( objectStatus "@baseboard_fab2_lib.baseboard_fab2(sch_1):page70_i9:rsvd(129)" )
			)
			( pin "U2D1.BR24"
				( objectStatus "@baseboard_fab2_lib.baseboard_fab2(sch_1):page70_i9:rsvd(130)" )
			)
			( pin "U2D1.BR22"
				( objectStatus "@baseboard_fab2_lib.baseboard_fab2(sch_1):page70_i9:rsvd(131)" )
			)
			( pin "U2D1.BP21"
				( objectStatus "@baseboard_fab2_lib.baseboard_fab2(sch_1):page70_i9:rsvd(132)" )
			)
			( pin "U2D1.BP17"
				( objectStatus "@baseboard_fab2_lib.baseboard_fab2(sch_1):page70_i9:rsvd(133)" )
			)
			( pin "U2D1.BN18"
				( objectStatus "@baseboard_fab2_lib.baseboard_fab2(sch_1):page70_i9:rsvd(134)" )
			)
			( pin "U2D1.BM19"
				( objectStatus "@baseboard_fab2_lib.baseboard_fab2(sch_1):page70_i9:rsvd(135)" )
			)
			( pin "U2D1.BM17"
				( objectStatus "@baseboard_fab2_lib.baseboard_fab2(sch_1):page70_i9:rsvd(136)" )
			)
			( pin "U2D1.BL20"
				( objectStatus "@baseboard_fab2_lib.baseboard_fab2(sch_1):page70_i9:rsvd(137)" )
			)
			( pin "U2D1.BL18"
				( objectStatus "@baseboard_fab2_lib.baseboard_fab2(sch_1):page70_i9:rsvd(138)" )
			)
			( pin "U2D1.BK17"
				( objectStatus "@baseboard_fab2_lib.baseboard_fab2(sch_1):page70_i9:rsvd(139)" )
			)
			( pin "U2D1.BJ20"
				( objectStatus "@baseboard_fab2_lib.baseboard_fab2(sch_1):page70_i9:rsvd(140)" )
			)
			( pin "U2D1.BJ18"
				( objectStatus "@baseboard_fab2_lib.baseboard_fab2(sch_1):page70_i9:rsvd(141)" )
			)
			( pin "U2D1.BJ16"
				( objectStatus "@baseboard_fab2_lib.baseboard_fab2(sch_1):page70_i9:rsvd(142)" )
			)
			( pin "U2D1.BH19"
				( objectStatus "@baseboard_fab2_lib.baseboard_fab2(sch_1):page70_i9:rsvd(143)" )
			)
			( pin "U2D1.BG20"
				( objectStatus "@baseboard_fab2_lib.baseboard_fab2(sch_1):page70_i9:rsvd(144)" )
			)
			( pin "U2D1.BG18"
				( objectStatus "@baseboard_fab2_lib.baseboard_fab2(sch_1):page70_i9:rsvd(145)" )
			)
			( pin "U2D1.BF21"
				( objectStatus "@baseboard_fab2_lib.baseboard_fab2(sch_1):page70_i9:rsvd(146)" )
			)
			( pin "U2D1.BE22"
				( objectStatus "@baseboard_fab2_lib.baseboard_fab2(sch_1):page70_i9:rsvd(147)" )
			)
			( pin "U2D1.BE20"
				( objectStatus "@baseboard_fab2_lib.baseboard_fab2(sch_1):page70_i9:rsvd(148)" )
			)
			( pin "U2D1.BE18"
				( objectStatus "@baseboard_fab2_lib.baseboard_fab2(sch_1):page70_i9:rsvd(149)" )
			)
			( pin "U2D1.BD69"
				( objectStatus "@baseboard_fab2_lib.baseboard_fab2(sch_1):page70_i9:rsvd(150)" )
			)
			( pin "U2D1.BD67"
				( objectStatus "@baseboard_fab2_lib.baseboard_fab2(sch_1):page70_i9:rsvd(151)" )
			)
			( pin "U2D1.BD65"
				( objectStatus "@baseboard_fab2_lib.baseboard_fab2(sch_1):page70_i9:rsvd(152)" )
			)
			( pin "U2D1.BD25"
				( objectStatus "@baseboard_fab2_lib.baseboard_fab2(sch_1):page70_i9:rsvd(153)" )
			)
			( pin "U2D1.BD19"
				( objectStatus "@baseboard_fab2_lib.baseboard_fab2(sch_1):page70_i9:rsvd(154)" )
			)
			( pin "U2D1.BD17"
				( objectStatus "@baseboard_fab2_lib.baseboard_fab2(sch_1):page70_i9:rsvd(155)" )
			)
			( pin "U2D1.BC68"
				( objectStatus "@baseboard_fab2_lib.baseboard_fab2(sch_1):page70_i9:rsvd(156)" )
			)
			( pin "U2D1.BC66"
				( objectStatus "@baseboard_fab2_lib.baseboard_fab2(sch_1):page70_i9:rsvd(157)" )
			)
			( pin "U2D1.BC64"
				( objectStatus "@baseboard_fab2_lib.baseboard_fab2(sch_1):page70_i9:rsvd(158)" )
			)
			( pin "U2D1.BC22"
				( objectStatus "@baseboard_fab2_lib.baseboard_fab2(sch_1):page70_i9:rsvd(159)" )
			)
			( pin "U2D1.BC20"
				( objectStatus "@baseboard_fab2_lib.baseboard_fab2(sch_1):page70_i9:rsvd(160)" )
			)
			( pin "U2D1.BC18"
				( objectStatus "@baseboard_fab2_lib.baseboard_fab2(sch_1):page70_i9:rsvd(161)" )
			)
			( pin "U2D1.BC14"
				( objectStatus "@baseboard_fab2_lib.baseboard_fab2(sch_1):page70_i9:rsvd(162)" )
			)
			( pin "U2D1.BB67"
				( objectStatus "@baseboard_fab2_lib.baseboard_fab2(sch_1):page70_i9:rsvd(163)" )
			)
			( pin "U2D1.BB65"
				( objectStatus "@baseboard_fab2_lib.baseboard_fab2(sch_1):page70_i9:rsvd(164)" )
			)
			( pin "U2D1.BB25"
				( objectStatus "@baseboard_fab2_lib.baseboard_fab2(sch_1):page70_i9:rsvd(165)" )
			)
			( pin "U2D1.BB21"
				( objectStatus "@baseboard_fab2_lib.baseboard_fab2(sch_1):page70_i9:rsvd(166)" )
			)
			( pin "U2D1.BB17"
				( objectStatus "@baseboard_fab2_lib.baseboard_fab2(sch_1):page70_i9:rsvd(167)" )
			)
			( pin "U2D1.BB15"
				( objectStatus "@baseboard_fab2_lib.baseboard_fab2(sch_1):page70_i9:rsvd(168)" )
			)
			( pin "U2D1.BB13"
				( objectStatus "@baseboard_fab2_lib.baseboard_fab2(sch_1):page70_i9:rsvd(169)" )
			)
			( pin "U2D1.BA82"
				( objectStatus "@baseboard_fab2_lib.baseboard_fab2(sch_1):page70_i9:rsvd(170)" )
			)
			( pin "U2D1.BA78"
				( objectStatus "@baseboard_fab2_lib.baseboard_fab2(sch_1):page70_i9:rsvd(171)" )
			)
			( pin "U2D1.AY83"
				( objectStatus "@baseboard_fab2_lib.baseboard_fab2(sch_1):page70_i9:rsvd(255)" )
			)
			( pin "U2D1.CL24"
				( objectStatus "@baseboard_fab2_lib.baseboard_fab2(sch_1):page70_i10:rsvd(81)" )
			)
			( pin "U2D1.CK77"
				( objectStatus "@baseboard_fab2_lib.baseboard_fab2(sch_1):page70_i10:rsvd(82)" )
			)
			( pin "U2D1.CK25"
				( objectStatus "@baseboard_fab2_lib.baseboard_fab2(sch_1):page70_i10:rsvd(83)" )
			)
			( pin "U2D1.CK23"
				( objectStatus "@baseboard_fab2_lib.baseboard_fab2(sch_1):page70_i10:rsvd(84)" )
			)
			( pin "U2D1.CK19"
				( objectStatus "@baseboard_fab2_lib.baseboard_fab2(sch_1):page70_i10:rsvd(85)" )
			)
			( pin "U2D1.CJ26"
				( objectStatus "@baseboard_fab2_lib.baseboard_fab2(sch_1):page70_i10:rsvd(86)" )
			)
			( pin "U2D1.CJ24"
				( objectStatus "@baseboard_fab2_lib.baseboard_fab2(sch_1):page70_i10:rsvd(87)" )
			)
			( pin "U2D1.CJ22"
				( objectStatus "@baseboard_fab2_lib.baseboard_fab2(sch_1):page70_i10:rsvd(88)" )
			)
			( pin "U2D1.CJ20"
				( objectStatus "@baseboard_fab2_lib.baseboard_fab2(sch_1):page70_i10:rsvd(89)" )
			)
			( pin "U2D1.CH77"
				( objectStatus "@baseboard_fab2_lib.baseboard_fab2(sch_1):page70_i10:rsvd(90)" )
			)
			( pin "U2D1.CH25"
				( objectStatus "@baseboard_fab2_lib.baseboard_fab2(sch_1):page70_i10:rsvd(91)" )
			)
			( pin "U2D1.AR16"
				( objectStatus "@baseboard_fab2_lib.baseboard_fab2(sch_1):page70_i10:test_6" )
			)
			( pin "U2D1.AU18"
				( objectStatus "@baseboard_fab2_lib.baseboard_fab2(sch_1):page70_i10:test_7" )
			)
			( pin "U2D1.AW16"
				( objectStatus "@baseboard_fab2_lib.baseboard_fab2(sch_1):page70_i10:test_8" )
			)
			( pin "U2D1.AW20"
				( objectStatus "@baseboard_fab2_lib.baseboard_fab2(sch_1):page70_i10:test_9" )
			)
			( pin "U2D1.AW22"
				( objectStatus "@baseboard_fab2_lib.baseboard_fab2(sch_1):page70_i10:test_10" )
			)
			( pin "R3D27.1"
				( objectStatus "@baseboard_fab2_lib.baseboard_fab2(sch_1):page71_i43:a" )
			)
			( pin "R3D27.2"
				( objectStatus "@baseboard_fab2_lib.baseboard_fab2(sch_1):page71_i43:b" )
			)
			( pin "RT8P1.1"
				( objectStatus "@baseboard_fab2_lib.baseboard_fab2(sch_1):page71_i49:a" )
			)
			( pin "RT8P1.2"
				( objectStatus "@baseboard_fab2_lib.baseboard_fab2(sch_1):page71_i49:b" )
			)
			( pin "U2D1.BN78"
				( objectStatus "@baseboard_fab2_lib.baseboard_fab2(sch_1):page71_i50:vccin(130)" )
			)
			( pin "U2D1.BN76"
				( objectStatus "@baseboard_fab2_lib.baseboard_fab2(sch_1):page71_i50:vccin(131)" )
			)
			( pin "U2D1.BN74"
				( objectStatus "@baseboard_fab2_lib.baseboard_fab2(sch_1):page71_i50:vccin(132)" )
			)
			( pin "U2D1.BN72"
				( objectStatus "@baseboard_fab2_lib.baseboard_fab2(sch_1):page71_i50:vccin(133)" )
			)
			( pin "U2D1.BN70"
				( objectStatus "@baseboard_fab2_lib.baseboard_fab2(sch_1):page71_i50:vccin(134)" )
			)
			( pin "U2D1.BN68"
				( objectStatus "@baseboard_fab2_lib.baseboard_fab2(sch_1):page71_i50:vccin(135)" )
			)
			( pin "U2D1.BN66"
				( objectStatus "@baseboard_fab2_lib.baseboard_fab2(sch_1):page71_i50:vccin(136)" )
			)
			( pin "U2D1.BN64"
				( objectStatus "@baseboard_fab2_lib.baseboard_fab2(sch_1):page71_i50:vccin(137)" )
			)
			( pin "U2D1.BN62"
				( objectStatus "@baseboard_fab2_lib.baseboard_fab2(sch_1):page71_i50:vccin(138)" )
			)
			( pin "U2D1.BN60"
				( objectStatus "@baseboard_fab2_lib.baseboard_fab2(sch_1):page71_i50:vccin(139)" )
			)
			( pin "U2D1.BM83"
				( objectStatus "@baseboard_fab2_lib.baseboard_fab2(sch_1):page71_i50:vccin(140)" )
			)
			( pin "U2D1.BM81"
				( objectStatus "@baseboard_fab2_lib.baseboard_fab2(sch_1):page71_i50:vccin(141)" )
			)
			( pin "U2D1.BM79"
				( objectStatus "@baseboard_fab2_lib.baseboard_fab2(sch_1):page71_i50:vccin(142)" )
			)
			( pin "U2D1.BM77"
				( objectStatus "@baseboard_fab2_lib.baseboard_fab2(sch_1):page71_i50:vccin(143)" )
			)
			( pin "U2D1.BM75"
				( objectStatus "@baseboard_fab2_lib.baseboard_fab2(sch_1):page71_i50:vccin(144)" )
			)
			( pin "U2D1.BM73"
				( objectStatus "@baseboard_fab2_lib.baseboard_fab2(sch_1):page71_i50:vccin(145)" )
			)
			( pin "U2D1.BM71"
				( objectStatus "@baseboard_fab2_lib.baseboard_fab2(sch_1):page71_i50:vccin(146)" )
			)
			( pin "U2D1.BM69"
				( objectStatus "@baseboard_fab2_lib.baseboard_fab2(sch_1):page71_i50:vccin(147)" )
			)
			( pin "U2D1.BM67"
				( objectStatus "@baseboard_fab2_lib.baseboard_fab2(sch_1):page71_i50:vccin(148)" )
			)
			( pin "U2D1.BM65"
				( objectStatus "@baseboard_fab2_lib.baseboard_fab2(sch_1):page71_i50:vccin(149)" )
			)
			( pin "U2D1.BM63"
				( objectStatus "@baseboard_fab2_lib.baseboard_fab2(sch_1):page71_i50:vccin(150)" )
			)
			( pin "U2D1.BM61"
				( objectStatus "@baseboard_fab2_lib.baseboard_fab2(sch_1):page71_i50:vccin(151)" )
			)
			( pin "U2D1.BL84"
				( objectStatus "@baseboard_fab2_lib.baseboard_fab2(sch_1):page71_i50:vccin(152)" )
			)
			( pin "U2D1.BL62"
				( objectStatus "@baseboard_fab2_lib.baseboard_fab2(sch_1):page71_i50:vccin(153)" )
			)
			( pin "U2D1.BL60"
				( objectStatus "@baseboard_fab2_lib.baseboard_fab2(sch_1):page71_i50:vccin(154)" )
			)
			( pin "U2D1.BK83"
				( objectStatus "@baseboard_fab2_lib.baseboard_fab2(sch_1):page71_i50:vccin(155)" )
			)
			( pin "U2D1.BK81"
				( objectStatus "@baseboard_fab2_lib.baseboard_fab2(sch_1):page71_i50:vccin(156)" )
			)
			( pin "U2D1.BK79"
				( objectStatus "@baseboard_fab2_lib.baseboard_fab2(sch_1):page71_i50:vccin(157)" )
			)
			( pin "U2D1.BK77"
				( objectStatus "@baseboard_fab2_lib.baseboard_fab2(sch_1):page71_i50:vccin(158)" )
			)
			( pin "U2D1.BK75"
				( objectStatus "@baseboard_fab2_lib.baseboard_fab2(sch_1):page71_i50:vccin(159)" )
			)
			( pin "U2D1.BK73"
				( objectStatus "@baseboard_fab2_lib.baseboard_fab2(sch_1):page71_i50:vccin(160)" )
			)
			( pin "U2D1.BK71"
				( objectStatus "@baseboard_fab2_lib.baseboard_fab2(sch_1):page71_i50:vccin(161)" )
			)
			( pin "U2D1.BK69"
				( objectStatus "@baseboard_fab2_lib.baseboard_fab2(sch_1):page71_i50:vccin(162)" )
			)
			( pin "U2D1.BK67"
				( objectStatus "@baseboard_fab2_lib.baseboard_fab2(sch_1):page71_i50:vccin(163)" )
			)
			( pin "U2D1.BK65"
				( objectStatus "@baseboard_fab2_lib.baseboard_fab2(sch_1):page71_i50:vccin(164)" )
			)
			( pin "U2D1.BK63"
				( objectStatus "@baseboard_fab2_lib.baseboard_fab2(sch_1):page71_i50:vccin(165)" )
			)
			( pin "U2D1.BK61"
				( objectStatus "@baseboard_fab2_lib.baseboard_fab2(sch_1):page71_i50:vccin(166)" )
			)
			( pin "U2D1.BJ84"
				( objectStatus "@baseboard_fab2_lib.baseboard_fab2(sch_1):page71_i50:vccin(167)" )
			)
			( pin "U2D1.BJ82"
				( objectStatus "@baseboard_fab2_lib.baseboard_fab2(sch_1):page71_i50:vccin(168)" )
			)
			( pin "U2D1.BJ80"
				( objectStatus "@baseboard_fab2_lib.baseboard_fab2(sch_1):page71_i50:vccin(169)" )
			)
			( pin "U2D1.BJ78"
				( objectStatus "@baseboard_fab2_lib.baseboard_fab2(sch_1):page71_i50:vccin(170)" )
			)
			( pin "U2D1.BJ76"
				( objectStatus "@baseboard_fab2_lib.baseboard_fab2(sch_1):page71_i50:vccin(171)" )
			)
			( pin "U2D1.BJ74"
				( objectStatus "@baseboard_fab2_lib.baseboard_fab2(sch_1):page71_i50:vccin(172)" )
			)
			( pin "U2D1.BJ72"
				( objectStatus "@baseboard_fab2_lib.baseboard_fab2(sch_1):page71_i50:vccin(173)" )
			)
			( pin "U2D1.BJ70"
				( objectStatus "@baseboard_fab2_lib.baseboard_fab2(sch_1):page71_i50:vccin(174)" )
			)
			( pin "U2D1.BJ68"
				( objectStatus "@baseboard_fab2_lib.baseboard_fab2(sch_1):page71_i50:vccin(175)" )
			)
			( pin "U2D1.BJ66"
				( objectStatus "@baseboard_fab2_lib.baseboard_fab2(sch_1):page71_i50:vccin(176)" )
			)
			( pin "U2D1.BJ64"
				( objectStatus "@baseboard_fab2_lib.baseboard_fab2(sch_1):page71_i50:vccin(177)" )
			)
			( pin "U2D1.BJ62"
				( objectStatus "@baseboard_fab2_lib.baseboard_fab2(sch_1):page71_i50:vccin(178)" )
			)
			( pin "U2D1.BJ60"
				( objectStatus "@baseboard_fab2_lib.baseboard_fab2(sch_1):page71_i50:vccin(179)" )
			)
			( pin "U2D1.BH83"
				( objectStatus "@baseboard_fab2_lib.baseboard_fab2(sch_1):page71_i50:vccin(180)" )
			)
			( pin "U2D1.BH81"
				( objectStatus "@baseboard_fab2_lib.baseboard_fab2(sch_1):page71_i50:vccin(181)" )
			)
			( pin "U2D1.BH79"
				( objectStatus "@baseboard_fab2_lib.baseboard_fab2(sch_1):page71_i50:vccin(182)" )
			)
			( pin "U2D1.BH77"
				( objectStatus "@baseboard_fab2_lib.baseboard_fab2(sch_1):page71_i50:vccin(183)" )
			)
			( pin "U2D1.BH75"
				( objectStatus "@baseboard_fab2_lib.baseboard_fab2(sch_1):page71_i50:vccin(184)" )
			)
			( pin "U2D1.BH73"
				( objectStatus "@baseboard_fab2_lib.baseboard_fab2(sch_1):page71_i50:vccin(185)" )
			)
			( pin "U2D1.BH71"
				( objectStatus "@baseboard_fab2_lib.baseboard_fab2(sch_1):page71_i50:vccin(186)" )
			)
			( pin "U2D1.BH69"
				( objectStatus "@baseboard_fab2_lib.baseboard_fab2(sch_1):page71_i50:vccin(187)" )
			)
			( pin "U2D1.BH67"
				( objectStatus "@baseboard_fab2_lib.baseboard_fab2(sch_1):page71_i50:vccin(188)" )
			)
			( pin "U2D1.BH65"
				( objectStatus "@baseboard_fab2_lib.baseboard_fab2(sch_1):page71_i50:vccin(189)" )
			)
			( pin "U2D1.BH63"
				( objectStatus "@baseboard_fab2_lib.baseboard_fab2(sch_1):page71_i50:vccin(190)" )
			)
			( pin "U2D1.BH61"
				( objectStatus "@baseboard_fab2_lib.baseboard_fab2(sch_1):page71_i50:vccin(191)" )
			)
			( pin "U2D1.BG84"
				( objectStatus "@baseboard_fab2_lib.baseboard_fab2(sch_1):page71_i50:vccin(192)" )
			)
			( pin "U2D1.BG70"
				( objectStatus "@baseboard_fab2_lib.baseboard_fab2(sch_1):page71_i50:vccin(193)" )
			)
			( pin "U2D1.BG68"
				( objectStatus "@baseboard_fab2_lib.baseboard_fab2(sch_1):page71_i50:vccin(194)" )
			)
			( pin "U2D1.BG66"
				( objectStatus "@baseboard_fab2_lib.baseboard_fab2(sch_1):page71_i50:vccin(195)" )
			)
			( pin "U2D1.BG64"
				( objectStatus "@baseboard_fab2_lib.baseboard_fab2(sch_1):page71_i50:vccin(196)" )
			)
			( pin "U2D1.BG62"
				( objectStatus "@baseboard_fab2_lib.baseboard_fab2(sch_1):page71_i50:vccin(197)" )
			)
			( pin "U2D1.BG60"
				( objectStatus "@baseboard_fab2_lib.baseboard_fab2(sch_1):page71_i50:vccin(198)" )
			)
			( pin "U2D1.BF85"
				( objectStatus "@baseboard_fab2_lib.baseboard_fab2(sch_1):page71_i50:vccin(199)" )
			)
			( pin "U2D1.BF83"
				( objectStatus "@baseboard_fab2_lib.baseboard_fab2(sch_1):page71_i50:vccin(200)" )
			)
			( pin "U2D1.BF81"
				( objectStatus "@baseboard_fab2_lib.baseboard_fab2(sch_1):page71_i50:vccin(201)" )
			)
			( pin "U2D1.BF79"
				( objectStatus "@baseboard_fab2_lib.baseboard_fab2(sch_1):page71_i50:vccin(202)" )
			)
			( pin "U2D1.BF77"
				( objectStatus "@baseboard_fab2_lib.baseboard_fab2(sch_1):page71_i50:vccin(203)" )
			)
			( pin "U2D1.BF75"
				( objectStatus "@baseboard_fab2_lib.baseboard_fab2(sch_1):page71_i50:vccin(204)" )
			)
			( pin "U2D1.BF73"
				( objectStatus "@baseboard_fab2_lib.baseboard_fab2(sch_1):page71_i50:vccin(205)" )
			)
			( pin "U2D1.BF61"
				( objectStatus "@baseboard_fab2_lib.baseboard_fab2(sch_1):page71_i50:vccin(206)" )
			)
			( pin "U2D1.BE84"
				( objectStatus "@baseboard_fab2_lib.baseboard_fab2(sch_1):page71_i50:vccin(207)" )
			)
			( pin "U2D1.BE82"
				( objectStatus "@baseboard_fab2_lib.baseboard_fab2(sch_1):page71_i50:vccin(208)" )
			)
			( pin "U2D1.BE80"
				( objectStatus "@baseboard_fab2_lib.baseboard_fab2(sch_1):page71_i50:vccin(209)" )
			)
			( pin "U2D1.BE78"
				( objectStatus "@baseboard_fab2_lib.baseboard_fab2(sch_1):page71_i50:vccin(210)" )
			)
			( pin "U2D1.BE76"
				( objectStatus "@baseboard_fab2_lib.baseboard_fab2(sch_1):page71_i50:vccin(211)" )
			)
			( pin "U2D1.BE74"
				( objectStatus "@baseboard_fab2_lib.baseboard_fab2(sch_1):page71_i50:vccin(212)" )
			)
			( pin "U2D1.BE72"
				( objectStatus "@baseboard_fab2_lib.baseboard_fab2(sch_1):page71_i50:vccin(213)" )
			)
			( pin "U2D1.BE62"
				( objectStatus "@baseboard_fab2_lib.baseboard_fab2(sch_1):page71_i50:vccin(214)" )
			)
			( pin "U2D1.BE60"
				( objectStatus "@baseboard_fab2_lib.baseboard_fab2(sch_1):page71_i50:vccin(215)" )
			)
			( pin "U2D1.BD85"
				( objectStatus "@baseboard_fab2_lib.baseboard_fab2(sch_1):page71_i50:vccin(216)" )
			)
			( pin "U2D1.BD83"
				( objectStatus "@baseboard_fab2_lib.baseboard_fab2(sch_1):page71_i50:vccin(217)" )
			)
			( pin "U2D1.BD81"
				( objectStatus "@baseboard_fab2_lib.baseboard_fab2(sch_1):page71_i50:vccin(218)" )
			)
			( pin "U2D1.BD79"
				( objectStatus "@baseboard_fab2_lib.baseboard_fab2(sch_1):page71_i50:vccin(219)" )
			)
			( pin "U2D1.BD77"
				( objectStatus "@baseboard_fab2_lib.baseboard_fab2(sch_1):page71_i50:vccin(220)" )
			)
			( pin "U2D1.BD75"
				( objectStatus "@baseboard_fab2_lib.baseboard_fab2(sch_1):page71_i50:vccin(221)" )
			)
			( pin "U2D1.BD73"
				( objectStatus "@baseboard_fab2_lib.baseboard_fab2(sch_1):page71_i50:vccin(222)" )
			)
			( pin "U2D1.BD61"
				( objectStatus "@baseboard_fab2_lib.baseboard_fab2(sch_1):page71_i50:vccin(223)" )
			)
			( pin "U2D1.BC84"
				( objectStatus "@baseboard_fab2_lib.baseboard_fab2(sch_1):page71_i50:vccin(224)" )
			)
			( pin "U2D1.BC62"
				( objectStatus "@baseboard_fab2_lib.baseboard_fab2(sch_1):page71_i50:vccin(225)" )
			)
			( pin "U2D1.BC60"
				( objectStatus "@baseboard_fab2_lib.baseboard_fab2(sch_1):page71_i50:vccin(226)" )
			)
			( pin "U2D1.BB85"
				( objectStatus "@baseboard_fab2_lib.baseboard_fab2(sch_1):page71_i50:vccin(227)" )
			)
			( pin "U2D1.BB61"
				( objectStatus "@baseboard_fab2_lib.baseboard_fab2(sch_1):page71_i50:vccin(228)" )
			)
			( pin "U2D1.BA60"
				( objectStatus "@baseboard_fab2_lib.baseboard_fab2(sch_1):page71_i50:vccin(229)" )
			)
			( pin "U2D1.AY61"
				( objectStatus "@baseboard_fab2_lib.baseboard_fab2(sch_1):page71_i50:vccin(230)" )
			)
			( pin "U2D1.AW60"
				( objectStatus "@baseboard_fab2_lib.baseboard_fab2(sch_1):page71_i50:vccin(231)" )
			)
			( pin "U2D1.AV61"
				( objectStatus "@baseboard_fab2_lib.baseboard_fab2(sch_1):page71_i50:vccin(232)" )
			)
			( pin "U2D1.AV59"
				( objectStatus "@baseboard_fab2_lib.baseboard_fab2(sch_1):page71_i50:vccin(233)" )
			)
			( pin "U2D1.AU60"
				( objectStatus "@baseboard_fab2_lib.baseboard_fab2(sch_1):page71_i50:vccin(234)" )
			)
			( pin "U2D1.AU58"
				( objectStatus "@baseboard_fab2_lib.baseboard_fab2(sch_1):page71_i50:vccin(235)" )
			)
			( pin "U2D1.AT59"
				( objectStatus "@baseboard_fab2_lib.baseboard_fab2(sch_1):page71_i50:vccin(236)" )
			)
			( pin "U2D1.AT57"
				( objectStatus "@baseboard_fab2_lib.baseboard_fab2(sch_1):page71_i50:vccin(237)" )
			)
			( pin "U2D1.AR58"
				( objectStatus "@baseboard_fab2_lib.baseboard_fab2(sch_1):page71_i50:vccin(238)" )
			)
			( pin "U2D1.AR56"
				( objectStatus "@baseboard_fab2_lib.baseboard_fab2(sch_1):page71_i50:vccin(239)" )
			)
			( pin "U2D1.AP57"
				( objectStatus "@baseboard_fab2_lib.baseboard_fab2(sch_1):page71_i50:vccin(240)" )
			)
			( pin "U2D1.AP55"
				( objectStatus "@baseboard_fab2_lib.baseboard_fab2(sch_1):page71_i50:vccin(241)" )
			)
			( pin "U2D1.AN56"
				( objectStatus "@baseboard_fab2_lib.baseboard_fab2(sch_1):page71_i50:vccin(242)" )
			)
			( pin "U2D1.AN54"
				( objectStatus "@baseboard_fab2_lib.baseboard_fab2(sch_1):page71_i50:vccin(243)" )
			)
			( pin "U2D1.AN32"
				( objectStatus "@baseboard_fab2_lib.baseboard_fab2(sch_1):page71_i50:vccin(244)" )
			)
			( pin "U2D1.AM55"
				( objectStatus "@baseboard_fab2_lib.baseboard_fab2(sch_1):page71_i50:vccin(245)" )
			)
			( pin "U2D1.AM53"
				( objectStatus "@baseboard_fab2_lib.baseboard_fab2(sch_1):page71_i50:vccin(246)" )
			)
			( pin "U2D1.AM33"
				( objectStatus "@baseboard_fab2_lib.baseboard_fab2(sch_1):page71_i50:vccin(247)" )
			)
			( pin "U2D1.AL54"
				( objectStatus "@baseboard_fab2_lib.baseboard_fab2(sch_1):page71_i50:vccin(248)" )
			)
			( pin "U2D1.AL52"
				( objectStatus "@baseboard_fab2_lib.baseboard_fab2(sch_1):page71_i50:vccin(249)" )
			)
			( pin "U2D1.AL50"
				( objectStatus "@baseboard_fab2_lib.baseboard_fab2(sch_1):page71_i50:vccin(250)" )
			)
			( pin "U2D1.AL48"
				( objectStatus "@baseboard_fab2_lib.baseboard_fab2(sch_1):page71_i50:vccin(251)" )
			)
			( pin "U2D1.AL46"
				( objectStatus "@baseboard_fab2_lib.baseboard_fab2(sch_1):page71_i50:vccin(252)" )
			)
			( pin "U2D1.AL34"
				( objectStatus "@baseboard_fab2_lib.baseboard_fab2(sch_1):page71_i50:vccin(253)" )
			)
			( pin "U2D1.AK53"
				( objectStatus "@baseboard_fab2_lib.baseboard_fab2(sch_1):page71_i50:vccin(254)" )
			)
			( pin "U2D1.AK51"
				( objectStatus "@baseboard_fab2_lib.baseboard_fab2(sch_1):page71_i50:vccin(255)" )
			)
			( pin "U2D1.AK49"
				( objectStatus "@baseboard_fab2_lib.baseboard_fab2(sch_1):page71_i50:vccin(256)" )
			)
			( pin "U2D1.AK47"
				( objectStatus "@baseboard_fab2_lib.baseboard_fab2(sch_1):page71_i50:vccin(257)" )
			)
			( pin "U2D1.AK45"
				( objectStatus "@baseboard_fab2_lib.baseboard_fab2(sch_1):page71_i50:vccin(258)" )
			)
			( pin "U2D1.AK35"
				( objectStatus "@baseboard_fab2_lib.baseboard_fab2(sch_1):page71_i50:vccin(259)" )
			)
			( pin "U2D1.AJ36"
				( objectStatus "@baseboard_fab2_lib.baseboard_fab2(sch_1):page71_i50:vccin(260)" )
			)
			( pin "U2D1.AH41"
				( objectStatus "@baseboard_fab2_lib.baseboard_fab2(sch_1):page71_i50:vccin(261)" )
			)
			( pin "U2D1.AH39"
				( objectStatus "@baseboard_fab2_lib.baseboard_fab2(sch_1):page71_i50:vccin(262)" )
			)
			( pin "U2D1.AH37"
				( objectStatus "@baseboard_fab2_lib.baseboard_fab2(sch_1):page71_i50:vccin(263)" )
			)
			( pin "U2D1.AG42"
				( objectStatus "@baseboard_fab2_lib.baseboard_fab2(sch_1):page71_i50:vccin(264)" )
			)
			( pin "U2D1.AG40"
				( objectStatus "@baseboard_fab2_lib.baseboard_fab2(sch_1):page71_i50:vccin(265)" )
			)
			( pin "U2D1.AG38"
				( objectStatus "@baseboard_fab2_lib.baseboard_fab2(sch_1):page71_i50:vccin(266)" )
			)
			( pin "U2D1.AF43"
				( objectStatus "@baseboard_fab2_lib.baseboard_fab2(sch_1):page71_i50:vccin(267)" )
			)
			( pin "U2D1.CY49"
				( objectStatus "@baseboard_fab2_lib.baseboard_fab2(sch_1):page71_i51:vccin(0)" )
			)
			( pin "U2D1.CY47"
				( objectStatus "@baseboard_fab2_lib.baseboard_fab2(sch_1):page71_i51:vccin(1)" )
			)
			( pin "U2D1.CW50"
				( objectStatus "@baseboard_fab2_lib.baseboard_fab2(sch_1):page71_i51:vccin(2)" )
			)
			( pin "U2D1.CW48"
				( objectStatus "@baseboard_fab2_lib.baseboard_fab2(sch_1):page71_i51:vccin(3)" )
			)
			( pin "U2D1.CW46"
				( objectStatus "@baseboard_fab2_lib.baseboard_fab2(sch_1):page71_i51:vccin(4)" )
			)
			( pin "U2D1.CV51"
				( objectStatus "@baseboard_fab2_lib.baseboard_fab2(sch_1):page71_i51:vccin(5)" )
			)
			( pin "U2D1.CU54"
				( objectStatus "@baseboard_fab2_lib.baseboard_fab2(sch_1):page71_i51:vccin(6)" )
			)
			( pin "U2D1.CU52"
				( objectStatus "@baseboard_fab2_lib.baseboard_fab2(sch_1):page71_i51:vccin(7)" )
			)
			( pin "U2D1.CU42"
				( objectStatus "@baseboard_fab2_lib.baseboard_fab2(sch_1):page71_i51:vccin(8)" )
			)
			( pin "U2D1.CU40"
				( objectStatus "@baseboard_fab2_lib.baseboard_fab2(sch_1):page71_i51:vccin(9)" )
			)
			( pin "U2D1.CU38"
				( objectStatus "@baseboard_fab2_lib.baseboard_fab2(sch_1):page71_i51:vccin(10)" )
			)
			( pin "U2D1.CT55"
				( objectStatus "@baseboard_fab2_lib.baseboard_fab2(sch_1):page71_i51:vccin(11)" )
			)
			( pin "U2D1.CT53"
				( objectStatus "@baseboard_fab2_lib.baseboard_fab2(sch_1):page71_i51:vccin(12)" )
			)
			( pin "U2D1.CT41"
				( objectStatus "@baseboard_fab2_lib.baseboard_fab2(sch_1):page71_i51:vccin(13)" )
			)
			( pin "U2D1.CT39"
				( objectStatus "@baseboard_fab2_lib.baseboard_fab2(sch_1):page71_i51:vccin(14)" )
			)
			( pin "U2D1.CT37"
				( objectStatus "@baseboard_fab2_lib.baseboard_fab2(sch_1):page71_i51:vccin(15)" )
			)
			( pin "U2D1.CR56"
				( objectStatus "@baseboard_fab2_lib.baseboard_fab2(sch_1):page71_i51:vccin(16)" )
			)
			( pin "U2D1.CR54"
				( objectStatus "@baseboard_fab2_lib.baseboard_fab2(sch_1):page71_i51:vccin(17)" )
			)
			( pin "U2D1.CR34"
				( objectStatus "@baseboard_fab2_lib.baseboard_fab2(sch_1):page71_i51:vccin(18)" )
			)
			( pin "U2D1.CP57"
				( objectStatus "@baseboard_fab2_lib.baseboard_fab2(sch_1):page71_i51:vccin(19)" )
			)
			( pin "U2D1.CP55"
				( objectStatus "@baseboard_fab2_lib.baseboard_fab2(sch_1):page71_i51:vccin(20)" )
			)
			( pin "U2D1.CP33"
				( objectStatus "@baseboard_fab2_lib.baseboard_fab2(sch_1):page71_i51:vccin(21)" )
			)
			( pin "U2D1.CN58"
				( objectStatus "@baseboard_fab2_lib.baseboard_fab2(sch_1):page71_i51:vccin(22)" )
			)
			( pin "U2D1.CN56"
				( objectStatus "@baseboard_fab2_lib.baseboard_fab2(sch_1):page71_i51:vccin(23)" )
			)
			( pin "U2D1.CM59"
				( objectStatus "@baseboard_fab2_lib.baseboard_fab2(sch_1):page71_i51:vccin(24)" )
			)
			( pin "U2D1.CM57"
				( objectStatus "@baseboard_fab2_lib.baseboard_fab2(sch_1):page71_i51:vccin(25)" )
			)
			( pin "U2D1.CL60"
				( objectStatus "@baseboard_fab2_lib.baseboard_fab2(sch_1):page71_i51:vccin(26)" )
			)
			( pin "U2D1.CL58"
				( objectStatus "@baseboard_fab2_lib.baseboard_fab2(sch_1):page71_i51:vccin(27)" )
			)
			( pin "U2D1.CK61"
				( objectStatus "@baseboard_fab2_lib.baseboard_fab2(sch_1):page71_i51:vccin(28)" )
			)
			( pin "U2D1.CK59"
				( objectStatus "@baseboard_fab2_lib.baseboard_fab2(sch_1):page71_i51:vccin(29)" )
			)
			( pin "U2D1.CJ60"
				( objectStatus "@baseboard_fab2_lib.baseboard_fab2(sch_1):page71_i51:vccin(30)" )
			)
			( pin "U2D1.CH85"
				( objectStatus "@baseboard_fab2_lib.baseboard_fab2(sch_1):page71_i51:vccin(31)" )
			)
			( pin "U2D1.CH61"
				( objectStatus "@baseboard_fab2_lib.baseboard_fab2(sch_1):page71_i51:vccin(32)" )
			)
			( pin "U2D1.CG84"
				( objectStatus "@baseboard_fab2_lib.baseboard_fab2(sch_1):page71_i51:vccin(33)" )
			)
			( pin "U2D1.CG60"
				( objectStatus "@baseboard_fab2_lib.baseboard_fab2(sch_1):page71_i51:vccin(34)" )
			)
			( pin "U2D1.CF85"
				( objectStatus "@baseboard_fab2_lib.baseboard_fab2(sch_1):page71_i51:vccin(35)" )
			)
			( pin "U2D1.CF61"
				( objectStatus "@baseboard_fab2_lib.baseboard_fab2(sch_1):page71_i51:vccin(36)" )
			)
			( pin "U2D1.CE84"
				( objectStatus "@baseboard_fab2_lib.baseboard_fab2(sch_1):page71_i51:vccin(37)" )
			)
			( pin "U2D1.CE60"
				( objectStatus "@baseboard_fab2_lib.baseboard_fab2(sch_1):page71_i51:vccin(38)" )
			)
			( pin "U2D1.CD85"
				( objectStatus "@baseboard_fab2_lib.baseboard_fab2(sch_1):page71_i51:vccin(39)" )
			)
			( pin "U2D1.CD83"
				( objectStatus "@baseboard_fab2_lib.baseboard_fab2(sch_1):page71_i51:vccin(40)" )
			)
			( pin "U2D1.CD61"
				( objectStatus "@baseboard_fab2_lib.baseboard_fab2(sch_1):page71_i51:vccin(41)" )
			)
			( pin "U2D1.CC84"
				( objectStatus "@baseboard_fab2_lib.baseboard_fab2(sch_1):page71_i51:vccin(42)" )
			)
			( pin "U2D1.CC62"
				( objectStatus "@baseboard_fab2_lib.baseboard_fab2(sch_1):page71_i51:vccin(43)" )
			)
			( pin "U2D1.CC60"
				( objectStatus "@baseboard_fab2_lib.baseboard_fab2(sch_1):page71_i51:vccin(44)" )
			)
			( pin "U2D1.CB83"
				( objectStatus "@baseboard_fab2_lib.baseboard_fab2(sch_1):page71_i51:vccin(45)" )
			)
			( pin "U2D1.CB81"
				( objectStatus "@baseboard_fab2_lib.baseboard_fab2(sch_1):page71_i51:vccin(46)" )
			)
			( pin "U2D1.CB79"
				( objectStatus "@baseboard_fab2_lib.baseboard_fab2(sch_1):page71_i51:vccin(47)" )
			)
			( pin "U2D1.CB77"
				( objectStatus "@baseboard_fab2_lib.baseboard_fab2(sch_1):page71_i51:vccin(48)" )
			)
			( pin "U2D1.CB75"
				( objectStatus "@baseboard_fab2_lib.baseboard_fab2(sch_1):page71_i51:vccin(49)" )
			)
			( pin "U2D1.CB73"
				( objectStatus "@baseboard_fab2_lib.baseboard_fab2(sch_1):page71_i51:vccin(50)" )
			)
			( pin "U2D1.CB61"
				( objectStatus "@baseboard_fab2_lib.baseboard_fab2(sch_1):page71_i51:vccin(51)" )
			)
			( pin "U2D1.CA84"
				( objectStatus "@baseboard_fab2_lib.baseboard_fab2(sch_1):page71_i51:vccin(52)" )
			)
			( pin "U2D1.CA82"
				( objectStatus "@baseboard_fab2_lib.baseboard_fab2(sch_1):page71_i51:vccin(53)" )
			)
			( pin "U2D1.CA80"
				( objectStatus "@baseboard_fab2_lib.baseboard_fab2(sch_1):page71_i51:vccin(54)" )
			)
			( pin "U2D1.CA78"
				( objectStatus "@baseboard_fab2_lib.baseboard_fab2(sch_1):page71_i51:vccin(55)" )
			)
			( pin "U2D1.CA76"
				( objectStatus "@baseboard_fab2_lib.baseboard_fab2(sch_1):page71_i51:vccin(56)" )
			)
			( pin "U2D1.CA74"
				( objectStatus "@baseboard_fab2_lib.baseboard_fab2(sch_1):page71_i51:vccin(57)" )
			)
			( pin "U2D1.CA72"
				( objectStatus "@baseboard_fab2_lib.baseboard_fab2(sch_1):page71_i51:vccin(58)" )
			)
			( pin "U2D1.CA62"
				( objectStatus "@baseboard_fab2_lib.baseboard_fab2(sch_1):page71_i51:vccin(59)" )
			)
			( pin "U2D1.CA60"
				( objectStatus "@baseboard_fab2_lib.baseboard_fab2(sch_1):page71_i51:vccin(60)" )
			)
			( pin "U2D1.BY83"
				( objectStatus "@baseboard_fab2_lib.baseboard_fab2(sch_1):page71_i51:vccin(61)" )
			)
			( pin "U2D1.BY81"
				( objectStatus "@baseboard_fab2_lib.baseboard_fab2(sch_1):page71_i51:vccin(62)" )
			)
			( pin "U2D1.BY79"
				( objectStatus "@baseboard_fab2_lib.baseboard_fab2(sch_1):page71_i51:vccin(63)" )
			)
			( pin "U2D1.BY77"
				( objectStatus "@baseboard_fab2_lib.baseboard_fab2(sch_1):page71_i51:vccin(64)" )
			)
			( pin "U2D1.BY75"
				( objectStatus "@baseboard_fab2_lib.baseboard_fab2(sch_1):page71_i51:vccin(65)" )
			)
			( pin "U2D1.BY73"
				( objectStatus "@baseboard_fab2_lib.baseboard_fab2(sch_1):page71_i51:vccin(66)" )
			)
			( pin "U2D1.BY61"
				( objectStatus "@baseboard_fab2_lib.baseboard_fab2(sch_1):page71_i51:vccin(67)" )
			)
			( pin "U2D1.BW84"
				( objectStatus "@baseboard_fab2_lib.baseboard_fab2(sch_1):page71_i51:vccin(68)" )
			)
			( pin "U2D1.BW70"
				( objectStatus "@baseboard_fab2_lib.baseboard_fab2(sch_1):page71_i51:vccin(69)" )
			)
			( pin "U2D1.BW68"
				( objectStatus "@baseboard_fab2_lib.baseboard_fab2(sch_1):page71_i51:vccin(70)" )
			)
			( pin "U2D1.BW66"
				( objectStatus "@baseboard_fab2_lib.baseboard_fab2(sch_1):page71_i51:vccin(71)" )
			)
			( pin "U2D1.BW64"
				( objectStatus "@baseboard_fab2_lib.baseboard_fab2(sch_1):page71_i51:vccin(72)" )
			)
			( pin "U2D1.BW62"
				( objectStatus "@baseboard_fab2_lib.baseboard_fab2(sch_1):page71_i51:vccin(73)" )
			)
			( pin "U2D1.BW60"
				( objectStatus "@baseboard_fab2_lib.baseboard_fab2(sch_1):page71_i51:vccin(74)" )
			)
			( pin "U2D1.BV83"
				( objectStatus "@baseboard_fab2_lib.baseboard_fab2(sch_1):page71_i51:vccin(75)" )
			)
			( pin "U2D1.BV81"
				( objectStatus "@baseboard_fab2_lib.baseboard_fab2(sch_1):page71_i51:vccin(76)" )
			)
			( pin "U2D1.BV79"
				( objectStatus "@baseboard_fab2_lib.baseboard_fab2(sch_1):page71_i51:vccin(77)" )
			)
			( pin "U2D1.BV77"
				( objectStatus "@baseboard_fab2_lib.baseboard_fab2(sch_1):page71_i51:vccin(78)" )
			)
			( pin "U2D1.BV75"
				( objectStatus "@baseboard_fab2_lib.baseboard_fab2(sch_1):page71_i51:vccin(79)" )
			)
			( pin "U2D1.BV73"
				( objectStatus "@baseboard_fab2_lib.baseboard_fab2(sch_1):page71_i51:vccin(80)" )
			)
			( pin "U2D1.BV71"
				( objectStatus "@baseboard_fab2_lib.baseboard_fab2(sch_1):page71_i51:vccin(81)" )
			)
			( pin "U2D1.BV69"
				( objectStatus "@baseboard_fab2_lib.baseboard_fab2(sch_1):page71_i51:vccin(82)" )
			)
			( pin "U2D1.BV67"
				( objectStatus "@baseboard_fab2_lib.baseboard_fab2(sch_1):page71_i51:vccin(83)" )
			)
			( pin "U2D1.BV65"
				( objectStatus "@baseboard_fab2_lib.baseboard_fab2(sch_1):page71_i51:vccin(84)" )
			)
			( pin "U2D1.BV63"
				( objectStatus "@baseboard_fab2_lib.baseboard_fab2(sch_1):page71_i51:vccin(85)" )
			)
			( pin "U2D1.BV61"
				( objectStatus "@baseboard_fab2_lib.baseboard_fab2(sch_1):page71_i51:vccin(86)" )
			)
			( pin "U2D1.BU84"
				( objectStatus "@baseboard_fab2_lib.baseboard_fab2(sch_1):page71_i51:vccin(87)" )
			)
			( pin "U2D1.BU82"
				( objectStatus "@baseboard_fab2_lib.baseboard_fab2(sch_1):page71_i51:vccin(88)" )
			)
			( pin "U2D1.BU80"
				( objectStatus "@baseboard_fab2_lib.baseboard_fab2(sch_1):page71_i51:vccin(89)" )
			)
			( pin "U2D1.BU78"
				( objectStatus "@baseboard_fab2_lib.baseboard_fab2(sch_1):page71_i51:vccin(90)" )
			)
			( pin "U2D1.BU76"
				( objectStatus "@baseboard_fab2_lib.baseboard_fab2(sch_1):page71_i51:vccin(91)" )
			)
			( pin "U2D1.BU74"
				( objectStatus "@baseboard_fab2_lib.baseboard_fab2(sch_1):page71_i51:vccin(92)" )
			)
			( pin "U2D1.BU72"
				( objectStatus "@baseboard_fab2_lib.baseboard_fab2(sch_1):page71_i51:vccin(93)" )
			)
			( pin "U2D1.BU70"
				( objectStatus "@baseboard_fab2_lib.baseboard_fab2(sch_1):page71_i51:vccin(94)" )
			)
			( pin "U2D1.BU68"
				( objectStatus "@baseboard_fab2_lib.baseboard_fab2(sch_1):page71_i51:vccin(95)" )
			)
			( pin "U2D1.BU66"
				( objectStatus "@baseboard_fab2_lib.baseboard_fab2(sch_1):page71_i51:vccin(96)" )
			)
			( pin "U2D1.BU64"
				( objectStatus "@baseboard_fab2_lib.baseboard_fab2(sch_1):page71_i51:vccin(97)" )
			)
			( pin "U2D1.BU62"
				( objectStatus "@baseboard_fab2_lib.baseboard_fab2(sch_1):page71_i51:vccin(98)" )
			)
			( pin "U2D1.BU60"
				( objectStatus "@baseboard_fab2_lib.baseboard_fab2(sch_1):page71_i51:vccin(99)" )
			)
			( pin "U2D1.BT83"
				( objectStatus "@baseboard_fab2_lib.baseboard_fab2(sch_1):page71_i51:vccin(100)" )
			)
			( pin "U2D1.BT81"
				( objectStatus "@baseboard_fab2_lib.baseboard_fab2(sch_1):page71_i51:vccin(101)" )
			)
			( pin "U2D1.BT79"
				( objectStatus "@baseboard_fab2_lib.baseboard_fab2(sch_1):page71_i51:vccin(102)" )
			)
			( pin "U2D1.BT77"
				( objectStatus "@baseboard_fab2_lib.baseboard_fab2(sch_1):page71_i51:vccin(103)" )
			)
			( pin "U2D1.BT75"
				( objectStatus "@baseboard_fab2_lib.baseboard_fab2(sch_1):page71_i51:vccin(104)" )
			)
			( pin "U2D1.BT73"
				( objectStatus "@baseboard_fab2_lib.baseboard_fab2(sch_1):page71_i51:vccin(105)" )
			)
			( pin "U2D1.BT71"
				( objectStatus "@baseboard_fab2_lib.baseboard_fab2(sch_1):page71_i51:vccin(106)" )
			)
			( pin "U2D1.BT69"
				( objectStatus "@baseboard_fab2_lib.baseboard_fab2(sch_1):page71_i51:vccin(107)" )
			)
			( pin "U2D1.BT67"
				( objectStatus "@baseboard_fab2_lib.baseboard_fab2(sch_1):page71_i51:vccin(108)" )
			)
			( pin "U2D1.BT65"
				( objectStatus "@baseboard_fab2_lib.baseboard_fab2(sch_1):page71_i51:vccin(109)" )
			)
			( pin "U2D1.BT63"
				( objectStatus "@baseboard_fab2_lib.baseboard_fab2(sch_1):page71_i51:vccin(110)" )
			)
			( pin "U2D1.BT61"
				( objectStatus "@baseboard_fab2_lib.baseboard_fab2(sch_1):page71_i51:vccin(111)" )
			)
			( pin "U2D1.BR84"
				( objectStatus "@baseboard_fab2_lib.baseboard_fab2(sch_1):page71_i51:vccin(112)" )
			)
			( pin "U2D1.BR62"
				( objectStatus "@baseboard_fab2_lib.baseboard_fab2(sch_1):page71_i51:vccin(113)" )
			)
			( pin "U2D1.BR60"
				( objectStatus "@baseboard_fab2_lib.baseboard_fab2(sch_1):page71_i51:vccin(114)" )
			)
			( pin "U2D1.BP83"
				( objectStatus "@baseboard_fab2_lib.baseboard_fab2(sch_1):page71_i51:vccin(115)" )
			)
			( pin "U2D1.BP81"
				( objectStatus "@baseboard_fab2_lib.baseboard_fab2(sch_1):page71_i51:vccin(116)" )
			)
			( pin "U2D1.BP79"
				( objectStatus "@baseboard_fab2_lib.baseboard_fab2(sch_1):page71_i51:vccin(117)" )
			)
			( pin "U2D1.BP77"
				( objectStatus "@baseboard_fab2_lib.baseboard_fab2(sch_1):page71_i51:vccin(118)" )
			)
			( pin "U2D1.BP75"
				( objectStatus "@baseboard_fab2_lib.baseboard_fab2(sch_1):page71_i51:vccin(119)" )
			)
			( pin "U2D1.BP73"
				( objectStatus "@baseboard_fab2_lib.baseboard_fab2(sch_1):page71_i51:vccin(120)" )
			)
			( pin "U2D1.BP71"
				( objectStatus "@baseboard_fab2_lib.baseboard_fab2(sch_1):page71_i51:vccin(121)" )
			)
			( pin "U2D1.BP69"
				( objectStatus "@baseboard_fab2_lib.baseboard_fab2(sch_1):page71_i51:vccin(122)" )
			)
			( pin "U2D1.BP67"
				( objectStatus "@baseboard_fab2_lib.baseboard_fab2(sch_1):page71_i51:vccin(123)" )
			)
			( pin "U2D1.BP65"
				( objectStatus "@baseboard_fab2_lib.baseboard_fab2(sch_1):page71_i51:vccin(124)" )
			)
			( pin "U2D1.BP63"
				( objectStatus "@baseboard_fab2_lib.baseboard_fab2(sch_1):page71_i51:vccin(125)" )
			)
			( pin "U2D1.BP61"
				( objectStatus "@baseboard_fab2_lib.baseboard_fab2(sch_1):page71_i51:vccin(126)" )
			)
			( pin "U2D1.BN84"
				( objectStatus "@baseboard_fab2_lib.baseboard_fab2(sch_1):page71_i51:vccin(127)" )
			)
			( pin "U2D1.BN82"
				( objectStatus "@baseboard_fab2_lib.baseboard_fab2(sch_1):page71_i51:vccin(128)" )
			)
			( pin "U2D1.BN80"
				( objectStatus "@baseboard_fab2_lib.baseboard_fab2(sch_1):page71_i51:vccin(129)" )
			)
			( pin "U2D1.BA86"
				( objectStatus "@baseboard_fab2_lib.baseboard_fab2(sch_1):page71_i51:vccin_sense" )
			)
			( pin "U2D1.AW86"
				( objectStatus "@baseboard_fab2_lib.baseboard_fab2(sch_1):page71_i51:vccinpmax(0)" )
			)
			( pin "U2D1.AV85"
				( objectStatus "@baseboard_fab2_lib.baseboard_fab2(sch_1):page71_i51:vccinpmax(1)" )
			)
			( pin "U2D1.AD41"
				( objectStatus "@baseboard_fab2_lib.baseboard_fab2(sch_1):page71_i51:vsensepmax" )
			)
			( pin "U2D1.AY85"
				( objectStatus "@baseboard_fab2_lib.baseboard_fab2(sch_1):page71_i51:vss_vccin_sense" )
			)
			( pin "R3D32.1"
				( objectStatus "@baseboard_fab2_lib.baseboard_fab2(sch_1):page71_i53:a" )
			)
			( pin "R3D32.2"
				( objectStatus "@baseboard_fab2_lib.baseboard_fab2(sch_1):page71_i53:b" )
			)
			( pin "C3D3.1"
				( objectStatus "@baseboard_fab2_lib.baseboard_fab2(sch_1):page72_i25:a" )
			)
			( pin "C3D3.2"
				( objectStatus "@baseboard_fab2_lib.baseboard_fab2(sch_1):page72_i25:b" )
			)
			( pin "U2D1.B49"
				( objectStatus "@baseboard_fab2_lib.baseboard_fab2(sch_1):page72_i32:vccd012(0)" )
			)
			( pin "U2D1.B53"
				( objectStatus "@baseboard_fab2_lib.baseboard_fab2(sch_1):page72_i32:vccd012(1)" )
			)
			( pin "U2D1.B59"
				( objectStatus "@baseboard_fab2_lib.baseboard_fab2(sch_1):page72_i32:vccd012(2)" )
			)
			( pin "U2D1.E46"
				( objectStatus "@baseboard_fab2_lib.baseboard_fab2(sch_1):page72_i32:vccd012(3)" )
			)
			( pin "U2D1.E48"
				( objectStatus "@baseboard_fab2_lib.baseboard_fab2(sch_1):page72_i32:vccd012(4)" )
			)
			( pin "U2D1.E50"
				( objectStatus "@baseboard_fab2_lib.baseboard_fab2(sch_1):page72_i32:vccd012(5)" )
			)
			( pin "U2D1.E52"
				( objectStatus "@baseboard_fab2_lib.baseboard_fab2(sch_1):page72_i32:vccd012(6)" )
			)
			( pin "U2D1.E54"
				( objectStatus "@baseboard_fab2_lib.baseboard_fab2(sch_1):page72_i32:vccd012(7)" )
			)
			( pin "U2D1.E56"
				( objectStatus "@baseboard_fab2_lib.baseboard_fab2(sch_1):page72_i32:vccd012(8)" )
			)
			( pin "U2D1.E58"
				( objectStatus "@baseboard_fab2_lib.baseboard_fab2(sch_1):page72_i32:vccd012(9)" )
			)
			( pin "U2D1.E60"
				( objectStatus "@baseboard_fab2_lib.baseboard_fab2(sch_1):page72_i32:vccd012(10)" )
			)
			( pin "U2D1.E62"
				( objectStatus "@baseboard_fab2_lib.baseboard_fab2(sch_1):page72_i32:vccd012(11)" )
			)
			( pin "U2D1.E64"
				( objectStatus "@baseboard_fab2_lib.baseboard_fab2(sch_1):page72_i32:vccd012(12)" )
			)
			( pin "U2D1.L46"
				( objectStatus "@baseboard_fab2_lib.baseboard_fab2(sch_1):page72_i32:vccd012(13)" )
			)
			( pin "U2D1.L48"
				( objectStatus "@baseboard_fab2_lib.baseboard_fab2(sch_1):page72_i32:vccd012(14)" )
			)
			( pin "U2D1.L50"
				( objectStatus "@baseboard_fab2_lib.baseboard_fab2(sch_1):page72_i32:vccd012(15)" )
			)
			( pin "U2D1.L52"
				( objectStatus "@baseboard_fab2_lib.baseboard_fab2(sch_1):page72_i32:vccd012(16)" )
			)
			( pin "U2D1.L54"
				( objectStatus "@baseboard_fab2_lib.baseboard_fab2(sch_1):page72_i32:vccd012(17)" )
			)
			( pin "U2D1.L56"
				( objectStatus "@baseboard_fab2_lib.baseboard_fab2(sch_1):page72_i32:vccd012(18)" )
			)
			( pin "U2D1.L58"
				( objectStatus "@baseboard_fab2_lib.baseboard_fab2(sch_1):page72_i32:vccd012(19)" )
			)
			( pin "U2D1.L60"
				( objectStatus "@baseboard_fab2_lib.baseboard_fab2(sch_1):page72_i32:vccd012(20)" )
			)
			( pin "U2D1.L62"
				( objectStatus "@baseboard_fab2_lib.baseboard_fab2(sch_1):page72_i32:vccd012(21)" )
			)
			( pin "U2D1.N64"
				( objectStatus "@baseboard_fab2_lib.baseboard_fab2(sch_1):page72_i32:vccd012(22)" )
			)
			( pin "U2D1.U46"
				( objectStatus "@baseboard_fab2_lib.baseboard_fab2(sch_1):page72_i32:vccd012(23)" )
			)
			( pin "U2D1.U48"
				( objectStatus "@baseboard_fab2_lib.baseboard_fab2(sch_1):page72_i32:vccd012(24)" )
			)
			( pin "U2D1.U50"
				( objectStatus "@baseboard_fab2_lib.baseboard_fab2(sch_1):page72_i32:vccd012(25)" )
			)
			( pin "U2D1.U52"
				( objectStatus "@baseboard_fab2_lib.baseboard_fab2(sch_1):page72_i32:vccd012(26)" )
			)
			( pin "U2D1.U54"
				( objectStatus "@baseboard_fab2_lib.baseboard_fab2(sch_1):page72_i32:vccd012(27)" )
			)
			( pin "U2D1.U56"
				( objectStatus "@baseboard_fab2_lib.baseboard_fab2(sch_1):page72_i32:vccd012(28)" )
			)
			( pin "U2D1.U58"
				( objectStatus "@baseboard_fab2_lib.baseboard_fab2(sch_1):page72_i32:vccd012(29)" )
			)
			( pin "U2D1.U60"
				( objectStatus "@baseboard_fab2_lib.baseboard_fab2(sch_1):page72_i32:vccd012(30)" )
			)
			( pin "U2D1.U62"
				( objectStatus "@baseboard_fab2_lib.baseboard_fab2(sch_1):page72_i32:vccd012(31)" )
			)
			( pin "U2D1.W64"
				( objectStatus "@baseboard_fab2_lib.baseboard_fab2(sch_1):page72_i32:vccd012(32)" )
			)
			( pin "U2D1.Y45"
				( objectStatus "@baseboard_fab2_lib.baseboard_fab2(sch_1):page72_i32:vccd012(33)" )
			)
			( pin "U2D1.Y47"
				( objectStatus "@baseboard_fab2_lib.baseboard_fab2(sch_1):page72_i32:vccd012(34)" )
			)
			( pin "U2D1.Y49"
				( objectStatus "@baseboard_fab2_lib.baseboard_fab2(sch_1):page72_i32:vccd012(35)" )
			)
			( pin "U2D1.Y51"
				( objectStatus "@baseboard_fab2_lib.baseboard_fab2(sch_1):page72_i32:vccd012(36)" )
			)
			( pin "U2D1.Y53"
				( objectStatus "@baseboard_fab2_lib.baseboard_fab2(sch_1):page72_i32:vccd012(37)" )
			)
			( pin "U2D1.Y55"
				( objectStatus "@baseboard_fab2_lib.baseboard_fab2(sch_1):page72_i32:vccd012(38)" )
			)
			( pin "U2D1.Y57"
				( objectStatus "@baseboard_fab2_lib.baseboard_fab2(sch_1):page72_i32:vccd012(39)" )
			)
			( pin "U2D1.Y59"
				( objectStatus "@baseboard_fab2_lib.baseboard_fab2(sch_1):page72_i32:vccd012(40)" )
			)
			( pin "U2D1.Y61"
				( objectStatus "@baseboard_fab2_lib.baseboard_fab2(sch_1):page72_i32:vccd012(41)" )
			)
			( pin "U2D1.Y63"
				( objectStatus "@baseboard_fab2_lib.baseboard_fab2(sch_1):page72_i32:vccd012(42)" )
			)
			( pin "U2D1.AD45"
				( objectStatus "@baseboard_fab2_lib.baseboard_fab2(sch_1):page72_i32:vccd012(43)" )
			)
			( pin "U2D1.AF55"
				( objectStatus "@baseboard_fab2_lib.baseboard_fab2(sch_1):page72_i32:vccd012(44)" )
			)
			( pin "U2D1.AF57"
				( objectStatus "@baseboard_fab2_lib.baseboard_fab2(sch_1):page72_i32:vccd012(45)" )
			)
			( pin "U2D1.AF59"
				( objectStatus "@baseboard_fab2_lib.baseboard_fab2(sch_1):page72_i32:vccd012(46)" )
			)
			( pin "U2D1.AF61"
				( objectStatus "@baseboard_fab2_lib.baseboard_fab2(sch_1):page72_i32:vccd012(47)" )
			)
			( pin "U2D1.AF63"
				( objectStatus "@baseboard_fab2_lib.baseboard_fab2(sch_1):page72_i32:vccd012(48)" )
			)
			( pin "U2D1.D45"
				( objectStatus "@baseboard_fab2_lib.baseboard_fab2(sch_1):page72_i32:vccd012(49)" )
			)
			( pin "U2D1.C46"
				( objectStatus "@baseboard_fab2_lib.baseboard_fab2(sch_1):page72_i32:vccd012(50)" )
			)
			( pin "U2D1.B47"
				( objectStatus "@baseboard_fab2_lib.baseboard_fab2(sch_1):page72_i32:vccd012(51)" )
			)
			( pin "U2D1.EF59"
				( objectStatus "@baseboard_fab2_lib.baseboard_fab2(sch_1):page72_i32:vccd345(0)" )
			)
			( pin "U2D1.EF53"
				( objectStatus "@baseboard_fab2_lib.baseboard_fab2(sch_1):page72_i32:vccd345(1)" )
			)
			( pin "U2D1.EF49"
				( objectStatus "@baseboard_fab2_lib.baseboard_fab2(sch_1):page72_i32:vccd345(2)" )
			)
			( pin "U2D1.EC62"
				( objectStatus "@baseboard_fab2_lib.baseboard_fab2(sch_1):page72_i32:vccd345(3)" )
			)
			( pin "U2D1.EC60"
				( objectStatus "@baseboard_fab2_lib.baseboard_fab2(sch_1):page72_i32:vccd345(4)" )
			)
			( pin "U2D1.EC58"
				( objectStatus "@baseboard_fab2_lib.baseboard_fab2(sch_1):page72_i32:vccd345(5)" )
			)
			( pin "U2D1.EC56"
				( objectStatus "@baseboard_fab2_lib.baseboard_fab2(sch_1):page72_i32:vccd345(6)" )
			)
			( pin "U2D1.EC54"
				( objectStatus "@baseboard_fab2_lib.baseboard_fab2(sch_1):page72_i32:vccd345(7)" )
			)
			( pin "U2D1.EC52"
				( objectStatus "@baseboard_fab2_lib.baseboard_fab2(sch_1):page72_i32:vccd345(8)" )
			)
			( pin "U2D1.EC50"
				( objectStatus "@baseboard_fab2_lib.baseboard_fab2(sch_1):page72_i32:vccd345(9)" )
			)
			( pin "U2D1.EC48"
				( objectStatus "@baseboard_fab2_lib.baseboard_fab2(sch_1):page72_i32:vccd345(10)" )
			)
			( pin "U2D1.EC46"
				( objectStatus "@baseboard_fab2_lib.baseboard_fab2(sch_1):page72_i32:vccd345(11)" )
			)
			( pin "U2D1.DU64"
				( objectStatus "@baseboard_fab2_lib.baseboard_fab2(sch_1):page72_i32:vccd345(12)" )
			)
			( pin "U2D1.DU62"
				( objectStatus "@baseboard_fab2_lib.baseboard_fab2(sch_1):page72_i32:vccd345(13)" )
			)
			( pin "U2D1.DU60"
				( objectStatus "@baseboard_fab2_lib.baseboard_fab2(sch_1):page72_i32:vccd345(14)" )
			)
			( pin "U2D1.DU58"
				( objectStatus "@baseboard_fab2_lib.baseboard_fab2(sch_1):page72_i32:vccd345(15)" )
			)
			( pin "U2D1.DU56"
				( objectStatus "@baseboard_fab2_lib.baseboard_fab2(sch_1):page72_i32:vccd345(16)" )
			)
			( pin "U2D1.DU54"
				( objectStatus "@baseboard_fab2_lib.baseboard_fab2(sch_1):page72_i32:vccd345(17)" )
			)
			( pin "U2D1.DU52"
				( objectStatus "@baseboard_fab2_lib.baseboard_fab2(sch_1):page72_i32:vccd345(18)" )
			)
			( pin "U2D1.DU50"
				( objectStatus "@baseboard_fab2_lib.baseboard_fab2(sch_1):page72_i32:vccd345(19)" )
			)
			( pin "U2D1.DU48"
				( objectStatus "@baseboard_fab2_lib.baseboard_fab2(sch_1):page72_i32:vccd345(20)" )
			)
			( pin "U2D1.DU46"
				( objectStatus "@baseboard_fab2_lib.baseboard_fab2(sch_1):page72_i32:vccd345(21)" )
			)
			( pin "U2D1.DL62"
				( objectStatus "@baseboard_fab2_lib.baseboard_fab2(sch_1):page72_i32:vccd345(22)" )
			)
			( pin "U2D1.DL60"
				( objectStatus "@baseboard_fab2_lib.baseboard_fab2(sch_1):page72_i32:vccd345(23)" )
			)
			( pin "U2D1.DL58"
				( objectStatus "@baseboard_fab2_lib.baseboard_fab2(sch_1):page72_i32:vccd345(24)" )
			)
			( pin "U2D1.DL56"
				( objectStatus "@baseboard_fab2_lib.baseboard_fab2(sch_1):page72_i32:vccd345(25)" )
			)
			( pin "U2D1.DL54"
				( objectStatus "@baseboard_fab2_lib.baseboard_fab2(sch_1):page72_i32:vccd345(26)" )
			)
			( pin "U2D1.DL52"
				( objectStatus "@baseboard_fab2_lib.baseboard_fab2(sch_1):page72_i32:vccd345(27)" )
			)
			( pin "U2D1.DL50"
				( objectStatus "@baseboard_fab2_lib.baseboard_fab2(sch_1):page72_i32:vccd345(28)" )
			)
			( pin "U2D1.DL48"
				( objectStatus "@baseboard_fab2_lib.baseboard_fab2(sch_1):page72_i32:vccd345(29)" )
			)
			( pin "U2D1.DL46"
				( objectStatus "@baseboard_fab2_lib.baseboard_fab2(sch_1):page72_i32:vccd345(30)" )
			)
			( pin "U2D1.DJ64"
				( objectStatus "@baseboard_fab2_lib.baseboard_fab2(sch_1):page72_i32:vccd345(31)" )
			)
			( pin "U2D1.DH63"
				( objectStatus "@baseboard_fab2_lib.baseboard_fab2(sch_1):page72_i32:vccd345(32)" )
			)
			( pin "U2D1.DH61"
				( objectStatus "@baseboard_fab2_lib.baseboard_fab2(sch_1):page72_i32:vccd345(33)" )
			)
			( pin "U2D1.DH59"
				( objectStatus "@baseboard_fab2_lib.baseboard_fab2(sch_1):page72_i32:vccd345(34)" )
			)
			( pin "U2D1.DH57"
				( objectStatus "@baseboard_fab2_lib.baseboard_fab2(sch_1):page72_i32:vccd345(35)" )
			)
			( pin "U2D1.DH55"
				( objectStatus "@baseboard_fab2_lib.baseboard_fab2(sch_1):page72_i32:vccd345(36)" )
			)
			( pin "U2D1.DH53"
				( objectStatus "@baseboard_fab2_lib.baseboard_fab2(sch_1):page72_i32:vccd345(37)" )
			)
			( pin "U2D1.DH51"
				( objectStatus "@baseboard_fab2_lib.baseboard_fab2(sch_1):page72_i32:vccd345(38)" )
			)
			( pin "U2D1.DH49"
				( objectStatus "@baseboard_fab2_lib.baseboard_fab2(sch_1):page72_i32:vccd345(39)" )
			)
			( pin "U2D1.DH47"
				( objectStatus "@baseboard_fab2_lib.baseboard_fab2(sch_1):page72_i32:vccd345(40)" )
			)
			( pin "U2D1.DH45"
				( objectStatus "@baseboard_fab2_lib.baseboard_fab2(sch_1):page72_i32:vccd345(41)" )
			)
			( pin "U2D1.DD45"
				( objectStatus "@baseboard_fab2_lib.baseboard_fab2(sch_1):page72_i32:vccd345(42)" )
			)
			( pin "U2D1.DB63"
				( objectStatus "@baseboard_fab2_lib.baseboard_fab2(sch_1):page72_i32:vccd345(43)" )
			)
			( pin "U2D1.DB61"
				( objectStatus "@baseboard_fab2_lib.baseboard_fab2(sch_1):page72_i32:vccd345(44)" )
			)
			( pin "U2D1.DB59"
				( objectStatus "@baseboard_fab2_lib.baseboard_fab2(sch_1):page72_i32:vccd345(45)" )
			)
			( pin "U2D1.DB57"
				( objectStatus "@baseboard_fab2_lib.baseboard_fab2(sch_1):page72_i32:vccd345(46)" )
			)
			( pin "U2D1.DB55"
				( objectStatus "@baseboard_fab2_lib.baseboard_fab2(sch_1):page72_i32:vccd345(47)" )
			)
			( pin "U2D1.DB53"
				( objectStatus "@baseboard_fab2_lib.baseboard_fab2(sch_1):page72_i32:vccd345(48)" )
			)
			( pin "U2D1.EF45"
				( objectStatus "@baseboard_fab2_lib.baseboard_fab2(sch_1):page72_i32:vccd345(49)" )
			)
			( pin "U2D1.EE44"
				( objectStatus "@baseboard_fab2_lib.baseboard_fab2(sch_1):page72_i32:vccd345(50)" )
			)
			( pin "U2D1.BL14"
				( objectStatus "@baseboard_fab2_lib.baseboard_fab2(sch_1):page72_i33:cd_vcc_core(0)" )
			)
			( pin "U2D1.BK15"
				( objectStatus "@baseboard_fab2_lib.baseboard_fab2(sch_1):page72_i33:cd_vcc_core(1)" )
			)
			( pin "U2D1.BK13"
				( objectStatus "@baseboard_fab2_lib.baseboard_fab2(sch_1):page72_i33:cd_vcc_core(2)" )
			)
			( pin "U2D1.BJ14"
				( objectStatus "@baseboard_fab2_lib.baseboard_fab2(sch_1):page72_i33:cd_vcc_core(3)" )
			)
			( pin "U2D1.BJ12"
				( objectStatus "@baseboard_fab2_lib.baseboard_fab2(sch_1):page72_i33:cd_vcc_core(4)" )
			)
			( pin "U2D1.BH13"
				( objectStatus "@baseboard_fab2_lib.baseboard_fab2(sch_1):page72_i33:cd_vcc_core(5)" )
			)
			( pin "U2D1.BG14"
				( objectStatus "@baseboard_fab2_lib.baseboard_fab2(sch_1):page72_i33:cd_vcc_core(6)" )
			)
			( pin "U2D1.BG12"
				( objectStatus "@baseboard_fab2_lib.baseboard_fab2(sch_1):page72_i33:cd_vcc_core(7)" )
			)
			( pin "U2D1.BF13"
				( objectStatus "@baseboard_fab2_lib.baseboard_fab2(sch_1):page72_i33:cd_vcc_core(8)" )
			)
			( pin "U2D1.BF11"
				( objectStatus "@baseboard_fab2_lib.baseboard_fab2(sch_1):page72_i33:cd_vcc_core(9)" )
			)
			( pin "U2D1.BE14"
				( objectStatus "@baseboard_fab2_lib.baseboard_fab2(sch_1):page72_i33:cd_vcc_core(10)" )
			)
			( pin "U2D1.BE12"
				( objectStatus "@baseboard_fab2_lib.baseboard_fab2(sch_1):page72_i33:cd_vcc_core(11)" )
			)
			( pin "U2D1.BD13"
				( objectStatus "@baseboard_fab2_lib.baseboard_fab2(sch_1):page72_i33:cd_vcc_core(12)" )
			)
			( pin "U2D1.BT27"
				( objectStatus "@baseboard_fab2_lib.baseboard_fab2(sch_1):page72_i33:cd_vccin(0)" )
			)
			( pin "U2D1.BU26"
				( objectStatus "@baseboard_fab2_lib.baseboard_fab2(sch_1):page72_i33:cd_vccin(1)" )
			)
			( pin "U2D1.BV27"
				( objectStatus "@baseboard_fab2_lib.baseboard_fab2(sch_1):page72_i33:cd_vccin(2)" )
			)
			( pin "U2D1.BY27"
				( objectStatus "@baseboard_fab2_lib.baseboard_fab2(sch_1):page72_i33:cd_vccin(3)" )
			)
			( pin "U2D1.BV15"
				( objectStatus "@baseboard_fab2_lib.baseboard_fab2(sch_1):page72_i33:cd_vccp(0)" )
			)
			( pin "U2D1.BV13"
				( objectStatus "@baseboard_fab2_lib.baseboard_fab2(sch_1):page72_i33:cd_vccp(1)" )
			)
			( pin "U2D1.BV11"
				( objectStatus "@baseboard_fab2_lib.baseboard_fab2(sch_1):page72_i33:cd_vccp(2)" )
			)
			( pin "U2D1.BU14"
				( objectStatus "@baseboard_fab2_lib.baseboard_fab2(sch_1):page72_i33:cd_vccp(3)" )
			)
			( pin "U2D1.BU12"
				( objectStatus "@baseboard_fab2_lib.baseboard_fab2(sch_1):page72_i33:cd_vccp(4)" )
			)
			( pin "U2D1.BT15"
				( objectStatus "@baseboard_fab2_lib.baseboard_fab2(sch_1):page72_i33:cd_vccp(5)" )
			)
			( pin "U2D1.BT13"
				( objectStatus "@baseboard_fab2_lib.baseboard_fab2(sch_1):page72_i33:cd_vccp(6)" )
			)
			( pin "U2D1.BT11"
				( objectStatus "@baseboard_fab2_lib.baseboard_fab2(sch_1):page72_i33:cd_vccp(7)" )
			)
			( pin "U2D1.BR14"
				( objectStatus "@baseboard_fab2_lib.baseboard_fab2(sch_1):page72_i33:cd_vccp(8)" )
			)
			( pin "U2D1.BR12"
				( objectStatus "@baseboard_fab2_lib.baseboard_fab2(sch_1):page72_i33:cd_vccp(9)" )
			)
			( pin "U2D1.BP15"
				( objectStatus "@baseboard_fab2_lib.baseboard_fab2(sch_1):page72_i33:cd_vccp(10)" )
			)
			( pin "U2D1.BP13"
				( objectStatus "@baseboard_fab2_lib.baseboard_fab2(sch_1):page72_i33:cd_vccp(11)" )
			)
			( pin "U2D1.BP11"
				( objectStatus "@baseboard_fab2_lib.baseboard_fab2(sch_1):page72_i33:cd_vccp(12)" )
			)
			( pin "U2D1.BN14"
				( objectStatus "@baseboard_fab2_lib.baseboard_fab2(sch_1):page72_i33:cd_vccp(13)" )
			)
			( pin "U2D1.BN12"
				( objectStatus "@baseboard_fab2_lib.baseboard_fab2(sch_1):page72_i33:cd_vccp(14)" )
			)
			( pin "U2D1.BM11"
				( objectStatus "@baseboard_fab2_lib.baseboard_fab2(sch_1):page72_i33:cd_vccp(15)" )
			)
			( pin "U2D1.B11"
				( objectStatus "@baseboard_fab2_lib.baseboard_fab2(sch_1):page72_i33:cd_vpp(0)" )
			)
			( pin "U2D1.A12"
				( objectStatus "@baseboard_fab2_lib.baseboard_fab2(sch_1):page72_i33:cd_vpp(1)" )
			)
			( pin "U2D1.A10"
				( objectStatus "@baseboard_fab2_lib.baseboard_fab2(sch_1):page72_i33:cd_vpp(2)" )
			)
			( pin "U2D1.A8"
				( objectStatus "@baseboard_fab2_lib.baseboard_fab2(sch_1):page72_i33:cd_vpp(3)" )
			)
			( pin "U2D1.CY55"
				( objectStatus "@baseboard_fab2_lib.baseboard_fab2(sch_1):page72_i33:vcc33" )
			)
			( pin "U2D1.CM15"
				( objectStatus "@baseboard_fab2_lib.baseboard_fab2(sch_1):page72_i33:vccio(20)" )
			)
			( pin "U2D1.CL12"
				( objectStatus "@baseboard_fab2_lib.baseboard_fab2(sch_1):page72_i33:vccio(21)" )
			)
			( pin "U2D1.CK5"
				( objectStatus "@baseboard_fab2_lib.baseboard_fab2(sch_1):page72_i33:vccio(22)" )
			)
			( pin "U2D1.CV7"
				( objectStatus "@baseboard_fab2_lib.baseboard_fab2(sch_1):page72_i33:vccio(23)" )
			)
			( pin "U2D1.CH9"
				( objectStatus "@baseboard_fab2_lib.baseboard_fab2(sch_1):page72_i33:vccio(24)" )
			)
			( pin "U2D1.D7"
				( objectStatus "@baseboard_fab2_lib.baseboard_fab2(sch_1):page72_i33:vccio(25)" )
			)
			( pin "U2D1.CE18"
				( objectStatus "@baseboard_fab2_lib.baseboard_fab2(sch_1):page72_i33:vccio(26)" )
			)
			( pin "U2D1.CD9"
				( objectStatus "@baseboard_fab2_lib.baseboard_fab2(sch_1):page72_i33:vccio(27)" )
			)
			( pin "U2D1.CB17"
				( objectStatus "@baseboard_fab2_lib.baseboard_fab2(sch_1):page72_i33:vccio(28)" )
			)
			( pin "U2D1.CB13"
				( objectStatus "@baseboard_fab2_lib.baseboard_fab2(sch_1):page72_i33:vccio(29)" )
			)
			( pin "U2D1.BP25"
				( objectStatus "@baseboard_fab2_lib.baseboard_fab2(sch_1):page72_i33:vccio(30)" )
			)
			( pin "U2D1.BJ24"
				( objectStatus "@baseboard_fab2_lib.baseboard_fab2(sch_1):page72_i33:vccio(31)" )
			)
			( pin "U2D1.BF23"
				( objectStatus "@baseboard_fab2_lib.baseboard_fab2(sch_1):page72_i33:vccio(32)" )
			)
			( pin "U2D1.DA14"
				( objectStatus "@baseboard_fab2_lib.baseboard_fab2(sch_1):page72_i33:vccio(33)" )
			)
			( pin "U2D1.BB5"
				( objectStatus "@baseboard_fab2_lib.baseboard_fab2(sch_1):page72_i33:vccio(34)" )
			)
			( pin "U2D1.BA24"
				( objectStatus "@baseboard_fab2_lib.baseboard_fab2(sch_1):page72_i33:vccio(35)" )
			)
			( pin "U2D1.AY11"
				( objectStatus "@baseboard_fab2_lib.baseboard_fab2(sch_1):page72_i33:vccio(36)" )
			)
			( pin "U2D1.AW6"
				( objectStatus "@baseboard_fab2_lib.baseboard_fab2(sch_1):page72_i33:vccio(37)" )
			)
			( pin "U2D1.AT11"
				( objectStatus "@baseboard_fab2_lib.baseboard_fab2(sch_1):page72_i33:vccio(38)" )
			)
			( pin "U2D1.DD7"
				( objectStatus "@baseboard_fab2_lib.baseboard_fab2(sch_1):page72_i33:vccio(39)" )
			)
			( pin "U2D1.AN10"
				( objectStatus "@baseboard_fab2_lib.baseboard_fab2(sch_1):page72_i33:vccio(40)" )
			)
			( pin "U2D1.DF13"
				( objectStatus "@baseboard_fab2_lib.baseboard_fab2(sch_1):page72_i33:vccio(41)" )
			)
			( pin "U2D1.AH9"
				( objectStatus "@baseboard_fab2_lib.baseboard_fab2(sch_1):page72_i33:vccio(42)" )
			)
			( pin "U2D1.AC4"
				( objectStatus "@baseboard_fab2_lib.baseboard_fab2(sch_1):page72_i33:vccio(43)" )
			)
			( pin "U2D1.AC20"
				( objectStatus "@baseboard_fab2_lib.baseboard_fab2(sch_1):page72_i33:vccio(44)" )
			)
			( pin "U2D1.AA10"
				( objectStatus "@baseboard_fab2_lib.baseboard_fab2(sch_1):page72_i33:vccio(45)" )
			)
			( pin "U2D1.W6"
				( objectStatus "@baseboard_fab2_lib.baseboard_fab2(sch_1):page72_i33:vccio(46)" )
			)
			( pin "U2D1.W4"
				( objectStatus "@baseboard_fab2_lib.baseboard_fab2(sch_1):page72_i33:vccio(47)" )
			)
			( pin "U2D1.DF21"
				( objectStatus "@baseboard_fab2_lib.baseboard_fab2(sch_1):page72_i33:vccio(48)" )
			)
			( pin "U2D1.U14"
				( objectStatus "@baseboard_fab2_lib.baseboard_fab2(sch_1):page72_i33:vccio(49)" )
			)
			( pin "U2D1.T3"
				( objectStatus "@baseboard_fab2_lib.baseboard_fab2(sch_1):page72_i33:vccio(50)" )
			)
			( pin "U2D1.P5"
				( objectStatus "@baseboard_fab2_lib.baseboard_fab2(sch_1):page72_i33:vccio(51)" )
			)
			( pin "U2D1.M21"
				( objectStatus "@baseboard_fab2_lib.baseboard_fab2(sch_1):page72_i33:vccio(52)" )
			)
			( pin "U2D1.M11"
				( objectStatus "@baseboard_fab2_lib.baseboard_fab2(sch_1):page72_i33:vccio(53)" )
			)
			( pin "U2D1.DG8"
				( objectStatus "@baseboard_fab2_lib.baseboard_fab2(sch_1):page72_i33:vccio(54)" )
			)
			( pin "U2D1.DH7"
				( objectStatus "@baseboard_fab2_lib.baseboard_fab2(sch_1):page72_i33:vccio(55)" )
			)
			( pin "U2D1.L16"
				( objectStatus "@baseboard_fab2_lib.baseboard_fab2(sch_1):page72_i33:vccio(56)" )
			)
			( pin "U2D1.L14"
				( objectStatus "@baseboard_fab2_lib.baseboard_fab2(sch_1):page72_i33:vccio(57)" )
			)
			( pin "U2D1.J10"
				( objectStatus "@baseboard_fab2_lib.baseboard_fab2(sch_1):page72_i33:vccio(58)" )
			)
			( pin "U2D1.H13"
				( objectStatus "@baseboard_fab2_lib.baseboard_fab2(sch_1):page72_i33:vccio(59)" )
			)
			( pin "U2D1.DJ16"
				( objectStatus "@baseboard_fab2_lib.baseboard_fab2(sch_1):page72_i33:vccio(60)" )
			)
			( pin "U2D1.DM17"
				( objectStatus "@baseboard_fab2_lib.baseboard_fab2(sch_1):page72_i33:vccio(61)" )
			)
			( pin "U2D1.DN8"
				( objectStatus "@baseboard_fab2_lib.baseboard_fab2(sch_1):page72_i33:vccio(62)" )
			)
			( pin "U2D1.DP19"
				( objectStatus "@baseboard_fab2_lib.baseboard_fab2(sch_1):page72_i33:vccio(63)" )
			)
			( pin "U2D1.DR10"
				( objectStatus "@baseboard_fab2_lib.baseboard_fab2(sch_1):page72_i33:vccio(64)" )
			)
			( pin "U2D1.DR2"
				( objectStatus "@baseboard_fab2_lib.baseboard_fab2(sch_1):page72_i33:vccio(65)" )
			)
			( pin "U2D1.DU20"
				( objectStatus "@baseboard_fab2_lib.baseboard_fab2(sch_1):page72_i33:vccio(66)" )
			)
			( pin "U2D1.EA12"
				( objectStatus "@baseboard_fab2_lib.baseboard_fab2(sch_1):page72_i33:vccio(67)" )
			)
			( pin "U2D1.EB15"
				( objectStatus "@baseboard_fab2_lib.baseboard_fab2(sch_1):page72_i33:vccio(68)" )
			)
			( pin "U2D1.J2"
				( objectStatus "@baseboard_fab2_lib.baseboard_fab2(sch_1):page72_i33:vccio(69)" )
			)
			( pin "U2D1.K15"
				( objectStatus "@baseboard_fab2_lib.baseboard_fab2(sch_1):page72_i33:vccio(70)" )
			)
			( pin "U2D1.M7"
				( objectStatus "@baseboard_fab2_lib.baseboard_fab2(sch_1):page72_i33:vccio(71)" )
			)
			( pin "U2D1.M9"
				( objectStatus "@baseboard_fab2_lib.baseboard_fab2(sch_1):page72_i33:vccio(72)" )
			)
			( pin "U2D1.N18"
				( objectStatus "@baseboard_fab2_lib.baseboard_fab2(sch_1):page72_i33:vccio(73)" )
			)
			( pin "U2D1.W10"
				( objectStatus "@baseboard_fab2_lib.baseboard_fab2(sch_1):page72_i33:vccio(74)" )
			)
			( pin "U2D1.BC26"
				( objectStatus "@baseboard_fab2_lib.baseboard_fab2(sch_1):page72_i33:vccio(75)" )
			)
			( pin "U2D1.BB27"
				( objectStatus "@baseboard_fab2_lib.baseboard_fab2(sch_1):page72_i33:vccio(76)" )
			)
			( pin "U2D1.BA26"
				( objectStatus "@baseboard_fab2_lib.baseboard_fab2(sch_1):page72_i33:vccio(77)" )
			)
			( pin "U2D1.AY27"
				( objectStatus "@baseboard_fab2_lib.baseboard_fab2(sch_1):page72_i33:vccio(78)" )
			)
			( pin "U2D1.AW26"
				( objectStatus "@baseboard_fab2_lib.baseboard_fab2(sch_1):page72_i33:vccio(79)" )
			)
			( pin "U2D1.AV27"
				( objectStatus "@baseboard_fab2_lib.baseboard_fab2(sch_1):page72_i33:vccio(80)" )
			)
			( pin "U2D1.CF27"
				( objectStatus "@baseboard_fab2_lib.baseboard_fab2(sch_1):page72_i33:vccio(81)" )
			)
			( pin "U2D1.CD27"
				( objectStatus "@baseboard_fab2_lib.baseboard_fab2(sch_1):page72_i33:vccio(82)" )
			)
			( pin "U2D1.CC26"
				( objectStatus "@baseboard_fab2_lib.baseboard_fab2(sch_1):page72_i33:vccio(83)" )
			)
			( pin "U2D1.CJ28"
				( objectStatus "@baseboard_fab2_lib.baseboard_fab2(sch_1):page72_i33:vccio(84)" )
			)
			( pin "U2D1.CH27"
				( objectStatus "@baseboard_fab2_lib.baseboard_fab2(sch_1):page72_i33:vccio(85)" )
			)
			( pin "U2D1.BM27"
				( objectStatus "@baseboard_fab2_lib.baseboard_fab2(sch_1):page72_i33:vccio(86)" )
			)
			( pin "U2D1.BL26"
				( objectStatus "@baseboard_fab2_lib.baseboard_fab2(sch_1):page72_i33:vccio(87)" )
			)
			( pin "U2D1.BK27"
				( objectStatus "@baseboard_fab2_lib.baseboard_fab2(sch_1):page72_i33:vccio(88)" )
			)
			( pin "U2D1.BK25"
				( objectStatus "@baseboard_fab2_lib.baseboard_fab2(sch_1):page72_i33:vccio(89)" )
			)
			( pin "U2D1.BJ26"
				( objectStatus "@baseboard_fab2_lib.baseboard_fab2(sch_1):page72_i33:vccio(90)" )
			)
			( pin "U2D1.BH27"
				( objectStatus "@baseboard_fab2_lib.baseboard_fab2(sch_1):page72_i33:vccio(91)" )
			)
			( pin "U2D1.BH25"
				( objectStatus "@baseboard_fab2_lib.baseboard_fab2(sch_1):page72_i33:vccio(92)" )
			)
			( pin "U2D1.BG26"
				( objectStatus "@baseboard_fab2_lib.baseboard_fab2(sch_1):page72_i33:vccio(93)" )
			)
			( pin "U2D1.BF27"
				( objectStatus "@baseboard_fab2_lib.baseboard_fab2(sch_1):page72_i33:vccio(94)" )
			)
			( pin "U2D1.AE36"
				( objectStatus "@baseboard_fab2_lib.baseboard_fab2(sch_1):page72_i33:vccio(95)" )
			)
			( pin "U2D1.AD37"
				( objectStatus "@baseboard_fab2_lib.baseboard_fab2(sch_1):page72_i33:vccio(96)" )
			)
			( pin "U2D1.AC36"
				( objectStatus "@baseboard_fab2_lib.baseboard_fab2(sch_1):page72_i33:vccio(97)" )
			)
			( pin "U2D1.AF35"
				( objectStatus "@baseboard_fab2_lib.baseboard_fab2(sch_1):page72_i33:vccio(98)" )
			)
			( pin "U2D1.AD35"
				( objectStatus "@baseboard_fab2_lib.baseboard_fab2(sch_1):page72_i33:vccio(99)" )
			)
			( pin "U2D1.AE34"
				( objectStatus "@baseboard_fab2_lib.baseboard_fab2(sch_1):page72_i33:vccio(100)" )
			)
			( pin "U2D1.AG34"
				( objectStatus "@baseboard_fab2_lib.baseboard_fab2(sch_1):page72_i33:vccio(101)" )
			)
			( pin "U2D1.AM29"
				( objectStatus "@baseboard_fab2_lib.baseboard_fab2(sch_1):page72_i33:vccio(102)" )
			)
			( pin "U2D1.AL28"
				( objectStatus "@baseboard_fab2_lib.baseboard_fab2(sch_1):page72_i33:vccio(103)" )
			)
			( pin "U2D1.AR28"
				( objectStatus "@baseboard_fab2_lib.baseboard_fab2(sch_1):page72_i33:vccio(104)" )
			)
			( pin "U2D1.CJ66"
				( objectStatus "@baseboard_fab2_lib.baseboard_fab2(sch_1):page72_i33:vccsa(0)" )
			)
			( pin "U2D1.CJ64"
				( objectStatus "@baseboard_fab2_lib.baseboard_fab2(sch_1):page72_i33:vccsa(1)" )
			)
			( pin "U2D1.CH75"
				( objectStatus "@baseboard_fab2_lib.baseboard_fab2(sch_1):page72_i33:vccsa(2)" )
			)
			( pin "U2D1.CH65"
				( objectStatus "@baseboard_fab2_lib.baseboard_fab2(sch_1):page72_i33:vccsa(3)" )
			)
			( pin "U2D1.CG74"
				( objectStatus "@baseboard_fab2_lib.baseboard_fab2(sch_1):page72_i33:vccsa(4)" )
			)
			( pin "U2D1.CG66"
				( objectStatus "@baseboard_fab2_lib.baseboard_fab2(sch_1):page72_i33:vccsa(5)" )
			)
			( pin "U2D1.CG64"
				( objectStatus "@baseboard_fab2_lib.baseboard_fab2(sch_1):page72_i33:vccsa(6)" )
			)
			( pin "U2D1.CF75"
				( objectStatus "@baseboard_fab2_lib.baseboard_fab2(sch_1):page72_i33:vccsa(7)" )
			)
			( pin "U2D1.CF73"
				( objectStatus "@baseboard_fab2_lib.baseboard_fab2(sch_1):page72_i33:vccsa(8)" )
			)
			( pin "U2D1.CF67"
				( objectStatus "@baseboard_fab2_lib.baseboard_fab2(sch_1):page72_i33:vccsa(9)" )
			)
			( pin "U2D1.CF65"
				( objectStatus "@baseboard_fab2_lib.baseboard_fab2(sch_1):page72_i33:vccsa(10)" )
			)
			( pin "U2D1.CE74"
				( objectStatus "@baseboard_fab2_lib.baseboard_fab2(sch_1):page72_i33:vccsa(11)" )
			)
			( pin "U2D1.CE72"
				( objectStatus "@baseboard_fab2_lib.baseboard_fab2(sch_1):page72_i33:vccsa(12)" )
			)
			( pin "U2D1.CE68"
				( objectStatus "@baseboard_fab2_lib.baseboard_fab2(sch_1):page72_i33:vccsa(13)" )
			)
			( pin "U2D1.CE66"
				( objectStatus "@baseboard_fab2_lib.baseboard_fab2(sch_1):page72_i33:vccsa(14)" )
			)
			( pin "U2D1.CE64"
				( objectStatus "@baseboard_fab2_lib.baseboard_fab2(sch_1):page72_i33:vccsa(15)" )
			)
			( pin "U2D1.CD71"
				( objectStatus "@baseboard_fab2_lib.baseboard_fab2(sch_1):page72_i33:vccsa(16)" )
			)
			( pin "U2D1.CD69"
				( objectStatus "@baseboard_fab2_lib.baseboard_fab2(sch_1):page72_i33:vccsa(17)" )
			)
			( pin "U2D1.CD67"
				( objectStatus "@baseboard_fab2_lib.baseboard_fab2(sch_1):page72_i33:vccsa(18)" )
			)
			( pin "U2D1.CD65"
				( objectStatus "@baseboard_fab2_lib.baseboard_fab2(sch_1):page72_i33:vccsa(19)" )
			)
			( pin "U2D1.CC70"
				( objectStatus "@baseboard_fab2_lib.baseboard_fab2(sch_1):page72_i33:vccsa(20)" )
			)
			( pin "U2D1.CC68"
				( objectStatus "@baseboard_fab2_lib.baseboard_fab2(sch_1):page72_i33:vccsa(21)" )
			)
			( pin "U2D1.CC66"
				( objectStatus "@baseboard_fab2_lib.baseboard_fab2(sch_1):page72_i33:vccsa(22)" )
			)
			( pin "U2D1.CB69"
				( objectStatus "@baseboard_fab2_lib.baseboard_fab2(sch_1):page72_i33:vccsa(23)" )
			)
			( pin "U2D1.CB67"
				( objectStatus "@baseboard_fab2_lib.baseboard_fab2(sch_1):page72_i33:vccsa(24)" )
			)
			( pin "U2D1.CB65"
				( objectStatus "@baseboard_fab2_lib.baseboard_fab2(sch_1):page72_i33:vccsa(25)" )
			)
			( pin "U2D1.BN16"
				( objectStatus "@baseboard_fab2_lib.baseboard_fab2(sch_1):page73_i107:cd_vcc_core_sense" )
			)
			( pin "U2D1.BU16"
				( objectStatus "@baseboard_fab2_lib.baseboard_fab2(sch_1):page73_i107:cd_vccp_sense(0)" )
			)
			( pin "U2D1.BT17"
				( objectStatus "@baseboard_fab2_lib.baseboard_fab2(sch_1):page73_i107:cd_vccp_sense(1)" )
			)
			( pin "U2D1.BL16"
				( objectStatus "@baseboard_fab2_lib.baseboard_fab2(sch_1):page73_i107:cd_vss_vcc_core_sense" )
			)
			( pin "U2D1.EF83"
				( objectStatus "@baseboard_fab2_lib.baseboard_fab2(sch_1):page73_i107:rsvd(0)" )
			)
			( pin "U2D1.EF81"
				( objectStatus "@baseboard_fab2_lib.baseboard_fab2(sch_1):page73_i107:rsvd(1)" )
			)
			( pin "U2D1.EF77"
				( objectStatus "@baseboard_fab2_lib.baseboard_fab2(sch_1):page73_i107:rsvd(2)" )
			)
			( pin "U2D1.EF47"
				( objectStatus "@baseboard_fab2_lib.baseboard_fab2(sch_1):page73_i107:rsvd(3)" )
			)
			( pin "U2D1.EE84"
				( objectStatus "@baseboard_fab2_lib.baseboard_fab2(sch_1):page73_i107:rsvd(4)" )
			)
			( pin "U2D1.EE82"
				( objectStatus "@baseboard_fab2_lib.baseboard_fab2(sch_1):page73_i107:rsvd(5)" )
			)
			( pin "U2D1.EE6"
				( objectStatus "@baseboard_fab2_lib.baseboard_fab2(sch_1):page73_i107:rsvd(6)" )
			)
			( pin "U2D1.EE46"
				( objectStatus "@baseboard_fab2_lib.baseboard_fab2(sch_1):page73_i107:rsvd(7)" )
			)
			( pin "U2D1.EE16"
				( objectStatus "@baseboard_fab2_lib.baseboard_fab2(sch_1):page73_i107:rsvd(8)" )
			)
			( pin "U2D1.ED83"
				( objectStatus "@baseboard_fab2_lib.baseboard_fab2(sch_1):page73_i107:rsvd(9)" )
			)
			( pin "U2D1.ED5"
				( objectStatus "@baseboard_fab2_lib.baseboard_fab2(sch_1):page73_i107:rsvd(10)" )
			)
			( pin "U2D1.ED45"
				( objectStatus "@baseboard_fab2_lib.baseboard_fab2(sch_1):page73_i107:rsvd(11)" )
			)
			( pin "U2D1.EC84"
				( objectStatus "@baseboard_fab2_lib.baseboard_fab2(sch_1):page73_i107:rsvd(12)" )
			)
			( pin "U2D1.EC44"
				( objectStatus "@baseboard_fab2_lib.baseboard_fab2(sch_1):page73_i107:rsvd(13)" )
			)
			( pin "U2D1.EC4"
				( objectStatus "@baseboard_fab2_lib.baseboard_fab2(sch_1):page73_i107:rsvd(14)" )
			)
			( pin "U2D1.EC16"
				( objectStatus "@baseboard_fab2_lib.baseboard_fab2(sch_1):page73_i107:rsvd(15)" )
			)
			( pin "U2D1.EB85"
				( objectStatus "@baseboard_fab2_lib.baseboard_fab2(sch_1):page73_i107:rsvd(16)" )
			)
			( pin "U2D1.EB5"
				( objectStatus "@baseboard_fab2_lib.baseboard_fab2(sch_1):page73_i107:rsvd(17)" )
			)
			( pin "U2D1.EB3"
				( objectStatus "@baseboard_fab2_lib.baseboard_fab2(sch_1):page73_i107:rsvd(18)" )
			)
			( pin "U2D1.EA44"
				( objectStatus "@baseboard_fab2_lib.baseboard_fab2(sch_1):page73_i107:rsvd(19)" )
			)
			( pin "U2D1.EA4"
				( objectStatus "@baseboard_fab2_lib.baseboard_fab2(sch_1):page73_i107:rsvd(20)" )
			)
			( pin "U2D1.DY3"
				( objectStatus "@baseboard_fab2_lib.baseboard_fab2(sch_1):page73_i107:rsvd(21)" )
			)
			( pin "U2D1.DW46"
				( objectStatus "@baseboard_fab2_lib.baseboard_fab2(sch_1):page73_i107:rsvd(22)" )
			)
			( pin "U2D1.DW44"
				( objectStatus "@baseboard_fab2_lib.baseboard_fab2(sch_1):page73_i107:rsvd(23)" )
			)
			( pin "U2D1.DV71"
				( objectStatus "@baseboard_fab2_lib.baseboard_fab2(sch_1):page73_i107:rsvd(24)" )
			)
			( pin "U2D1.DV61"
				( objectStatus "@baseboard_fab2_lib.baseboard_fab2(sch_1):page73_i107:rsvd(25)" )
			)
			( pin "U2D1.DU44"
				( objectStatus "@baseboard_fab2_lib.baseboard_fab2(sch_1):page73_i107:rsvd(26)" )
			)
			( pin "U2D1.DT71"
				( objectStatus "@baseboard_fab2_lib.baseboard_fab2(sch_1):page73_i107:rsvd(27)" )
			)
			( pin "U2D1.DR44"
				( objectStatus "@baseboard_fab2_lib.baseboard_fab2(sch_1):page73_i107:rsvd(28)" )
			)
			( pin "U2D1.DP65"
				( objectStatus "@baseboard_fab2_lib.baseboard_fab2(sch_1):page73_i107:rsvd(29)" )
			)
			( pin "U2D1.DP17"
				( objectStatus "@baseboard_fab2_lib.baseboard_fab2(sch_1):page73_i107:rsvd(30)" )
			)
			( pin "U2D1.DN66"
				( objectStatus "@baseboard_fab2_lib.baseboard_fab2(sch_1):page73_i107:rsvd(31)" )
			)
			( pin "U2D1.DN62"
				( objectStatus "@baseboard_fab2_lib.baseboard_fab2(sch_1):page73_i107:rsvd(32)" )
			)
			( pin "U2D1.DM67"
				( objectStatus "@baseboard_fab2_lib.baseboard_fab2(sch_1):page73_i107:rsvd(33)" )
			)
			( pin "U2D1.DL66"
				( objectStatus "@baseboard_fab2_lib.baseboard_fab2(sch_1):page73_i107:rsvd(34)" )
			)
			( pin "U2D1.DL38"
				( objectStatus "@baseboard_fab2_lib.baseboard_fab2(sch_1):page73_i107:rsvd(35)" )
			)
			( pin "U2D1.DK67"
				( objectStatus "@baseboard_fab2_lib.baseboard_fab2(sch_1):page73_i107:rsvd(36)" )
			)
			( pin "U2D1.DK65"
				( objectStatus "@baseboard_fab2_lib.baseboard_fab2(sch_1):page73_i107:rsvd(37)" )
			)
			( pin "U2D1.DK37"
				( objectStatus "@baseboard_fab2_lib.baseboard_fab2(sch_1):page73_i107:rsvd(38)" )
			)
			( pin "U2D1.DK15"
				( objectStatus "@baseboard_fab2_lib.baseboard_fab2(sch_1):page73_i107:rsvd(39)" )
			)
			( pin "U2D1.DJ66"
				( objectStatus "@baseboard_fab2_lib.baseboard_fab2(sch_1):page73_i107:rsvd(40)" )
			)
			( pin "U2D1.DJ36"
				( objectStatus "@baseboard_fab2_lib.baseboard_fab2(sch_1):page73_i107:rsvd(41)" )
			)
			( pin "U2D1.DH65"
				( objectStatus "@baseboard_fab2_lib.baseboard_fab2(sch_1):page73_i107:rsvd(42)" )
			)
			( pin "U2D1.DG64"
				( objectStatus "@baseboard_fab2_lib.baseboard_fab2(sch_1):page73_i107:rsvd(43)" )
			)
			( pin "U2D1.DG36"
				( objectStatus "@baseboard_fab2_lib.baseboard_fab2(sch_1):page73_i107:rsvd(44)" )
			)
			( pin "U2D1.DD51"
				( objectStatus "@baseboard_fab2_lib.baseboard_fab2(sch_1):page73_i107:rsvd(45)" )
			)
			( pin "U2D1.DC52"
				( objectStatus "@baseboard_fab2_lib.baseboard_fab2(sch_1):page73_i107:rsvd(46)" )
			)
			( pin "U2D1.DC46"
				( objectStatus "@baseboard_fab2_lib.baseboard_fab2(sch_1):page73_i107:rsvd(47)" )
			)
			( pin "U2D1.DA56"
				( objectStatus "@baseboard_fab2_lib.baseboard_fab2(sch_1):page73_i107:rsvd(48)" )
			)
			( pin "U2D1.DA54"
				( objectStatus "@baseboard_fab2_lib.baseboard_fab2(sch_1):page73_i107:rsvd(49)" )
			)
			( pin "U2D1.DA52"
				( objectStatus "@baseboard_fab2_lib.baseboard_fab2(sch_1):page73_i107:rsvd(50)" )
			)
			( pin "U2D1.DA40"
				( objectStatus "@baseboard_fab2_lib.baseboard_fab2(sch_1):page73_i107:rsvd(51)" )
			)
			( pin "U2D1.DA24"
				( objectStatus "@baseboard_fab2_lib.baseboard_fab2(sch_1):page73_i107:rsvd(52)" )
			)
			( pin "U2D1.CY73"
				( objectStatus "@baseboard_fab2_lib.baseboard_fab2(sch_1):page73_i107:rsvd(53)" )
			)
			( pin "U2D1.CY63"
				( objectStatus "@baseboard_fab2_lib.baseboard_fab2(sch_1):page73_i107:rsvd(54)" )
			)
			( pin "U2D1.CY57"
				( objectStatus "@baseboard_fab2_lib.baseboard_fab2(sch_1):page73_i107:rsvd(55)" )
			)
			( pin "U2D1.CY53"
				( objectStatus "@baseboard_fab2_lib.baseboard_fab2(sch_1):page73_i107:rsvd(56)" )
			)
			( pin "U2D1.CY39"
				( objectStatus "@baseboard_fab2_lib.baseboard_fab2(sch_1):page73_i107:rsvd(57)" )
			)
			( pin "U2D1.CY25"
				( objectStatus "@baseboard_fab2_lib.baseboard_fab2(sch_1):page73_i107:rsvd(58)" )
			)
			( pin "U2D1.CY23"
				( objectStatus "@baseboard_fab2_lib.baseboard_fab2(sch_1):page73_i107:rsvd(59)" )
			)
			( pin "U2D1.CW62"
				( objectStatus "@baseboard_fab2_lib.baseboard_fab2(sch_1):page73_i107:rsvd(60)" )
			)
			( pin "U2D1.CW60"
				( objectStatus "@baseboard_fab2_lib.baseboard_fab2(sch_1):page73_i107:rsvd(61)" )
			)
			( pin "U2D1.CW24"
				( objectStatus "@baseboard_fab2_lib.baseboard_fab2(sch_1):page73_i107:rsvd(62)" )
			)
			( pin "U2D1.CW22"
				( objectStatus "@baseboard_fab2_lib.baseboard_fab2(sch_1):page73_i107:rsvd(63)" )
			)
			( pin "U2D1.CV69"
				( objectStatus "@baseboard_fab2_lib.baseboard_fab2(sch_1):page73_i107:rsvd(64)" )
			)
			( pin "U2D1.CV23"
				( objectStatus "@baseboard_fab2_lib.baseboard_fab2(sch_1):page73_i107:rsvd(65)" )
			)
			( pin "U2D1.CU60"
				( objectStatus "@baseboard_fab2_lib.baseboard_fab2(sch_1):page73_i107:rsvd(66)" )
			)
			( pin "U2D1.CU6"
				( objectStatus "@baseboard_fab2_lib.baseboard_fab2(sch_1):page73_i107:rsvd(67)" )
			)
			( pin "U2D1.CU24"
				( objectStatus "@baseboard_fab2_lib.baseboard_fab2(sch_1):page73_i107:rsvd(68)" )
			)
			( pin "U2D1.CT69"
				( objectStatus "@baseboard_fab2_lib.baseboard_fab2(sch_1):page73_i107:rsvd(69)" )
			)
			( pin "U2D1.CT5"
				( objectStatus "@baseboard_fab2_lib.baseboard_fab2(sch_1):page73_i107:rsvd(70)" )
			)
			( pin "U2D1.CT23"
				( objectStatus "@baseboard_fab2_lib.baseboard_fab2(sch_1):page73_i107:rsvd(71)" )
			)
			( pin "U2D1.CR60"
				( objectStatus "@baseboard_fab2_lib.baseboard_fab2(sch_1):page73_i107:rsvd(72)" )
			)
			( pin "U2D1.CP31"
				( objectStatus "@baseboard_fab2_lib.baseboard_fab2(sch_1):page73_i107:rsvd(73)" )
			)
			( pin "U2D1.CP23"
				( objectStatus "@baseboard_fab2_lib.baseboard_fab2(sch_1):page73_i107:rsvd(74)" )
			)
			( pin "U2D1.CN28"
				( objectStatus "@baseboard_fab2_lib.baseboard_fab2(sch_1):page73_i107:rsvd(75)" )
			)
			( pin "U2D1.CN24"
				( objectStatus "@baseboard_fab2_lib.baseboard_fab2(sch_1):page73_i107:rsvd(76)" )
			)
			( pin "U2D1.CN22"
				( objectStatus "@baseboard_fab2_lib.baseboard_fab2(sch_1):page73_i107:rsvd(77)" )
			)
			( pin "U2D1.CM25"
				( objectStatus "@baseboard_fab2_lib.baseboard_fab2(sch_1):page73_i107:rsvd(78)" )
			)
			( pin "U2D1.CM23"
				( objectStatus "@baseboard_fab2_lib.baseboard_fab2(sch_1):page73_i107:rsvd(79)" )
			)
			( pin "U2D1.CL26"
				( objectStatus "@baseboard_fab2_lib.baseboard_fab2(sch_1):page73_i107:rsvd(80)" )
			)
			( pin "U2D1.EE10"
				( objectStatus "@baseboard_fab2_lib.baseboard_fab2(sch_1):page73_i107:vccio(0)" )
			)
			( pin "U2D1.AE10"
				( objectStatus "@baseboard_fab2_lib.baseboard_fab2(sch_1):page73_i107:vccio(1)" )
			)
			( pin "U2D1.AF5"
				( objectStatus "@baseboard_fab2_lib.baseboard_fab2(sch_1):page73_i107:vccio(2)" )
			)
			( pin "U2D1.DV11"
				( objectStatus "@baseboard_fab2_lib.baseboard_fab2(sch_1):page73_i107:vccio(3)" )
			)
			( pin "U2D1.AM5"
				( objectStatus "@baseboard_fab2_lib.baseboard_fab2(sch_1):page73_i107:vccio(4)" )
			)
			( pin "U2D1.AT5"
				( objectStatus "@baseboard_fab2_lib.baseboard_fab2(sch_1):page73_i107:vccio(5)" )
			)
			( pin "U2D1.AT7"
				( objectStatus "@baseboard_fab2_lib.baseboard_fab2(sch_1):page73_i107:vccio(6)" )
			)
			( pin "U2D1.BE24"
				( objectStatus "@baseboard_fab2_lib.baseboard_fab2(sch_1):page73_i107:vccio(7)" )
			)
			( pin "U2D1.DK21"
				( objectStatus "@baseboard_fab2_lib.baseboard_fab2(sch_1):page73_i107:vccio(8)" )
			)
			( pin "U2D1.CF5"
				( objectStatus "@baseboard_fab2_lib.baseboard_fab2(sch_1):page73_i107:vccio(9)" )
			)
			( pin "U2D1.CG14"
				( objectStatus "@baseboard_fab2_lib.baseboard_fab2(sch_1):page73_i107:vccio(10)" )
			)
			( pin "U2D1.CL20"
				( objectStatus "@baseboard_fab2_lib.baseboard_fab2(sch_1):page73_i107:vccio(11)" )
			)
			( pin "U2D1.CP13"
				( objectStatus "@baseboard_fab2_lib.baseboard_fab2(sch_1):page73_i107:vccio(12)" )
			)
			( pin "U2D1.DE14"
				( objectStatus "@baseboard_fab2_lib.baseboard_fab2(sch_1):page73_i107:vccio(13)" )
			)
			( pin "U2D1.DC18"
				( objectStatus "@baseboard_fab2_lib.baseboard_fab2(sch_1):page73_i107:vccio(14)" )
			)
			( pin "U2D1.CY17"
				( objectStatus "@baseboard_fab2_lib.baseboard_fab2(sch_1):page73_i107:vccio(15)" )
			)
			( pin "U2D1.CU18"
				( objectStatus "@baseboard_fab2_lib.baseboard_fab2(sch_1):page73_i107:vccio(16)" )
			)
			( pin "U2D1.CV21"
				( objectStatus "@baseboard_fab2_lib.baseboard_fab2(sch_1):page73_i107:vccio(17)" )
			)
			( pin "U2D1.CU12"
				( objectStatus "@baseboard_fab2_lib.baseboard_fab2(sch_1):page73_i107:vccio(18)" )
			)
			( pin "U2D1.CN6"
				( objectStatus "@baseboard_fab2_lib.baseboard_fab2(sch_1):page73_i107:vccio(19)" )
			)
			( pin "U2D1.BH5"
				( objectStatus "@baseboard_fab2_lib.baseboard_fab2(sch_1):page73_i107:vccio_sense" )
			)
			( pin "U2D1.CE76"
				( objectStatus "@baseboard_fab2_lib.baseboard_fab2(sch_1):page73_i107:vccsa_sense" )
			)
			( pin "U2D1.BF5"
				( objectStatus "@baseboard_fab2_lib.baseboard_fab2(sch_1):page73_i107:vss_vccio_sense" )
			)
			( pin "U2D1.CG76"
				( objectStatus "@baseboard_fab2_lib.baseboard_fab2(sch_1):page73_i107:vss_vccsa_sense" )
			)
			( pin "U2D1.J74"
				( objectStatus "@baseboard_fab2_lib.baseboard_fab2(sch_1):page74_i20:vss(1094)" )
			)
			( pin "U2D1.J72"
				( objectStatus "@baseboard_fab2_lib.baseboard_fab2(sch_1):page74_i20:vss(1095)" )
			)
			( pin "U2D1.J40"
				( objectStatus "@baseboard_fab2_lib.baseboard_fab2(sch_1):page74_i20:vss(1096)" )
			)
			( pin "U2D1.J38"
				( objectStatus "@baseboard_fab2_lib.baseboard_fab2(sch_1):page74_i20:vss(1097)" )
			)
			( pin "U2D1.J34"
				( objectStatus "@baseboard_fab2_lib.baseboard_fab2(sch_1):page74_i20:vss(1098)" )
			)
			( pin "U2D1.J32"
				( objectStatus "@baseboard_fab2_lib.baseboard_fab2(sch_1):page74_i20:vss(1099)" )
			)
			( pin "U2D1.J28"
				( objectStatus "@baseboard_fab2_lib.baseboard_fab2(sch_1):page74_i20:vss(1100)" )
			)
			( pin "U2D1.J26"
				( objectStatus "@baseboard_fab2_lib.baseboard_fab2(sch_1):page74_i20:vss(1101)" )
			)
			( pin "U2D1.J22"
				( objectStatus "@baseboard_fab2_lib.baseboard_fab2(sch_1):page74_i20:vss(1102)" )
			)
			( pin "U2D1.J14"
				( objectStatus "@baseboard_fab2_lib.baseboard_fab2(sch_1):page74_i20:vss(1103)" )
			)
			( pin "U2D1.J12"
				( objectStatus "@baseboard_fab2_lib.baseboard_fab2(sch_1):page74_i20:vss(1104)" )
			)
			( pin "U2D1.J4"
				( objectStatus "@baseboard_fab2_lib.baseboard_fab2(sch_1):page74_i20:vss(1105)" )
			)
			( pin "U2D1.DN44"
				( objectStatus "@baseboard_fab2_lib.baseboard_fab2(sch_1):page74_i20:vss(1106)" )
			)
			( pin "U2D1.H75"
				( objectStatus "@baseboard_fab2_lib.baseboard_fab2(sch_1):page74_i20:vss(1107)" )
			)
			( pin "U2D1.H71"
				( objectStatus "@baseboard_fab2_lib.baseboard_fab2(sch_1):page74_i20:vss(1108)" )
			)
			( pin "U2D1.H65"
				( objectStatus "@baseboard_fab2_lib.baseboard_fab2(sch_1):page74_i20:vss(1109)" )
			)
			( pin "U2D1.H41"
				( objectStatus "@baseboard_fab2_lib.baseboard_fab2(sch_1):page74_i20:vss(1110)" )
			)
			( pin "U2D1.H39"
				( objectStatus "@baseboard_fab2_lib.baseboard_fab2(sch_1):page74_i20:vss(1111)" )
			)
			( pin "U2D1.H37"
				( objectStatus "@baseboard_fab2_lib.baseboard_fab2(sch_1):page74_i20:vss(1112)" )
			)
			( pin "U2D1.H35"
				( objectStatus "@baseboard_fab2_lib.baseboard_fab2(sch_1):page74_i20:vss(1113)" )
			)
			( pin "U2D1.H33"
				( objectStatus "@baseboard_fab2_lib.baseboard_fab2(sch_1):page74_i20:vss(1114)" )
			)
			( pin "U2D1.H31"
				( objectStatus "@baseboard_fab2_lib.baseboard_fab2(sch_1):page74_i20:vss(1115)" )
			)
			( pin "U2D1.H29"
				( objectStatus "@baseboard_fab2_lib.baseboard_fab2(sch_1):page74_i20:vss(1116)" )
			)
			( pin "U2D1.H27"
				( objectStatus "@baseboard_fab2_lib.baseboard_fab2(sch_1):page74_i20:vss(1117)" )
			)
			( pin "U2D1.H25"
				( objectStatus "@baseboard_fab2_lib.baseboard_fab2(sch_1):page74_i20:vss(1118)" )
			)
			( pin "U2D1.H11"
				( objectStatus "@baseboard_fab2_lib.baseboard_fab2(sch_1):page74_i20:vss(1119)" )
			)
			( pin "U2D1.H3"
				( objectStatus "@baseboard_fab2_lib.baseboard_fab2(sch_1):page74_i20:vss(1120)" )
			)
			( pin "U2D1.G82"
				( objectStatus "@baseboard_fab2_lib.baseboard_fab2(sch_1):page74_i20:vss(1121)" )
			)
			( pin "U2D1.G80"
				( objectStatus "@baseboard_fab2_lib.baseboard_fab2(sch_1):page74_i20:vss(1122)" )
			)
			( pin "U2D1.G78"
				( objectStatus "@baseboard_fab2_lib.baseboard_fab2(sch_1):page74_i20:vss(1123)" )
			)
			( pin "U2D1.G76"
				( objectStatus "@baseboard_fab2_lib.baseboard_fab2(sch_1):page74_i20:vss(1124)" )
			)
			( pin "U2D1.G70"
				( objectStatus "@baseboard_fab2_lib.baseboard_fab2(sch_1):page74_i20:vss(1125)" )
			)
			( pin "U2D1.G66"
				( objectStatus "@baseboard_fab2_lib.baseboard_fab2(sch_1):page74_i20:vss(1126)" )
			)
			( pin "U2D1.G42"
				( objectStatus "@baseboard_fab2_lib.baseboard_fab2(sch_1):page74_i20:vss(1127)" )
			)
			( pin "U2D1.G38"
				( objectStatus "@baseboard_fab2_lib.baseboard_fab2(sch_1):page74_i20:vss(1128)" )
			)
			( pin "U2D1.G36"
				( objectStatus "@baseboard_fab2_lib.baseboard_fab2(sch_1):page74_i20:vss(1129)" )
			)
			( pin "U2D1.G32"
				( objectStatus "@baseboard_fab2_lib.baseboard_fab2(sch_1):page74_i20:vss(1130)" )
			)
			( pin "U2D1.G30"
				( objectStatus "@baseboard_fab2_lib.baseboard_fab2(sch_1):page74_i20:vss(1131)" )
			)
			( pin "U2D1.G26"
				( objectStatus "@baseboard_fab2_lib.baseboard_fab2(sch_1):page74_i20:vss(1132)" )
			)
			( pin "U2D1.G24"
				( objectStatus "@baseboard_fab2_lib.baseboard_fab2(sch_1):page74_i20:vss(1133)" )
			)
			( pin "U2D1.G22"
				( objectStatus "@baseboard_fab2_lib.baseboard_fab2(sch_1):page74_i20:vss(1134)" )
			)
			( pin "U2D1.G8"
				( objectStatus "@baseboard_fab2_lib.baseboard_fab2(sch_1):page74_i20:vss(1135)" )
			)
			( pin "U2D1.G4"
				( objectStatus "@baseboard_fab2_lib.baseboard_fab2(sch_1):page74_i20:vss(1136)" )
			)
			( pin "U2D1.F69"
				( objectStatus "@baseboard_fab2_lib.baseboard_fab2(sch_1):page74_i20:vss(1137)" )
			)
			( pin "U2D1.F67"
				( objectStatus "@baseboard_fab2_lib.baseboard_fab2(sch_1):page74_i20:vss(1138)" )
			)
			( pin "U2D1.F43"
				( objectStatus "@baseboard_fab2_lib.baseboard_fab2(sch_1):page74_i20:vss(1139)" )
			)
			( pin "U2D1.F37"
				( objectStatus "@baseboard_fab2_lib.baseboard_fab2(sch_1):page74_i20:vss(1140)" )
			)
			( pin "U2D1.F31"
				( objectStatus "@baseboard_fab2_lib.baseboard_fab2(sch_1):page74_i20:vss(1141)" )
			)
			( pin "U2D1.F25"
				( objectStatus "@baseboard_fab2_lib.baseboard_fab2(sch_1):page74_i20:vss(1142)" )
			)
			( pin "U2D1.F19"
				( objectStatus "@baseboard_fab2_lib.baseboard_fab2(sch_1):page74_i20:vss(1143)" )
			)
			( pin "U2D1.F17"
				( objectStatus "@baseboard_fab2_lib.baseboard_fab2(sch_1):page74_i20:vss(1144)" )
			)
			( pin "U2D1.F5"
				( objectStatus "@baseboard_fab2_lib.baseboard_fab2(sch_1):page74_i20:vss(1145)" )
			)
			( pin "U2D1.E76"
				( objectStatus "@baseboard_fab2_lib.baseboard_fab2(sch_1):page74_i20:vss(1146)" )
			)
			( pin "U2D1.E74"
				( objectStatus "@baseboard_fab2_lib.baseboard_fab2(sch_1):page74_i20:vss(1147)" )
			)
			( pin "U2D1.E72"
				( objectStatus "@baseboard_fab2_lib.baseboard_fab2(sch_1):page74_i20:vss(1148)" )
			)
			( pin "U2D1.E22"
				( objectStatus "@baseboard_fab2_lib.baseboard_fab2(sch_1):page74_i20:vss(1149)" )
			)
			( pin "U2D1.E20"
				( objectStatus "@baseboard_fab2_lib.baseboard_fab2(sch_1):page74_i20:vss(1150)" )
			)
			( pin "U2D1.E18"
				( objectStatus "@baseboard_fab2_lib.baseboard_fab2(sch_1):page74_i20:vss(1151)" )
			)
			( pin "U2D1.E16"
				( objectStatus "@baseboard_fab2_lib.baseboard_fab2(sch_1):page74_i20:vss(1152)" )
			)
			( pin "U2D1.E8"
				( objectStatus "@baseboard_fab2_lib.baseboard_fab2(sch_1):page74_i20:vss(1153)" )
			)
			( pin "U2D1.E6"
				( objectStatus "@baseboard_fab2_lib.baseboard_fab2(sch_1):page74_i20:vss(1154)" )
			)
			( pin "U2D1.D77"
				( objectStatus "@baseboard_fab2_lib.baseboard_fab2(sch_1):page74_i20:vss(1155)" )
			)
			( pin "U2D1.D43"
				( objectStatus "@baseboard_fab2_lib.baseboard_fab2(sch_1):page74_i20:vss(1156)" )
			)
			( pin "U2D1.D41"
				( objectStatus "@baseboard_fab2_lib.baseboard_fab2(sch_1):page74_i20:vss(1157)" )
			)
			( pin "U2D1.D39"
				( objectStatus "@baseboard_fab2_lib.baseboard_fab2(sch_1):page74_i20:vss(1158)" )
			)
			( pin "U2D1.D37"
				( objectStatus "@baseboard_fab2_lib.baseboard_fab2(sch_1):page74_i20:vss(1159)" )
			)
			( pin "U2D1.D35"
				( objectStatus "@baseboard_fab2_lib.baseboard_fab2(sch_1):page74_i20:vss(1160)" )
			)
			( pin "U2D1.D33"
				( objectStatus "@baseboard_fab2_lib.baseboard_fab2(sch_1):page74_i20:vss(1161)" )
			)
			( pin "U2D1.D31"
				( objectStatus "@baseboard_fab2_lib.baseboard_fab2(sch_1):page74_i20:vss(1162)" )
			)
			( pin "U2D1.D29"
				( objectStatus "@baseboard_fab2_lib.baseboard_fab2(sch_1):page74_i20:vss(1163)" )
			)
			( pin "U2D1.D27"
				( objectStatus "@baseboard_fab2_lib.baseboard_fab2(sch_1):page74_i20:vss(1164)" )
			)
			( pin "U2D1.D25"
				( objectStatus "@baseboard_fab2_lib.baseboard_fab2(sch_1):page74_i20:vss(1165)" )
			)
			( pin "U2D1.D13"
				( objectStatus "@baseboard_fab2_lib.baseboard_fab2(sch_1):page74_i20:vss(1166)" )
			)
			( pin "U2D1.D11"
				( objectStatus "@baseboard_fab2_lib.baseboard_fab2(sch_1):page74_i20:vss(1167)" )
			)
			( pin "U2D1.CM27"
				( objectStatus "@baseboard_fab2_lib.baseboard_fab2(sch_1):page74_i20:vss(1168)" )
			)
			( pin "U2D1.C78"
				( objectStatus "@baseboard_fab2_lib.baseboard_fab2(sch_1):page74_i20:vss(1169)" )
			)
			( pin "U2D1.C76"
				( objectStatus "@baseboard_fab2_lib.baseboard_fab2(sch_1):page74_i20:vss(1170)" )
			)
			( pin "U2D1.C16"
				( objectStatus "@baseboard_fab2_lib.baseboard_fab2(sch_1):page74_i20:vss(1171)" )
			)
			( pin "U2D1.C14"
				( objectStatus "@baseboard_fab2_lib.baseboard_fab2(sch_1):page74_i20:vss(1172)" )
			)
			( pin "U2D1.C12"
				( objectStatus "@baseboard_fab2_lib.baseboard_fab2(sch_1):page74_i20:vss(1173)" )
			)
			( pin "U2D1.C10"
				( objectStatus "@baseboard_fab2_lib.baseboard_fab2(sch_1):page74_i20:vss(1174)" )
			)
			( pin "U2D1.C8"
				( objectStatus "@baseboard_fab2_lib.baseboard_fab2(sch_1):page74_i20:vss(1175)" )
			)
			( pin "U2D1.B75"
				( objectStatus "@baseboard_fab2_lib.baseboard_fab2(sch_1):page74_i20:vss(1176)" )
			)
			( pin "U2D1.B71"
				( objectStatus "@baseboard_fab2_lib.baseboard_fab2(sch_1):page74_i20:vss(1177)" )
			)
			( pin "U2D1.B37"
				( objectStatus "@baseboard_fab2_lib.baseboard_fab2(sch_1):page74_i20:vss(1178)" )
			)
			( pin "U2D1.B31"
				( objectStatus "@baseboard_fab2_lib.baseboard_fab2(sch_1):page74_i20:vss(1179)" )
			)
			( pin "U2D1.B25"
				( objectStatus "@baseboard_fab2_lib.baseboard_fab2(sch_1):page74_i20:vss(1180)" )
			)
			( pin "U2D1.A38"
				( objectStatus "@baseboard_fab2_lib.baseboard_fab2(sch_1):page74_i20:vss(1181)" )
			)
			( pin "U2D1.A36"
				( objectStatus "@baseboard_fab2_lib.baseboard_fab2(sch_1):page74_i20:vss(1182)" )
			)
			( pin "U2D1.A32"
				( objectStatus "@baseboard_fab2_lib.baseboard_fab2(sch_1):page74_i20:vss(1183)" )
			)
			( pin "U2D1.A30"
				( objectStatus "@baseboard_fab2_lib.baseboard_fab2(sch_1):page74_i20:vss(1184)" )
			)
			( pin "U2D1.A26"
				( objectStatus "@baseboard_fab2_lib.baseboard_fab2(sch_1):page74_i20:vss(1185)" )
			)
			( pin "U2D1.AC58"
				( objectStatus "@baseboard_fab2_lib.baseboard_fab2(sch_1):page74_i20:vss(1186)" )
			)
			( pin "U2D1.AC60"
				( objectStatus "@baseboard_fab2_lib.baseboard_fab2(sch_1):page74_i20:vss(1187)" )
			)
			( pin "U2D1.AC62"
				( objectStatus "@baseboard_fab2_lib.baseboard_fab2(sch_1):page74_i20:vss(1188)" )
			)
			( pin "U2D1.AJ4"
				( objectStatus "@baseboard_fab2_lib.baseboard_fab2(sch_1):page74_i20:vss(1189)" )
			)
			( pin "U2D1.AR6"
				( objectStatus "@baseboard_fab2_lib.baseboard_fab2(sch_1):page74_i20:vss(1190)" )
			)
			( pin "U2D1.CG6"
				( objectStatus "@baseboard_fab2_lib.baseboard_fab2(sch_1):page74_i20:vss(1191)" )
			)
			( pin "U2D1.CW6"
				( objectStatus "@baseboard_fab2_lib.baseboard_fab2(sch_1):page74_i20:vss(1192)" )
			)
			( pin "U2D1.DE48"
				( objectStatus "@baseboard_fab2_lib.baseboard_fab2(sch_1):page74_i20:vss(1193)" )
			)
			( pin "U2D1.DE50"
				( objectStatus "@baseboard_fab2_lib.baseboard_fab2(sch_1):page74_i20:vss(1194)" )
			)
			( pin "U2D1.DE52"
				( objectStatus "@baseboard_fab2_lib.baseboard_fab2(sch_1):page74_i20:vss(1195)" )
			)
			( pin "U2D1.DE54"
				( objectStatus "@baseboard_fab2_lib.baseboard_fab2(sch_1):page74_i20:vss(1196)" )
			)
			( pin "U2D1.DE56"
				( objectStatus "@baseboard_fab2_lib.baseboard_fab2(sch_1):page74_i20:vss(1197)" )
			)
			( pin "U2D1.DE58"
				( objectStatus "@baseboard_fab2_lib.baseboard_fab2(sch_1):page74_i20:vss(1198)" )
			)
			( pin "U2D1.DE60"
				( objectStatus "@baseboard_fab2_lib.baseboard_fab2(sch_1):page74_i20:vss(1199)" )
			)
			( pin "U2D1.DE62"
				( objectStatus "@baseboard_fab2_lib.baseboard_fab2(sch_1):page74_i20:vss(1200)" )
			)
			( pin "U2D1.DL8"
				( objectStatus "@baseboard_fab2_lib.baseboard_fab2(sch_1):page74_i20:vss(1201)" )
			)
			( pin "U2D1.DN18"
				( objectStatus "@baseboard_fab2_lib.baseboard_fab2(sch_1):page74_i20:vss(1202)" )
			)
			( pin "U2D1.DP45"
				( objectStatus "@baseboard_fab2_lib.baseboard_fab2(sch_1):page74_i20:vss(1203)" )
			)
			( pin "U2D1.DP47"
				( objectStatus "@baseboard_fab2_lib.baseboard_fab2(sch_1):page74_i20:vss(1204)" )
			)
			( pin "U2D1.DP49"
				( objectStatus "@baseboard_fab2_lib.baseboard_fab2(sch_1):page74_i20:vss(1205)" )
			)
			( pin "U2D1.DP51"
				( objectStatus "@baseboard_fab2_lib.baseboard_fab2(sch_1):page74_i20:vss(1206)" )
			)
			( pin "U2D1.DP53"
				( objectStatus "@baseboard_fab2_lib.baseboard_fab2(sch_1):page74_i20:vss(1207)" )
			)
			( pin "U2D1.DP55"
				( objectStatus "@baseboard_fab2_lib.baseboard_fab2(sch_1):page74_i20:vss(1208)" )
			)
			( pin "U2D1.DP57"
				( objectStatus "@baseboard_fab2_lib.baseboard_fab2(sch_1):page74_i20:vss(1209)" )
			)
			( pin "U2D1.DP59"
				( objectStatus "@baseboard_fab2_lib.baseboard_fab2(sch_1):page74_i20:vss(1210)" )
			)
			( pin "U2D1.DP61"
				( objectStatus "@baseboard_fab2_lib.baseboard_fab2(sch_1):page74_i20:vss(1211)" )
			)
			( pin "U2D1.DP63"
				( objectStatus "@baseboard_fab2_lib.baseboard_fab2(sch_1):page74_i20:vss(1212)" )
			)
			( pin "U2D1.DP9"
				( objectStatus "@baseboard_fab2_lib.baseboard_fab2(sch_1):page74_i20:vss(1213)" )
			)
			( pin "U2D1.DV19"
				( objectStatus "@baseboard_fab2_lib.baseboard_fab2(sch_1):page74_i20:vss(1214)" )
			)
			( pin "U2D1.DY45"
				( objectStatus "@baseboard_fab2_lib.baseboard_fab2(sch_1):page74_i20:vss(1215)" )
			)
			( pin "U2D1.DY47"
				( objectStatus "@baseboard_fab2_lib.baseboard_fab2(sch_1):page74_i20:vss(1216)" )
			)
			( pin "U2D1.DY49"
				( objectStatus "@baseboard_fab2_lib.baseboard_fab2(sch_1):page74_i20:vss(1217)" )
			)
			( pin "U2D1.DY51"
				( objectStatus "@baseboard_fab2_lib.baseboard_fab2(sch_1):page74_i20:vss(1218)" )
			)
			( pin "U2D1.DY53"
				( objectStatus "@baseboard_fab2_lib.baseboard_fab2(sch_1):page74_i20:vss(1219)" )
			)
			( pin "U2D1.DY55"
				( objectStatus "@baseboard_fab2_lib.baseboard_fab2(sch_1):page74_i20:vss(1220)" )
			)
			( pin "U2D1.DY57"
				( objectStatus "@baseboard_fab2_lib.baseboard_fab2(sch_1):page74_i20:vss(1221)" )
			)
			( pin "U2D1.DY59"
				( objectStatus "@baseboard_fab2_lib.baseboard_fab2(sch_1):page74_i20:vss(1222)" )
			)
			( pin "U2D1.DY61"
				( objectStatus "@baseboard_fab2_lib.baseboard_fab2(sch_1):page74_i20:vss(1223)" )
			)
			( pin "U2D1.DY63"
				( objectStatus "@baseboard_fab2_lib.baseboard_fab2(sch_1):page74_i20:vss(1224)" )
			)
			( pin "U2D1.EA14"
				( objectStatus "@baseboard_fab2_lib.baseboard_fab2(sch_1):page74_i20:vss(1225)" )
			)
			( pin "U2D1.L8"
				( objectStatus "@baseboard_fab2_lib.baseboard_fab2(sch_1):page74_i20:vss(1226)" )
			)
			( pin "U2D1.V11"
				( objectStatus "@baseboard_fab2_lib.baseboard_fab2(sch_1):page74_i20:vss(1227)" )
			)
			( pin "U2D1.E66"
				( objectStatus "@baseboard_fab2_lib.baseboard_fab2(sch_1):page74_i20:vss(1228)" )
			)
			( pin "U2D1.ED69"
				( objectStatus "@baseboard_fab2_lib.baseboard_fab2(sch_1):page74_i20:vss(1229)" )
			)
			( pin "U2D1.EE80"
				( objectStatus "@baseboard_fab2_lib.baseboard_fab2(sch_1):page74_i20:vss(1230)" )
			)
			( pin "U2D1.EE8"
				( objectStatus "@baseboard_fab2_lib.baseboard_fab2(sch_1):page74_i20:vss(1231)" )
			)
			( pin "U2D1.EE40"
				( objectStatus "@baseboard_fab2_lib.baseboard_fab2(sch_1):page74_i20:vss(1232)" )
			)
			( pin "U2D1.ED81"
				( objectStatus "@baseboard_fab2_lib.baseboard_fab2(sch_1):page74_i20:vss(1233)" )
			)
			( pin "U2D1.ED7"
				( objectStatus "@baseboard_fab2_lib.baseboard_fab2(sch_1):page74_i20:vss(1234)" )
			)
			( pin "U2D1.ED41"
				( objectStatus "@baseboard_fab2_lib.baseboard_fab2(sch_1):page74_i20:vss(1235)" )
			)
			( pin "U2D1.EC82"
				( objectStatus "@baseboard_fab2_lib.baseboard_fab2(sch_1):page74_i20:vss(1236)" )
			)
			( pin "U2D1.EC6"
				( objectStatus "@baseboard_fab2_lib.baseboard_fab2(sch_1):page74_i20:vss(1237)" )
			)
			( pin "U2D1.EC42"
				( objectStatus "@baseboard_fab2_lib.baseboard_fab2(sch_1):page74_i20:vss(1238)" )
			)
			( pin "U2D1.DW2"
				( objectStatus "@baseboard_fab2_lib.baseboard_fab2(sch_1):page74_i20:vss(1239)" )
			)
			( pin "U2D1.EB83"
				( objectStatus "@baseboard_fab2_lib.baseboard_fab2(sch_1):page74_i20:vss(1240)" )
			)
			( pin "U2D1.EA84"
				( objectStatus "@baseboard_fab2_lib.baseboard_fab2(sch_1):page74_i20:vss(1241)" )
			)
			( pin "U2D1.DY85"
				( objectStatus "@baseboard_fab2_lib.baseboard_fab2(sch_1):page74_i20:vss(1242)" )
			)
			( pin "U2D1.J86"
				( objectStatus "@baseboard_fab2_lib.baseboard_fab2(sch_1):page74_i20:vss(1243)" )
			)
			( pin "U2D1.E82"
				( objectStatus "@baseboard_fab2_lib.baseboard_fab2(sch_1):page74_i20:vss(1244)" )
			)
			( pin "U2D1.D81"
				( objectStatus "@baseboard_fab2_lib.baseboard_fab2(sch_1):page74_i20:vss(1245)" )
			)
			( pin "U2D1.D3"
				( objectStatus "@baseboard_fab2_lib.baseboard_fab2(sch_1):page74_i20:vss(1246)" )
			)
			( pin "U2D1.C80"
				( objectStatus "@baseboard_fab2_lib.baseboard_fab2(sch_1):page74_i20:vss(1247)" )
			)
			( pin "U2D1.C4"
				( objectStatus "@baseboard_fab2_lib.baseboard_fab2(sch_1):page74_i20:vss(1248)" )
			)
			( pin "U2D1.B79"
				( objectStatus "@baseboard_fab2_lib.baseboard_fab2(sch_1):page74_i20:vss(1249)" )
			)
			( pin "U2D1.B5"
				( objectStatus "@baseboard_fab2_lib.baseboard_fab2(sch_1):page74_i20:vss(1250)" )
			)
			( pin "U2D1.B43"
				( objectStatus "@baseboard_fab2_lib.baseboard_fab2(sch_1):page74_i20:vss(1251)" )
			)
			( pin "U2D1.A42"
				( objectStatus "@baseboard_fab2_lib.baseboard_fab2(sch_1):page74_i20:vss(1252)" )
			)
			( pin "U2D1.B9"
				( objectStatus "@baseboard_fab2_lib.baseboard_fab2(sch_1):page74_i20:vss(1253)" )
			)
			( pin "U2D1.AA16"
				( objectStatus "@baseboard_fab2_lib.baseboard_fab2(sch_1):page74_i21:vss(934)" )
			)
			( pin "U2D1.AA4"
				( objectStatus "@baseboard_fab2_lib.baseboard_fab2(sch_1):page74_i21:vss(935)" )
			)
			( pin "U2D1.Y85"
				( objectStatus "@baseboard_fab2_lib.baseboard_fab2(sch_1):page74_i21:vss(936)" )
			)
			( pin "U2D1.Y83"
				( objectStatus "@baseboard_fab2_lib.baseboard_fab2(sch_1):page74_i21:vss(937)" )
			)
			( pin "U2D1.Y81"
				( objectStatus "@baseboard_fab2_lib.baseboard_fab2(sch_1):page74_i21:vss(938)" )
			)
			( pin "U2D1.Y79"
				( objectStatus "@baseboard_fab2_lib.baseboard_fab2(sch_1):page74_i21:vss(939)" )
			)
			( pin "U2D1.Y73"
				( objectStatus "@baseboard_fab2_lib.baseboard_fab2(sch_1):page74_i21:vss(940)" )
			)
			( pin "U2D1.Y71"
				( objectStatus "@baseboard_fab2_lib.baseboard_fab2(sch_1):page74_i21:vss(941)" )
			)
			( pin "U2D1.Y9"
				( objectStatus "@baseboard_fab2_lib.baseboard_fab2(sch_1):page74_i21:vss(942)" )
			)
			( pin "U2D1.Y7"
				( objectStatus "@baseboard_fab2_lib.baseboard_fab2(sch_1):page74_i21:vss(943)" )
			)
			( pin "U2D1.Y67"
				( objectStatus "@baseboard_fab2_lib.baseboard_fab2(sch_1):page74_i21:vss(944)" )
			)
			( pin "U2D1.Y5"
				( objectStatus "@baseboard_fab2_lib.baseboard_fab2(sch_1):page74_i21:vss(945)" )
			)
			( pin "U2D1.Y17"
				( objectStatus "@baseboard_fab2_lib.baseboard_fab2(sch_1):page74_i21:vss(946)" )
			)
			( pin "U2D1.Y15"
				( objectStatus "@baseboard_fab2_lib.baseboard_fab2(sch_1):page74_i21:vss(947)" )
			)
			( pin "U2D1.W82"
				( objectStatus "@baseboard_fab2_lib.baseboard_fab2(sch_1):page74_i21:vss(948)" )
			)
			( pin "U2D1.W78"
				( objectStatus "@baseboard_fab2_lib.baseboard_fab2(sch_1):page74_i21:vss(949)" )
			)
			( pin "U2D1.W74"
				( objectStatus "@baseboard_fab2_lib.baseboard_fab2(sch_1):page74_i21:vss(950)" )
			)
			( pin "U2D1.W68"
				( objectStatus "@baseboard_fab2_lib.baseboard_fab2(sch_1):page74_i21:vss(951)" )
			)
			( pin "U2D1.W42"
				( objectStatus "@baseboard_fab2_lib.baseboard_fab2(sch_1):page74_i21:vss(952)" )
			)
			( pin "U2D1.W40"
				( objectStatus "@baseboard_fab2_lib.baseboard_fab2(sch_1):page74_i21:vss(953)" )
			)
			( pin "U2D1.W38"
				( objectStatus "@baseboard_fab2_lib.baseboard_fab2(sch_1):page74_i21:vss(954)" )
			)
			( pin "U2D1.W36"
				( objectStatus "@baseboard_fab2_lib.baseboard_fab2(sch_1):page74_i21:vss(955)" )
			)
			( pin "U2D1.W34"
				( objectStatus "@baseboard_fab2_lib.baseboard_fab2(sch_1):page74_i21:vss(956)" )
			)
			( pin "U2D1.W32"
				( objectStatus "@baseboard_fab2_lib.baseboard_fab2(sch_1):page74_i21:vss(957)" )
			)
			( pin "U2D1.W30"
				( objectStatus "@baseboard_fab2_lib.baseboard_fab2(sch_1):page74_i21:vss(958)" )
			)
			( pin "U2D1.W28"
				( objectStatus "@baseboard_fab2_lib.baseboard_fab2(sch_1):page74_i21:vss(959)" )
			)
			( pin "U2D1.W26"
				( objectStatus "@baseboard_fab2_lib.baseboard_fab2(sch_1):page74_i21:vss(960)" )
			)
			( pin "U2D1.W24"
				( objectStatus "@baseboard_fab2_lib.baseboard_fab2(sch_1):page74_i21:vss(961)" )
			)
			( pin "U2D1.W22"
				( objectStatus "@baseboard_fab2_lib.baseboard_fab2(sch_1):page74_i21:vss(962)" )
			)
			( pin "U2D1.W12"
				( objectStatus "@baseboard_fab2_lib.baseboard_fab2(sch_1):page74_i21:vss(963)" )
			)
			( pin "U2D1.AC56"
				( objectStatus "@baseboard_fab2_lib.baseboard_fab2(sch_1):page74_i21:vss(964)" )
			)
			( pin "U2D1.W8"
				( objectStatus "@baseboard_fab2_lib.baseboard_fab2(sch_1):page74_i21:vss(965)" )
			)
			( pin "U2D1.V83"
				( objectStatus "@baseboard_fab2_lib.baseboard_fab2(sch_1):page74_i21:vss(966)" )
			)
			( pin "U2D1.V77"
				( objectStatus "@baseboard_fab2_lib.baseboard_fab2(sch_1):page74_i21:vss(967)" )
			)
			( pin "U2D1.V75"
				( objectStatus "@baseboard_fab2_lib.baseboard_fab2(sch_1):page74_i21:vss(968)" )
			)
			( pin "U2D1.V73"
				( objectStatus "@baseboard_fab2_lib.baseboard_fab2(sch_1):page74_i21:vss(969)" )
			)
			( pin "U2D1.V43"
				( objectStatus "@baseboard_fab2_lib.baseboard_fab2(sch_1):page74_i21:vss(970)" )
			)
			( pin "U2D1.V23"
				( objectStatus "@baseboard_fab2_lib.baseboard_fab2(sch_1):page74_i21:vss(971)" )
			)
			( pin "U2D1.V21"
				( objectStatus "@baseboard_fab2_lib.baseboard_fab2(sch_1):page74_i21:vss(972)" )
			)
			( pin "U2D1.V15"
				( objectStatus "@baseboard_fab2_lib.baseboard_fab2(sch_1):page74_i21:vss(973)" )
			)
			( pin "U2D1.V13"
				( objectStatus "@baseboard_fab2_lib.baseboard_fab2(sch_1):page74_i21:vss(974)" )
			)
			( pin "U2D1.V9"
				( objectStatus "@baseboard_fab2_lib.baseboard_fab2(sch_1):page74_i21:vss(975)" )
			)
			( pin "U2D1.V5"
				( objectStatus "@baseboard_fab2_lib.baseboard_fab2(sch_1):page74_i21:vss(976)" )
			)
			( pin "U2D1.V1"
				( objectStatus "@baseboard_fab2_lib.baseboard_fab2(sch_1):page74_i21:vss(977)" )
			)
			( pin "U2D1.U86"
				( objectStatus "@baseboard_fab2_lib.baseboard_fab2(sch_1):page74_i21:vss(978)" )
			)
			( pin "U2D1.U80"
				( objectStatus "@baseboard_fab2_lib.baseboard_fab2(sch_1):page74_i21:vss(979)" )
			)
			( pin "U2D1.U78"
				( objectStatus "@baseboard_fab2_lib.baseboard_fab2(sch_1):page74_i21:vss(980)" )
			)
			( pin "U2D1.U76"
				( objectStatus "@baseboard_fab2_lib.baseboard_fab2(sch_1):page74_i21:vss(981)" )
			)
			( pin "U2D1.U74"
				( objectStatus "@baseboard_fab2_lib.baseboard_fab2(sch_1):page74_i21:vss(982)" )
			)
			( pin "U2D1.U70"
				( objectStatus "@baseboard_fab2_lib.baseboard_fab2(sch_1):page74_i21:vss(983)" )
			)
			( pin "U2D1.U68"
				( objectStatus "@baseboard_fab2_lib.baseboard_fab2(sch_1):page74_i21:vss(984)" )
			)
			( pin "U2D1.U42"
				( objectStatus "@baseboard_fab2_lib.baseboard_fab2(sch_1):page74_i21:vss(985)" )
			)
			( pin "U2D1.U36"
				( objectStatus "@baseboard_fab2_lib.baseboard_fab2(sch_1):page74_i21:vss(986)" )
			)
			( pin "U2D1.U30"
				( objectStatus "@baseboard_fab2_lib.baseboard_fab2(sch_1):page74_i21:vss(987)" )
			)
			( pin "U2D1.U24"
				( objectStatus "@baseboard_fab2_lib.baseboard_fab2(sch_1):page74_i21:vss(988)" )
			)
			( pin "U2D1.U22"
				( objectStatus "@baseboard_fab2_lib.baseboard_fab2(sch_1):page74_i21:vss(989)" )
			)
			( pin "U2D1.U20"
				( objectStatus "@baseboard_fab2_lib.baseboard_fab2(sch_1):page74_i21:vss(990)" )
			)
			( pin "U2D1.U6"
				( objectStatus "@baseboard_fab2_lib.baseboard_fab2(sch_1):page74_i21:vss(991)" )
			)
			( pin "U2D1.U4"
				( objectStatus "@baseboard_fab2_lib.baseboard_fab2(sch_1):page74_i21:vss(992)" )
			)
			( pin "U2D1.U2"
				( objectStatus "@baseboard_fab2_lib.baseboard_fab2(sch_1):page74_i21:vss(993)" )
			)
			( pin "U2D1.T85"
				( objectStatus "@baseboard_fab2_lib.baseboard_fab2(sch_1):page74_i21:vss(994)" )
			)
			( pin "U2D1.T83"
				( objectStatus "@baseboard_fab2_lib.baseboard_fab2(sch_1):page74_i21:vss(995)" )
			)
			( pin "U2D1.T77"
				( objectStatus "@baseboard_fab2_lib.baseboard_fab2(sch_1):page74_i21:vss(996)" )
			)
			( pin "U2D1.T73"
				( objectStatus "@baseboard_fab2_lib.baseboard_fab2(sch_1):page74_i21:vss(997)" )
			)
			( pin "U2D1.T65"
				( objectStatus "@baseboard_fab2_lib.baseboard_fab2(sch_1):page74_i21:vss(998)" )
			)
			( pin "U2D1.T41"
				( objectStatus "@baseboard_fab2_lib.baseboard_fab2(sch_1):page74_i21:vss(999)" )
			)
			( pin "U2D1.T37"
				( objectStatus "@baseboard_fab2_lib.baseboard_fab2(sch_1):page74_i21:vss(1000)" )
			)
			( pin "U2D1.T35"
				( objectStatus "@baseboard_fab2_lib.baseboard_fab2(sch_1):page74_i21:vss(1001)" )
			)
			( pin "U2D1.T31"
				( objectStatus "@baseboard_fab2_lib.baseboard_fab2(sch_1):page74_i21:vss(1002)" )
			)
			( pin "U2D1.T29"
				( objectStatus "@baseboard_fab2_lib.baseboard_fab2(sch_1):page74_i21:vss(1003)" )
			)
			( pin "U2D1.T25"
				( objectStatus "@baseboard_fab2_lib.baseboard_fab2(sch_1):page74_i21:vss(1004)" )
			)
			( pin "U2D1.T17"
				( objectStatus "@baseboard_fab2_lib.baseboard_fab2(sch_1):page74_i21:vss(1005)" )
			)
			( pin "U2D1.T13"
				( objectStatus "@baseboard_fab2_lib.baseboard_fab2(sch_1):page74_i21:vss(1006)" )
			)
			( pin "U2D1.R86"
				( objectStatus "@baseboard_fab2_lib.baseboard_fab2(sch_1):page74_i21:vss(1007)" )
			)
			( pin "U2D1.R78"
				( objectStatus "@baseboard_fab2_lib.baseboard_fab2(sch_1):page74_i21:vss(1008)" )
			)
			( pin "U2D1.R72"
				( objectStatus "@baseboard_fab2_lib.baseboard_fab2(sch_1):page74_i21:vss(1009)" )
			)
			( pin "U2D1.R68"
				( objectStatus "@baseboard_fab2_lib.baseboard_fab2(sch_1):page74_i21:vss(1010)" )
			)
			( pin "U2D1.R40"
				( objectStatus "@baseboard_fab2_lib.baseboard_fab2(sch_1):page74_i21:vss(1011)" )
			)
			( pin "U2D1.R38"
				( objectStatus "@baseboard_fab2_lib.baseboard_fab2(sch_1):page74_i21:vss(1012)" )
			)
			( pin "U2D1.R34"
				( objectStatus "@baseboard_fab2_lib.baseboard_fab2(sch_1):page74_i21:vss(1013)" )
			)
			( pin "U2D1.R32"
				( objectStatus "@baseboard_fab2_lib.baseboard_fab2(sch_1):page74_i21:vss(1014)" )
			)
			( pin "U2D1.R28"
				( objectStatus "@baseboard_fab2_lib.baseboard_fab2(sch_1):page74_i21:vss(1015)" )
			)
			( pin "U2D1.R26"
				( objectStatus "@baseboard_fab2_lib.baseboard_fab2(sch_1):page74_i21:vss(1016)" )
			)
			( pin "U2D1.R22"
				( objectStatus "@baseboard_fab2_lib.baseboard_fab2(sch_1):page74_i21:vss(1017)" )
			)
			( pin "U2D1.R4"
				( objectStatus "@baseboard_fab2_lib.baseboard_fab2(sch_1):page74_i21:vss(1018)" )
			)
			( pin "U2D1.R2"
				( objectStatus "@baseboard_fab2_lib.baseboard_fab2(sch_1):page74_i21:vss(1019)" )
			)
			( pin "U2D1.R18"
				( objectStatus "@baseboard_fab2_lib.baseboard_fab2(sch_1):page74_i21:vss(1020)" )
			)
			( pin "U2D1.R14"
				( objectStatus "@baseboard_fab2_lib.baseboard_fab2(sch_1):page74_i21:vss(1021)" )
			)
			( pin "U2D1.P83"
				( objectStatus "@baseboard_fab2_lib.baseboard_fab2(sch_1):page74_i21:vss(1022)" )
			)
			( pin "U2D1.P81"
				( objectStatus "@baseboard_fab2_lib.baseboard_fab2(sch_1):page74_i21:vss(1023)" )
			)
			( pin "U2D1.P71"
				( objectStatus "@baseboard_fab2_lib.baseboard_fab2(sch_1):page74_i21:vss(1024)" )
			)
			( pin "U2D1.P69"
				( objectStatus "@baseboard_fab2_lib.baseboard_fab2(sch_1):page74_i21:vss(1025)" )
			)
			( pin "U2D1.P67"
				( objectStatus "@baseboard_fab2_lib.baseboard_fab2(sch_1):page74_i21:vss(1026)" )
			)
			( pin "U2D1.P39"
				( objectStatus "@baseboard_fab2_lib.baseboard_fab2(sch_1):page74_i21:vss(1027)" )
			)
			( pin "U2D1.P33"
				( objectStatus "@baseboard_fab2_lib.baseboard_fab2(sch_1):page74_i21:vss(1028)" )
			)
			( pin "U2D1.P27"
				( objectStatus "@baseboard_fab2_lib.baseboard_fab2(sch_1):page74_i21:vss(1029)" )
			)
			( pin "U2D1.P15"
				( objectStatus "@baseboard_fab2_lib.baseboard_fab2(sch_1):page74_i21:vss(1030)" )
			)
			( pin "U2D1.P11"
				( objectStatus "@baseboard_fab2_lib.baseboard_fab2(sch_1):page74_i21:vss(1031)" )
			)
			( pin "U2D1.N8"
				( objectStatus "@baseboard_fab2_lib.baseboard_fab2(sch_1):page74_i21:vss(1032)" )
			)
			( pin "U2D1.N4"
				( objectStatus "@baseboard_fab2_lib.baseboard_fab2(sch_1):page74_i21:vss(1033)" )
			)
			( pin "U2D1.N78"
				( objectStatus "@baseboard_fab2_lib.baseboard_fab2(sch_1):page74_i21:vss(1034)" )
			)
			( pin "U2D1.N76"
				( objectStatus "@baseboard_fab2_lib.baseboard_fab2(sch_1):page74_i21:vss(1035)" )
			)
			( pin "U2D1.N74"
				( objectStatus "@baseboard_fab2_lib.baseboard_fab2(sch_1):page74_i21:vss(1036)" )
			)
			( pin "U2D1.N72"
				( objectStatus "@baseboard_fab2_lib.baseboard_fab2(sch_1):page74_i21:vss(1037)" )
			)
			( pin "U2D1.N70"
				( objectStatus "@baseboard_fab2_lib.baseboard_fab2(sch_1):page74_i21:vss(1038)" )
			)
			( pin "U2D1.N66"
				( objectStatus "@baseboard_fab2_lib.baseboard_fab2(sch_1):page74_i21:vss(1039)" )
			)
			( pin "U2D1.N6"
				( objectStatus "@baseboard_fab2_lib.baseboard_fab2(sch_1):page74_i21:vss(1040)" )
			)
			( pin "U2D1.N22"
				( objectStatus "@baseboard_fab2_lib.baseboard_fab2(sch_1):page74_i21:vss(1041)" )
			)
			( pin "U2D1.N20"
				( objectStatus "@baseboard_fab2_lib.baseboard_fab2(sch_1):page74_i21:vss(1042)" )
			)
			( pin "U2D1.DM19"
				( objectStatus "@baseboard_fab2_lib.baseboard_fab2(sch_1):page74_i21:vss(1043)" )
			)
			( pin "U2D1.M85"
				( objectStatus "@baseboard_fab2_lib.baseboard_fab2(sch_1):page74_i21:vss(1044)" )
			)
			( pin "U2D1.M83"
				( objectStatus "@baseboard_fab2_lib.baseboard_fab2(sch_1):page74_i21:vss(1045)" )
			)
			( pin "U2D1.M79"
				( objectStatus "@baseboard_fab2_lib.baseboard_fab2(sch_1):page74_i21:vss(1046)" )
			)
			( pin "U2D1.M71"
				( objectStatus "@baseboard_fab2_lib.baseboard_fab2(sch_1):page74_i21:vss(1047)" )
			)
			( pin "U2D1.M65"
				( objectStatus "@baseboard_fab2_lib.baseboard_fab2(sch_1):page74_i21:vss(1048)" )
			)
			( pin "U2D1.M43"
				( objectStatus "@baseboard_fab2_lib.baseboard_fab2(sch_1):page74_i21:vss(1049)" )
			)
			( pin "U2D1.M41"
				( objectStatus "@baseboard_fab2_lib.baseboard_fab2(sch_1):page74_i21:vss(1050)" )
			)
			( pin "U2D1.M39"
				( objectStatus "@baseboard_fab2_lib.baseboard_fab2(sch_1):page74_i21:vss(1051)" )
			)
			( pin "U2D1.M37"
				( objectStatus "@baseboard_fab2_lib.baseboard_fab2(sch_1):page74_i21:vss(1052)" )
			)
			( pin "U2D1.M35"
				( objectStatus "@baseboard_fab2_lib.baseboard_fab2(sch_1):page74_i21:vss(1053)" )
			)
			( pin "U2D1.M33"
				( objectStatus "@baseboard_fab2_lib.baseboard_fab2(sch_1):page74_i21:vss(1054)" )
			)
			( pin "U2D1.M31"
				( objectStatus "@baseboard_fab2_lib.baseboard_fab2(sch_1):page74_i21:vss(1055)" )
			)
			( pin "U2D1.M29"
				( objectStatus "@baseboard_fab2_lib.baseboard_fab2(sch_1):page74_i21:vss(1056)" )
			)
			( pin "U2D1.M27"
				( objectStatus "@baseboard_fab2_lib.baseboard_fab2(sch_1):page74_i21:vss(1057)" )
			)
			( pin "U2D1.M25"
				( objectStatus "@baseboard_fab2_lib.baseboard_fab2(sch_1):page74_i21:vss(1058)" )
			)
			( pin "U2D1.M23"
				( objectStatus "@baseboard_fab2_lib.baseboard_fab2(sch_1):page74_i21:vss(1059)" )
			)
			( pin "U2D1.M19"
				( objectStatus "@baseboard_fab2_lib.baseboard_fab2(sch_1):page74_i21:vss(1060)" )
			)
			( pin "U2D1.M17"
				( objectStatus "@baseboard_fab2_lib.baseboard_fab2(sch_1):page74_i21:vss(1061)" )
			)
			( pin "U2D1.M15"
				( objectStatus "@baseboard_fab2_lib.baseboard_fab2(sch_1):page74_i21:vss(1062)" )
			)
			( pin "U2D1.CT7"
				( objectStatus "@baseboard_fab2_lib.baseboard_fab2(sch_1):page74_i21:vss(1063)" )
			)
			( pin "U2D1.BT9"
				( objectStatus "@baseboard_fab2_lib.baseboard_fab2(sch_1):page74_i21:vss(1064)" )
			)
			( pin "U2D1.L82"
				( objectStatus "@baseboard_fab2_lib.baseboard_fab2(sch_1):page74_i21:vss(1065)" )
			)
			( pin "U2D1.L80"
				( objectStatus "@baseboard_fab2_lib.baseboard_fab2(sch_1):page74_i21:vss(1066)" )
			)
			( pin "U2D1.L78"
				( objectStatus "@baseboard_fab2_lib.baseboard_fab2(sch_1):page74_i21:vss(1067)" )
			)
			( pin "U2D1.L72"
				( objectStatus "@baseboard_fab2_lib.baseboard_fab2(sch_1):page74_i21:vss(1068)" )
			)
			( pin "U2D1.L22"
				( objectStatus "@baseboard_fab2_lib.baseboard_fab2(sch_1):page74_i21:vss(1069)" )
			)
			( pin "U2D1.L20"
				( objectStatus "@baseboard_fab2_lib.baseboard_fab2(sch_1):page74_i21:vss(1070)" )
			)
			( pin "U2D1.L6"
				( objectStatus "@baseboard_fab2_lib.baseboard_fab2(sch_1):page74_i21:vss(1071)" )
			)
			( pin "U2D1.L2"
				( objectStatus "@baseboard_fab2_lib.baseboard_fab2(sch_1):page74_i21:vss(1072)" )
			)
			( pin "U2D1.L10"
				( objectStatus "@baseboard_fab2_lib.baseboard_fab2(sch_1):page74_i21:vss(1073)" )
			)
			( pin "U2D1.K85"
				( objectStatus "@baseboard_fab2_lib.baseboard_fab2(sch_1):page74_i21:vss(1074)" )
			)
			( pin "U2D1.K83"
				( objectStatus "@baseboard_fab2_lib.baseboard_fab2(sch_1):page74_i21:vss(1075)" )
			)
			( pin "U2D1.K81"
				( objectStatus "@baseboard_fab2_lib.baseboard_fab2(sch_1):page74_i21:vss(1076)" )
			)
			( pin "U2D1.K77"
				( objectStatus "@baseboard_fab2_lib.baseboard_fab2(sch_1):page74_i21:vss(1077)" )
			)
			( pin "U2D1.K73"
				( objectStatus "@baseboard_fab2_lib.baseboard_fab2(sch_1):page74_i21:vss(1078)" )
			)
			( pin "U2D1.K71"
				( objectStatus "@baseboard_fab2_lib.baseboard_fab2(sch_1):page74_i21:vss(1079)" )
			)
			( pin "U2D1.K69"
				( objectStatus "@baseboard_fab2_lib.baseboard_fab2(sch_1):page74_i21:vss(1080)" )
			)
			( pin "U2D1.K67"
				( objectStatus "@baseboard_fab2_lib.baseboard_fab2(sch_1):page74_i21:vss(1081)" )
			)
			( pin "U2D1.K65"
				( objectStatus "@baseboard_fab2_lib.baseboard_fab2(sch_1):page74_i21:vss(1082)" )
			)
			( pin "U2D1.K39"
				( objectStatus "@baseboard_fab2_lib.baseboard_fab2(sch_1):page74_i21:vss(1083)" )
			)
			( pin "U2D1.K33"
				( objectStatus "@baseboard_fab2_lib.baseboard_fab2(sch_1):page74_i21:vss(1084)" )
			)
			( pin "U2D1.K27"
				( objectStatus "@baseboard_fab2_lib.baseboard_fab2(sch_1):page74_i21:vss(1085)" )
			)
			( pin "U2D1.DB7"
				( objectStatus "@baseboard_fab2_lib.baseboard_fab2(sch_1):page74_i21:vss(1086)" )
			)
			( pin "U2D1.K17"
				( objectStatus "@baseboard_fab2_lib.baseboard_fab2(sch_1):page74_i21:vss(1087)" )
			)
			( pin "U2D1.K13"
				( objectStatus "@baseboard_fab2_lib.baseboard_fab2(sch_1):page74_i21:vss(1088)" )
			)
			( pin "U2D1.K11"
				( objectStatus "@baseboard_fab2_lib.baseboard_fab2(sch_1):page74_i21:vss(1089)" )
			)
			( pin "U2D1.K1"
				( objectStatus "@baseboard_fab2_lib.baseboard_fab2(sch_1):page74_i21:vss(1090)" )
			)
			( pin "U2D1.J84"
				( objectStatus "@baseboard_fab2_lib.baseboard_fab2(sch_1):page74_i21:vss(1091)" )
			)
			( pin "U2D1.J82"
				( objectStatus "@baseboard_fab2_lib.baseboard_fab2(sch_1):page74_i21:vss(1092)" )
			)
			( pin "U2D1.J76"
				( objectStatus "@baseboard_fab2_lib.baseboard_fab2(sch_1):page74_i21:vss(1093)" )
			)
			( pin "U2D1.AL68"
				( objectStatus "@baseboard_fab2_lib.baseboard_fab2(sch_1):page74_i22:vss(774)" )
			)
			( pin "U2D1.AL64"
				( objectStatus "@baseboard_fab2_lib.baseboard_fab2(sch_1):page74_i22:vss(775)" )
			)
			( pin "U2D1.AL56"
				( objectStatus "@baseboard_fab2_lib.baseboard_fab2(sch_1):page74_i22:vss(776)" )
			)
			( pin "U2D1.AL32"
				( objectStatus "@baseboard_fab2_lib.baseboard_fab2(sch_1):page74_i22:vss(777)" )
			)
			( pin "U2D1.AL30"
				( objectStatus "@baseboard_fab2_lib.baseboard_fab2(sch_1):page74_i22:vss(778)" )
			)
			( pin "U2D1.AL24"
				( objectStatus "@baseboard_fab2_lib.baseboard_fab2(sch_1):page74_i22:vss(779)" )
			)
			( pin "U2D1.AL10"
				( objectStatus "@baseboard_fab2_lib.baseboard_fab2(sch_1):page74_i22:vss(780)" )
			)
			( pin "U2D1.AL4"
				( objectStatus "@baseboard_fab2_lib.baseboard_fab2(sch_1):page74_i22:vss(781)" )
			)
			( pin "U2D1.AK85"
				( objectStatus "@baseboard_fab2_lib.baseboard_fab2(sch_1):page74_i22:vss(782)" )
			)
			( pin "U2D1.AK83"
				( objectStatus "@baseboard_fab2_lib.baseboard_fab2(sch_1):page74_i22:vss(783)" )
			)
			( pin "U2D1.AK81"
				( objectStatus "@baseboard_fab2_lib.baseboard_fab2(sch_1):page74_i22:vss(784)" )
			)
			( pin "U2D1.AK79"
				( objectStatus "@baseboard_fab2_lib.baseboard_fab2(sch_1):page74_i22:vss(785)" )
			)
			( pin "U2D1.AK73"
				( objectStatus "@baseboard_fab2_lib.baseboard_fab2(sch_1):page74_i22:vss(786)" )
			)
			( pin "U2D1.AK67"
				( objectStatus "@baseboard_fab2_lib.baseboard_fab2(sch_1):page74_i22:vss(787)" )
			)
			( pin "U2D1.AK65"
				( objectStatus "@baseboard_fab2_lib.baseboard_fab2(sch_1):page74_i22:vss(788)" )
			)
			( pin "U2D1.AK55"
				( objectStatus "@baseboard_fab2_lib.baseboard_fab2(sch_1):page74_i22:vss(789)" )
			)
			( pin "U2D1.AK33"
				( objectStatus "@baseboard_fab2_lib.baseboard_fab2(sch_1):page74_i22:vss(790)" )
			)
			( pin "U2D1.AK31"
				( objectStatus "@baseboard_fab2_lib.baseboard_fab2(sch_1):page74_i22:vss(791)" )
			)
			( pin "U2D1.AK29"
				( objectStatus "@baseboard_fab2_lib.baseboard_fab2(sch_1):page74_i22:vss(792)" )
			)
			( pin "U2D1.AK25"
				( objectStatus "@baseboard_fab2_lib.baseboard_fab2(sch_1):page74_i22:vss(793)" )
			)
			( pin "U2D1.AK23"
				( objectStatus "@baseboard_fab2_lib.baseboard_fab2(sch_1):page74_i22:vss(794)" )
			)
			( pin "U2D1.AK19"
				( objectStatus "@baseboard_fab2_lib.baseboard_fab2(sch_1):page74_i22:vss(795)" )
			)
			( pin "U2D1.AK13"
				( objectStatus "@baseboard_fab2_lib.baseboard_fab2(sch_1):page74_i22:vss(796)" )
			)
			( pin "U2D1.AK9"
				( objectStatus "@baseboard_fab2_lib.baseboard_fab2(sch_1):page74_i22:vss(797)" )
			)
			( pin "U2D1.AJ86"
				( objectStatus "@baseboard_fab2_lib.baseboard_fab2(sch_1):page74_i22:vss(798)" )
			)
			( pin "U2D1.AJ82"
				( objectStatus "@baseboard_fab2_lib.baseboard_fab2(sch_1):page74_i22:vss(799)" )
			)
			( pin "U2D1.AJ78"
				( objectStatus "@baseboard_fab2_lib.baseboard_fab2(sch_1):page74_i22:vss(800)" )
			)
			( pin "U2D1.AJ74"
				( objectStatus "@baseboard_fab2_lib.baseboard_fab2(sch_1):page74_i22:vss(801)" )
			)
			( pin "U2D1.AJ68"
				( objectStatus "@baseboard_fab2_lib.baseboard_fab2(sch_1):page74_i22:vss(802)" )
			)
			( pin "U2D1.AJ66"
				( objectStatus "@baseboard_fab2_lib.baseboard_fab2(sch_1):page74_i22:vss(803)" )
			)
			( pin "U2D1.AJ54"
				( objectStatus "@baseboard_fab2_lib.baseboard_fab2(sch_1):page74_i22:vss(804)" )
			)
			( pin "U2D1.AJ52"
				( objectStatus "@baseboard_fab2_lib.baseboard_fab2(sch_1):page74_i22:vss(805)" )
			)
			( pin "U2D1.AJ50"
				( objectStatus "@baseboard_fab2_lib.baseboard_fab2(sch_1):page74_i22:vss(806)" )
			)
			( pin "U2D1.AJ48"
				( objectStatus "@baseboard_fab2_lib.baseboard_fab2(sch_1):page74_i22:vss(807)" )
			)
			( pin "U2D1.AJ46"
				( objectStatus "@baseboard_fab2_lib.baseboard_fab2(sch_1):page74_i22:vss(808)" )
			)
			( pin "U2D1.AJ34"
				( objectStatus "@baseboard_fab2_lib.baseboard_fab2(sch_1):page74_i22:vss(809)" )
			)
			( pin "U2D1.AJ32"
				( objectStatus "@baseboard_fab2_lib.baseboard_fab2(sch_1):page74_i22:vss(810)" )
			)
			( pin "U2D1.AJ28"
				( objectStatus "@baseboard_fab2_lib.baseboard_fab2(sch_1):page74_i22:vss(811)" )
			)
			( pin "U2D1.AJ26"
				( objectStatus "@baseboard_fab2_lib.baseboard_fab2(sch_1):page74_i22:vss(812)" )
			)
			( pin "U2D1.AJ22"
				( objectStatus "@baseboard_fab2_lib.baseboard_fab2(sch_1):page74_i22:vss(813)" )
			)
			( pin "U2D1.AJ8"
				( objectStatus "@baseboard_fab2_lib.baseboard_fab2(sch_1):page74_i22:vss(814)" )
			)
			( pin "U2D1.AH83"
				( objectStatus "@baseboard_fab2_lib.baseboard_fab2(sch_1):page74_i22:vss(815)" )
			)
			( pin "U2D1.AH77"
				( objectStatus "@baseboard_fab2_lib.baseboard_fab2(sch_1):page74_i22:vss(816)" )
			)
			( pin "U2D1.AH75"
				( objectStatus "@baseboard_fab2_lib.baseboard_fab2(sch_1):page74_i22:vss(817)" )
			)
			( pin "U2D1.AH69"
				( objectStatus "@baseboard_fab2_lib.baseboard_fab2(sch_1):page74_i22:vss(818)" )
			)
			( pin "U2D1.AH65"
				( objectStatus "@baseboard_fab2_lib.baseboard_fab2(sch_1):page74_i22:vss(819)" )
			)
			( pin "U2D1.AH61"
				( objectStatus "@baseboard_fab2_lib.baseboard_fab2(sch_1):page74_i22:vss(820)" )
			)
			( pin "U2D1.AH59"
				( objectStatus "@baseboard_fab2_lib.baseboard_fab2(sch_1):page74_i22:vss(821)" )
			)
			( pin "U2D1.AH53"
				( objectStatus "@baseboard_fab2_lib.baseboard_fab2(sch_1):page74_i22:vss(822)" )
			)
			( pin "U2D1.AH51"
				( objectStatus "@baseboard_fab2_lib.baseboard_fab2(sch_1):page74_i22:vss(823)" )
			)
			( pin "U2D1.AH49"
				( objectStatus "@baseboard_fab2_lib.baseboard_fab2(sch_1):page74_i22:vss(824)" )
			)
			( pin "U2D1.AH47"
				( objectStatus "@baseboard_fab2_lib.baseboard_fab2(sch_1):page74_i22:vss(825)" )
			)
			( pin "U2D1.AH45"
				( objectStatus "@baseboard_fab2_lib.baseboard_fab2(sch_1):page74_i22:vss(826)" )
			)
			( pin "U2D1.AH35"
				( objectStatus "@baseboard_fab2_lib.baseboard_fab2(sch_1):page74_i22:vss(827)" )
			)
			( pin "U2D1.AH33"
				( objectStatus "@baseboard_fab2_lib.baseboard_fab2(sch_1):page74_i22:vss(828)" )
			)
			( pin "U2D1.AH27"
				( objectStatus "@baseboard_fab2_lib.baseboard_fab2(sch_1):page74_i22:vss(829)" )
			)
			( pin "U2D1.AH21"
				( objectStatus "@baseboard_fab2_lib.baseboard_fab2(sch_1):page74_i22:vss(830)" )
			)
			( pin "U2D1.AH5"
				( objectStatus "@baseboard_fab2_lib.baseboard_fab2(sch_1):page74_i22:vss(831)" )
			)
			( pin "U2D1.AH1"
				( objectStatus "@baseboard_fab2_lib.baseboard_fab2(sch_1):page74_i22:vss(832)" )
			)
			( pin "U2D1.AG80"
				( objectStatus "@baseboard_fab2_lib.baseboard_fab2(sch_1):page74_i22:vss(833)" )
			)
			( pin "U2D1.AG78"
				( objectStatus "@baseboard_fab2_lib.baseboard_fab2(sch_1):page74_i22:vss(834)" )
			)
			( pin "U2D1.AG76"
				( objectStatus "@baseboard_fab2_lib.baseboard_fab2(sch_1):page74_i22:vss(835)" )
			)
			( pin "U2D1.AG74"
				( objectStatus "@baseboard_fab2_lib.baseboard_fab2(sch_1):page74_i22:vss(836)" )
			)
			( pin "U2D1.AG70"
				( objectStatus "@baseboard_fab2_lib.baseboard_fab2(sch_1):page74_i22:vss(837)" )
			)
			( pin "U2D1.AG64"
				( objectStatus "@baseboard_fab2_lib.baseboard_fab2(sch_1):page74_i22:vss(838)" )
			)
			( pin "U2D1.AG36"
				( objectStatus "@baseboard_fab2_lib.baseboard_fab2(sch_1):page74_i22:vss(839)" )
			)
			( pin "U2D1.AG18"
				( objectStatus "@baseboard_fab2_lib.baseboard_fab2(sch_1):page74_i22:vss(840)" )
			)
			( pin "U2D1.AG14"
				( objectStatus "@baseboard_fab2_lib.baseboard_fab2(sch_1):page74_i22:vss(841)" )
			)
			( pin "U2D1.AG12"
				( objectStatus "@baseboard_fab2_lib.baseboard_fab2(sch_1):page74_i22:vss(842)" )
			)
			( pin "U2D1.AF85"
				( objectStatus "@baseboard_fab2_lib.baseboard_fab2(sch_1):page74_i22:vss(843)" )
			)
			( pin "U2D1.AF83"
				( objectStatus "@baseboard_fab2_lib.baseboard_fab2(sch_1):page74_i22:vss(844)" )
			)
			( pin "U2D1.AF77"
				( objectStatus "@baseboard_fab2_lib.baseboard_fab2(sch_1):page74_i22:vss(845)" )
			)
			( pin "U2D1.AF73"
				( objectStatus "@baseboard_fab2_lib.baseboard_fab2(sch_1):page74_i22:vss(846)" )
			)
			( pin "U2D1.AF41"
				( objectStatus "@baseboard_fab2_lib.baseboard_fab2(sch_1):page74_i22:vss(847)" )
			)
			( pin "U2D1.AF39"
				( objectStatus "@baseboard_fab2_lib.baseboard_fab2(sch_1):page74_i22:vss(848)" )
			)
			( pin "U2D1.AF37"
				( objectStatus "@baseboard_fab2_lib.baseboard_fab2(sch_1):page74_i22:vss(849)" )
			)
			( pin "U2D1.AF33"
				( objectStatus "@baseboard_fab2_lib.baseboard_fab2(sch_1):page74_i22:vss(850)" )
			)
			( pin "U2D1.AF31"
				( objectStatus "@baseboard_fab2_lib.baseboard_fab2(sch_1):page74_i22:vss(851)" )
			)
			( pin "U2D1.AF29"
				( objectStatus "@baseboard_fab2_lib.baseboard_fab2(sch_1):page74_i22:vss(852)" )
			)
			( pin "U2D1.AF27"
				( objectStatus "@baseboard_fab2_lib.baseboard_fab2(sch_1):page74_i22:vss(853)" )
			)
			( pin "U2D1.AF25"
				( objectStatus "@baseboard_fab2_lib.baseboard_fab2(sch_1):page74_i22:vss(854)" )
			)
			( pin "U2D1.AF23"
				( objectStatus "@baseboard_fab2_lib.baseboard_fab2(sch_1):page74_i22:vss(855)" )
			)
			( pin "U2D1.AF21"
				( objectStatus "@baseboard_fab2_lib.baseboard_fab2(sch_1):page74_i22:vss(856)" )
			)
			( pin "U2D1.AF9"
				( objectStatus "@baseboard_fab2_lib.baseboard_fab2(sch_1):page74_i22:vss(857)" )
			)
			( pin "U2D1.AC52"
				( objectStatus "@baseboard_fab2_lib.baseboard_fab2(sch_1):page74_i22:vss(858)" )
			)
			( pin "U2D1.AF1"
				( objectStatus "@baseboard_fab2_lib.baseboard_fab2(sch_1):page74_i22:vss(859)" )
			)
			( pin "U2D1.AE78"
				( objectStatus "@baseboard_fab2_lib.baseboard_fab2(sch_1):page74_i22:vss(860)" )
			)
			( pin "U2D1.AE70"
				( objectStatus "@baseboard_fab2_lib.baseboard_fab2(sch_1):page74_i22:vss(861)" )
			)
			( pin "U2D1.AE68"
				( objectStatus "@baseboard_fab2_lib.baseboard_fab2(sch_1):page74_i22:vss(862)" )
			)
			( pin "U2D1.AE66"
				( objectStatus "@baseboard_fab2_lib.baseboard_fab2(sch_1):page74_i22:vss(863)" )
			)
			( pin "U2D1.AE64"
				( objectStatus "@baseboard_fab2_lib.baseboard_fab2(sch_1):page74_i22:vss(864)" )
			)
			( pin "U2D1.AE42"
				( objectStatus "@baseboard_fab2_lib.baseboard_fab2(sch_1):page74_i22:vss(865)" )
			)
			( pin "U2D1.AE40"
				( objectStatus "@baseboard_fab2_lib.baseboard_fab2(sch_1):page74_i22:vss(866)" )
			)
			( pin "U2D1.AE38"
				( objectStatus "@baseboard_fab2_lib.baseboard_fab2(sch_1):page74_i22:vss(867)" )
			)
			( pin "U2D1.AE16"
				( objectStatus "@baseboard_fab2_lib.baseboard_fab2(sch_1):page74_i22:vss(868)" )
			)
			( pin "U2D1.AC54"
				( objectStatus "@baseboard_fab2_lib.baseboard_fab2(sch_1):page74_i22:vss(869)" )
			)
			( pin "U2D1.AE8"
				( objectStatus "@baseboard_fab2_lib.baseboard_fab2(sch_1):page74_i22:vss(870)" )
			)
			( pin "U2D1.AE4"
				( objectStatus "@baseboard_fab2_lib.baseboard_fab2(sch_1):page74_i22:vss(871)" )
			)
			( pin "U2D1.AD85"
				( objectStatus "@baseboard_fab2_lib.baseboard_fab2(sch_1):page74_i22:vss(872)" )
			)
			( pin "U2D1.AD83"
				( objectStatus "@baseboard_fab2_lib.baseboard_fab2(sch_1):page74_i22:vss(873)" )
			)
			( pin "U2D1.AD81"
				( objectStatus "@baseboard_fab2_lib.baseboard_fab2(sch_1):page74_i22:vss(874)" )
			)
			( pin "U2D1.AD75"
				( objectStatus "@baseboard_fab2_lib.baseboard_fab2(sch_1):page74_i22:vss(875)" )
			)
			( pin "U2D1.AD73"
				( objectStatus "@baseboard_fab2_lib.baseboard_fab2(sch_1):page74_i22:vss(876)" )
			)
			( pin "U2D1.AD71"
				( objectStatus "@baseboard_fab2_lib.baseboard_fab2(sch_1):page74_i22:vss(877)" )
			)
			( pin "U2D1.AD43"
				( objectStatus "@baseboard_fab2_lib.baseboard_fab2(sch_1):page74_i22:vss(878)" )
			)
			( pin "U2D1.AD39"
				( objectStatus "@baseboard_fab2_lib.baseboard_fab2(sch_1):page74_i22:vss(879)" )
			)
			( pin "U2D1.AD33"
				( objectStatus "@baseboard_fab2_lib.baseboard_fab2(sch_1):page74_i22:vss(880)" )
			)
			( pin "U2D1.AD27"
				( objectStatus "@baseboard_fab2_lib.baseboard_fab2(sch_1):page74_i22:vss(881)" )
			)
			( pin "U2D1.AD21"
				( objectStatus "@baseboard_fab2_lib.baseboard_fab2(sch_1):page74_i22:vss(882)" )
			)
			( pin "U2D1.AD19"
				( objectStatus "@baseboard_fab2_lib.baseboard_fab2(sch_1):page74_i22:vss(883)" )
			)
			( pin "U2D1.AD15"
				( objectStatus "@baseboard_fab2_lib.baseboard_fab2(sch_1):page74_i22:vss(884)" )
			)
			( pin "U2D1.AD13"
				( objectStatus "@baseboard_fab2_lib.baseboard_fab2(sch_1):page74_i22:vss(885)" )
			)
			( pin "U2D1.AD11"
				( objectStatus "@baseboard_fab2_lib.baseboard_fab2(sch_1):page74_i22:vss(886)" )
			)
			( pin "U2D1.AD9"
				( objectStatus "@baseboard_fab2_lib.baseboard_fab2(sch_1):page74_i22:vss(887)" )
			)
			( pin "U2D1.AD7"
				( objectStatus "@baseboard_fab2_lib.baseboard_fab2(sch_1):page74_i22:vss(888)" )
			)
			( pin "U2D1.AD3"
				( objectStatus "@baseboard_fab2_lib.baseboard_fab2(sch_1):page74_i22:vss(889)" )
			)
			( pin "U2D1.AC86"
				( objectStatus "@baseboard_fab2_lib.baseboard_fab2(sch_1):page74_i22:vss(890)" )
			)
			( pin "U2D1.AC84"
				( objectStatus "@baseboard_fab2_lib.baseboard_fab2(sch_1):page74_i22:vss(891)" )
			)
			( pin "U2D1.AC78"
				( objectStatus "@baseboard_fab2_lib.baseboard_fab2(sch_1):page74_i22:vss(892)" )
			)
			( pin "U2D1.AC72"
				( objectStatus "@baseboard_fab2_lib.baseboard_fab2(sch_1):page74_i22:vss(893)" )
			)
			( pin "U2D1.AC70"
				( objectStatus "@baseboard_fab2_lib.baseboard_fab2(sch_1):page74_i22:vss(894)" )
			)
			( pin "U2D1.AC64"
				( objectStatus "@baseboard_fab2_lib.baseboard_fab2(sch_1):page74_i22:vss(895)" )
			)
			( pin "U2D1.AC40"
				( objectStatus "@baseboard_fab2_lib.baseboard_fab2(sch_1):page74_i22:vss(896)" )
			)
			( pin "U2D1.AC38"
				( objectStatus "@baseboard_fab2_lib.baseboard_fab2(sch_1):page74_i22:vss(897)" )
			)
			( pin "U2D1.AC34"
				( objectStatus "@baseboard_fab2_lib.baseboard_fab2(sch_1):page74_i22:vss(898)" )
			)
			( pin "U2D1.AC32"
				( objectStatus "@baseboard_fab2_lib.baseboard_fab2(sch_1):page74_i22:vss(899)" )
			)
			( pin "U2D1.AC28"
				( objectStatus "@baseboard_fab2_lib.baseboard_fab2(sch_1):page74_i22:vss(900)" )
			)
			( pin "U2D1.AC26"
				( objectStatus "@baseboard_fab2_lib.baseboard_fab2(sch_1):page74_i22:vss(901)" )
			)
			( pin "U2D1.AC22"
				( objectStatus "@baseboard_fab2_lib.baseboard_fab2(sch_1):page74_i22:vss(902)" )
			)
			( pin "U2D1.AC18"
				( objectStatus "@baseboard_fab2_lib.baseboard_fab2(sch_1):page74_i22:vss(903)" )
			)
			( pin "U2D1.AB85"
				( objectStatus "@baseboard_fab2_lib.baseboard_fab2(sch_1):page74_i22:vss(904)" )
			)
			( pin "U2D1.AB83"
				( objectStatus "@baseboard_fab2_lib.baseboard_fab2(sch_1):page74_i22:vss(905)" )
			)
			( pin "U2D1.AB79"
				( objectStatus "@baseboard_fab2_lib.baseboard_fab2(sch_1):page74_i22:vss(906)" )
			)
			( pin "U2D1.AB73"
				( objectStatus "@baseboard_fab2_lib.baseboard_fab2(sch_1):page74_i22:vss(907)" )
			)
			( pin "U2D1.AB69"
				( objectStatus "@baseboard_fab2_lib.baseboard_fab2(sch_1):page74_i22:vss(908)" )
			)
			( pin "U2D1.AB65"
				( objectStatus "@baseboard_fab2_lib.baseboard_fab2(sch_1):page74_i22:vss(909)" )
			)
			( pin "U2D1.AB41"
				( objectStatus "@baseboard_fab2_lib.baseboard_fab2(sch_1):page74_i22:vss(910)" )
			)
			( pin "U2D1.AB37"
				( objectStatus "@baseboard_fab2_lib.baseboard_fab2(sch_1):page74_i22:vss(911)" )
			)
			( pin "U2D1.AB35"
				( objectStatus "@baseboard_fab2_lib.baseboard_fab2(sch_1):page74_i22:vss(912)" )
			)
			( pin "U2D1.AB31"
				( objectStatus "@baseboard_fab2_lib.baseboard_fab2(sch_1):page74_i22:vss(913)" )
			)
			( pin "U2D1.AB29"
				( objectStatus "@baseboard_fab2_lib.baseboard_fab2(sch_1):page74_i22:vss(914)" )
			)
			( pin "U2D1.AB25"
				( objectStatus "@baseboard_fab2_lib.baseboard_fab2(sch_1):page74_i22:vss(915)" )
			)
			( pin "U2D1.AB23"
				( objectStatus "@baseboard_fab2_lib.baseboard_fab2(sch_1):page74_i22:vss(916)" )
			)
			( pin "U2D1.AB21"
				( objectStatus "@baseboard_fab2_lib.baseboard_fab2(sch_1):page74_i22:vss(917)" )
			)
			( pin "U2D1.AB11"
				( objectStatus "@baseboard_fab2_lib.baseboard_fab2(sch_1):page74_i22:vss(918)" )
			)
			( pin "U2D1.AB5"
				( objectStatus "@baseboard_fab2_lib.baseboard_fab2(sch_1):page74_i22:vss(919)" )
			)
			( pin "U2D1.AB1"
				( objectStatus "@baseboard_fab2_lib.baseboard_fab2(sch_1):page74_i22:vss(920)" )
			)
			( pin "U2D1.AA82"
				( objectStatus "@baseboard_fab2_lib.baseboard_fab2(sch_1):page74_i22:vss(921)" )
			)
			( pin "U2D1.AA80"
				( objectStatus "@baseboard_fab2_lib.baseboard_fab2(sch_1):page74_i22:vss(922)" )
			)
			( pin "U2D1.AA78"
				( objectStatus "@baseboard_fab2_lib.baseboard_fab2(sch_1):page74_i22:vss(923)" )
			)
			( pin "U2D1.AA76"
				( objectStatus "@baseboard_fab2_lib.baseboard_fab2(sch_1):page74_i22:vss(924)" )
			)
			( pin "U2D1.AA68"
				( objectStatus "@baseboard_fab2_lib.baseboard_fab2(sch_1):page74_i22:vss(925)" )
			)
			( pin "U2D1.AA66"
				( objectStatus "@baseboard_fab2_lib.baseboard_fab2(sch_1):page74_i22:vss(926)" )
			)
			( pin "U2D1.AA64"
				( objectStatus "@baseboard_fab2_lib.baseboard_fab2(sch_1):page74_i22:vss(927)" )
			)
			( pin "U2D1.AA42"
				( objectStatus "@baseboard_fab2_lib.baseboard_fab2(sch_1):page74_i22:vss(928)" )
			)
			( pin "U2D1.AA36"
				( objectStatus "@baseboard_fab2_lib.baseboard_fab2(sch_1):page74_i22:vss(929)" )
			)
			( pin "U2D1.AA30"
				( objectStatus "@baseboard_fab2_lib.baseboard_fab2(sch_1):page74_i22:vss(930)" )
			)
			( pin "U2D1.AA24"
				( objectStatus "@baseboard_fab2_lib.baseboard_fab2(sch_1):page74_i22:vss(931)" )
			)
			( pin "U2D1.AA22"
				( objectStatus "@baseboard_fab2_lib.baseboard_fab2(sch_1):page74_i22:vss(932)" )
			)
			( pin "U2D1.AA18"
				( objectStatus "@baseboard_fab2_lib.baseboard_fab2(sch_1):page74_i22:vss(933)" )
			)
			( pin "U2D1.BG72"
				( objectStatus "@baseboard_fab2_lib.baseboard_fab2(sch_1):page74_i23:vss(614)" )
			)
			( pin "U2D1.BG24"
				( objectStatus "@baseboard_fab2_lib.baseboard_fab2(sch_1):page74_i23:vss(615)" )
			)
			( pin "U2D1.BG22"
				( objectStatus "@baseboard_fab2_lib.baseboard_fab2(sch_1):page74_i23:vss(616)" )
			)
			( pin "U2D1.BG10"
				( objectStatus "@baseboard_fab2_lib.baseboard_fab2(sch_1):page74_i23:vss(617)" )
			)
			( pin "U2D1.BG8"
				( objectStatus "@baseboard_fab2_lib.baseboard_fab2(sch_1):page74_i23:vss(618)" )
			)
			( pin "U2D1.BG6"
				( objectStatus "@baseboard_fab2_lib.baseboard_fab2(sch_1):page74_i23:vss(619)" )
			)
			( pin "U2D1.BF71"
				( objectStatus "@baseboard_fab2_lib.baseboard_fab2(sch_1):page74_i23:vss(620)" )
			)
			( pin "U2D1.BF69"
				( objectStatus "@baseboard_fab2_lib.baseboard_fab2(sch_1):page74_i23:vss(621)" )
			)
			( pin "U2D1.BF67"
				( objectStatus "@baseboard_fab2_lib.baseboard_fab2(sch_1):page74_i23:vss(622)" )
			)
			( pin "U2D1.BF65"
				( objectStatus "@baseboard_fab2_lib.baseboard_fab2(sch_1):page74_i23:vss(623)" )
			)
			( pin "U2D1.BF63"
				( objectStatus "@baseboard_fab2_lib.baseboard_fab2(sch_1):page74_i23:vss(624)" )
			)
			( pin "U2D1.BF25"
				( objectStatus "@baseboard_fab2_lib.baseboard_fab2(sch_1):page74_i23:vss(625)" )
			)
			( pin "U2D1.BF19"
				( objectStatus "@baseboard_fab2_lib.baseboard_fab2(sch_1):page74_i23:vss(626)" )
			)
			( pin "U2D1.BF17"
				( objectStatus "@baseboard_fab2_lib.baseboard_fab2(sch_1):page74_i23:vss(627)" )
			)
			( pin "U2D1.BF15"
				( objectStatus "@baseboard_fab2_lib.baseboard_fab2(sch_1):page74_i23:vss(628)" )
			)
			( pin "U2D1.BF9"
				( objectStatus "@baseboard_fab2_lib.baseboard_fab2(sch_1):page74_i23:vss(629)" )
			)
			( pin "U2D1.BE70"
				( objectStatus "@baseboard_fab2_lib.baseboard_fab2(sch_1):page74_i23:vss(630)" )
			)
			( pin "U2D1.BE68"
				( objectStatus "@baseboard_fab2_lib.baseboard_fab2(sch_1):page74_i23:vss(631)" )
			)
			( pin "U2D1.BE66"
				( objectStatus "@baseboard_fab2_lib.baseboard_fab2(sch_1):page74_i23:vss(632)" )
			)
			( pin "U2D1.BE64"
				( objectStatus "@baseboard_fab2_lib.baseboard_fab2(sch_1):page74_i23:vss(633)" )
			)
			( pin "U2D1.BE26"
				( objectStatus "@baseboard_fab2_lib.baseboard_fab2(sch_1):page74_i23:vss(634)" )
			)
			( pin "U2D1.BE10"
				( objectStatus "@baseboard_fab2_lib.baseboard_fab2(sch_1):page74_i23:vss(635)" )
			)
			( pin "U2D1.BE8"
				( objectStatus "@baseboard_fab2_lib.baseboard_fab2(sch_1):page74_i23:vss(636)" )
			)
			( pin "U2D1.BE6"
				( objectStatus "@baseboard_fab2_lib.baseboard_fab2(sch_1):page74_i23:vss(637)" )
			)
			( pin "U2D1.BE4"
				( objectStatus "@baseboard_fab2_lib.baseboard_fab2(sch_1):page74_i23:vss(638)" )
			)
			( pin "U2D1.BD71"
				( objectStatus "@baseboard_fab2_lib.baseboard_fab2(sch_1):page74_i23:vss(639)" )
			)
			( pin "U2D1.BD63"
				( objectStatus "@baseboard_fab2_lib.baseboard_fab2(sch_1):page74_i23:vss(640)" )
			)
			( pin "U2D1.BD27"
				( objectStatus "@baseboard_fab2_lib.baseboard_fab2(sch_1):page74_i23:vss(641)" )
			)
			( pin "U2D1.BD21"
				( objectStatus "@baseboard_fab2_lib.baseboard_fab2(sch_1):page74_i23:vss(642)" )
			)
			( pin "U2D1.BD15"
				( objectStatus "@baseboard_fab2_lib.baseboard_fab2(sch_1):page74_i23:vss(643)" )
			)
			( pin "U2D1.BD11"
				( objectStatus "@baseboard_fab2_lib.baseboard_fab2(sch_1):page74_i23:vss(644)" )
			)
			( pin "U2D1.BD5"
				( objectStatus "@baseboard_fab2_lib.baseboard_fab2(sch_1):page74_i23:vss(645)" )
			)
			( pin "U2D1.BC82"
				( objectStatus "@baseboard_fab2_lib.baseboard_fab2(sch_1):page74_i23:vss(646)" )
			)
			( pin "U2D1.BC80"
				( objectStatus "@baseboard_fab2_lib.baseboard_fab2(sch_1):page74_i23:vss(647)" )
			)
			( pin "U2D1.BC78"
				( objectStatus "@baseboard_fab2_lib.baseboard_fab2(sch_1):page74_i23:vss(648)" )
			)
			( pin "U2D1.BC76"
				( objectStatus "@baseboard_fab2_lib.baseboard_fab2(sch_1):page74_i23:vss(649)" )
			)
			( pin "U2D1.BC74"
				( objectStatus "@baseboard_fab2_lib.baseboard_fab2(sch_1):page74_i23:vss(650)" )
			)
			( pin "U2D1.BC72"
				( objectStatus "@baseboard_fab2_lib.baseboard_fab2(sch_1):page74_i23:vss(651)" )
			)
			( pin "U2D1.BC70"
				( objectStatus "@baseboard_fab2_lib.baseboard_fab2(sch_1):page74_i23:vss(652)" )
			)
			( pin "U2D1.BC16"
				( objectStatus "@baseboard_fab2_lib.baseboard_fab2(sch_1):page74_i23:vss(653)" )
			)
			( pin "U2D1.BC12"
				( objectStatus "@baseboard_fab2_lib.baseboard_fab2(sch_1):page74_i23:vss(654)" )
			)
			( pin "U2D1.BC8"
				( objectStatus "@baseboard_fab2_lib.baseboard_fab2(sch_1):page74_i23:vss(655)" )
			)
			( pin "U2D1.BC4"
				( objectStatus "@baseboard_fab2_lib.baseboard_fab2(sch_1):page74_i23:vss(656)" )
			)
			( pin "U2D1.BB83"
				( objectStatus "@baseboard_fab2_lib.baseboard_fab2(sch_1):page74_i23:vss(657)" )
			)
			( pin "U2D1.BB81"
				( objectStatus "@baseboard_fab2_lib.baseboard_fab2(sch_1):page74_i23:vss(658)" )
			)
			( pin "U2D1.BB79"
				( objectStatus "@baseboard_fab2_lib.baseboard_fab2(sch_1):page74_i23:vss(659)" )
			)
			( pin "U2D1.BB77"
				( objectStatus "@baseboard_fab2_lib.baseboard_fab2(sch_1):page74_i23:vss(660)" )
			)
			( pin "U2D1.BB75"
				( objectStatus "@baseboard_fab2_lib.baseboard_fab2(sch_1):page74_i23:vss(661)" )
			)
			( pin "U2D1.BB73"
				( objectStatus "@baseboard_fab2_lib.baseboard_fab2(sch_1):page74_i23:vss(662)" )
			)
			( pin "U2D1.BB69"
				( objectStatus "@baseboard_fab2_lib.baseboard_fab2(sch_1):page74_i23:vss(663)" )
			)
			( pin "U2D1.BB63"
				( objectStatus "@baseboard_fab2_lib.baseboard_fab2(sch_1):page74_i23:vss(664)" )
			)
			( pin "U2D1.BB23"
				( objectStatus "@baseboard_fab2_lib.baseboard_fab2(sch_1):page74_i23:vss(665)" )
			)
			( pin "U2D1.BB19"
				( objectStatus "@baseboard_fab2_lib.baseboard_fab2(sch_1):page74_i23:vss(666)" )
			)
			( pin "U2D1.BA84"
				( objectStatus "@baseboard_fab2_lib.baseboard_fab2(sch_1):page74_i23:vss(667)" )
			)
			( pin "U2D1.BA80"
				( objectStatus "@baseboard_fab2_lib.baseboard_fab2(sch_1):page74_i23:vss(668)" )
			)
			( pin "U2D1.BA74"
				( objectStatus "@baseboard_fab2_lib.baseboard_fab2(sch_1):page74_i23:vss(669)" )
			)
			( pin "U2D1.BA68"
				( objectStatus "@baseboard_fab2_lib.baseboard_fab2(sch_1):page74_i23:vss(670)" )
			)
			( pin "U2D1.BA62"
				( objectStatus "@baseboard_fab2_lib.baseboard_fab2(sch_1):page74_i23:vss(671)" )
			)
			( pin "U2D1.BA12"
				( objectStatus "@baseboard_fab2_lib.baseboard_fab2(sch_1):page74_i23:vss(672)" )
			)
			( pin "U2D1.BA6"
				( objectStatus "@baseboard_fab2_lib.baseboard_fab2(sch_1):page74_i23:vss(673)" )
			)
			( pin "U2D1.BA2"
				( objectStatus "@baseboard_fab2_lib.baseboard_fab2(sch_1):page74_i23:vss(674)" )
			)
			( pin "U2D1.AY81"
				( objectStatus "@baseboard_fab2_lib.baseboard_fab2(sch_1):page74_i23:vss(675)" )
			)
			( pin "U2D1.AY79"
				( objectStatus "@baseboard_fab2_lib.baseboard_fab2(sch_1):page74_i23:vss(676)" )
			)
			( pin "U2D1.AY63"
				( objectStatus "@baseboard_fab2_lib.baseboard_fab2(sch_1):page74_i23:vss(677)" )
			)
			( pin "U2D1.AY25"
				( objectStatus "@baseboard_fab2_lib.baseboard_fab2(sch_1):page74_i23:vss(678)" )
			)
			( pin "U2D1.AY23"
				( objectStatus "@baseboard_fab2_lib.baseboard_fab2(sch_1):page74_i23:vss(679)" )
			)
			( pin "U2D1.AY21"
				( objectStatus "@baseboard_fab2_lib.baseboard_fab2(sch_1):page74_i23:vss(680)" )
			)
			( pin "U2D1.AY17"
				( objectStatus "@baseboard_fab2_lib.baseboard_fab2(sch_1):page74_i23:vss(681)" )
			)
			( pin "U2D1.AY15"
				( objectStatus "@baseboard_fab2_lib.baseboard_fab2(sch_1):page74_i23:vss(682)" )
			)
			( pin "U2D1.AY5"
				( objectStatus "@baseboard_fab2_lib.baseboard_fab2(sch_1):page74_i23:vss(683)" )
			)
			( pin "U2D1.AW84"
				( objectStatus "@baseboard_fab2_lib.baseboard_fab2(sch_1):page74_i23:vss(684)" )
			)
			( pin "U2D1.AW82"
				( objectStatus "@baseboard_fab2_lib.baseboard_fab2(sch_1):page74_i23:vss(685)" )
			)
			( pin "U2D1.AW78"
				( objectStatus "@baseboard_fab2_lib.baseboard_fab2(sch_1):page74_i23:vss(686)" )
			)
			( pin "U2D1.AW74"
				( objectStatus "@baseboard_fab2_lib.baseboard_fab2(sch_1):page74_i23:vss(687)" )
			)
			( pin "U2D1.AW72"
				( objectStatus "@baseboard_fab2_lib.baseboard_fab2(sch_1):page74_i23:vss(688)" )
			)
			( pin "U2D1.AW70"
				( objectStatus "@baseboard_fab2_lib.baseboard_fab2(sch_1):page74_i23:vss(689)" )
			)
			( pin "U2D1.AW68"
				( objectStatus "@baseboard_fab2_lib.baseboard_fab2(sch_1):page74_i23:vss(690)" )
			)
			( pin "U2D1.AW66"
				( objectStatus "@baseboard_fab2_lib.baseboard_fab2(sch_1):page74_i23:vss(691)" )
			)
			( pin "U2D1.AW62"
				( objectStatus "@baseboard_fab2_lib.baseboard_fab2(sch_1):page74_i23:vss(692)" )
			)
			( pin "U2D1.AW10"
				( objectStatus "@baseboard_fab2_lib.baseboard_fab2(sch_1):page74_i23:vss(693)" )
			)
			( pin "U2D1.AW2"
				( objectStatus "@baseboard_fab2_lib.baseboard_fab2(sch_1):page74_i23:vss(694)" )
			)
			( pin "U2D1.AV83"
				( objectStatus "@baseboard_fab2_lib.baseboard_fab2(sch_1):page74_i23:vss(695)" )
			)
			( pin "U2D1.AV75"
				( objectStatus "@baseboard_fab2_lib.baseboard_fab2(sch_1):page74_i23:vss(696)" )
			)
			( pin "U2D1.AV67"
				( objectStatus "@baseboard_fab2_lib.baseboard_fab2(sch_1):page74_i23:vss(697)" )
			)
			( pin "U2D1.AV65"
				( objectStatus "@baseboard_fab2_lib.baseboard_fab2(sch_1):page74_i23:vss(698)" )
			)
			( pin "U2D1.AV63"
				( objectStatus "@baseboard_fab2_lib.baseboard_fab2(sch_1):page74_i23:vss(699)" )
			)
			( pin "U2D1.AV25"
				( objectStatus "@baseboard_fab2_lib.baseboard_fab2(sch_1):page74_i23:vss(700)" )
			)
			( pin "U2D1.AV23"
				( objectStatus "@baseboard_fab2_lib.baseboard_fab2(sch_1):page74_i23:vss(701)" )
			)
			( pin "U2D1.AV19"
				( objectStatus "@baseboard_fab2_lib.baseboard_fab2(sch_1):page74_i23:vss(702)" )
			)
			( pin "U2D1.AV13"
				( objectStatus "@baseboard_fab2_lib.baseboard_fab2(sch_1):page74_i23:vss(703)" )
			)
			( pin "U2D1.AV11"
				( objectStatus "@baseboard_fab2_lib.baseboard_fab2(sch_1):page74_i23:vss(704)" )
			)
			( pin "U2D1.AV7"
				( objectStatus "@baseboard_fab2_lib.baseboard_fab2(sch_1):page74_i23:vss(705)" )
			)
			( pin "U2D1.AV3"
				( objectStatus "@baseboard_fab2_lib.baseboard_fab2(sch_1):page74_i23:vss(706)" )
			)
			( pin "U2D1.AV1"
				( objectStatus "@baseboard_fab2_lib.baseboard_fab2(sch_1):page74_i23:vss(707)" )
			)
			( pin "U2D1.AU86"
				( objectStatus "@baseboard_fab2_lib.baseboard_fab2(sch_1):page74_i23:vss(708)" )
			)
			( pin "U2D1.AU84"
				( objectStatus "@baseboard_fab2_lib.baseboard_fab2(sch_1):page74_i23:vss(709)" )
			)
			( pin "U2D1.AU80"
				( objectStatus "@baseboard_fab2_lib.baseboard_fab2(sch_1):page74_i23:vss(710)" )
			)
			( pin "U2D1.AU78"
				( objectStatus "@baseboard_fab2_lib.baseboard_fab2(sch_1):page74_i23:vss(711)" )
			)
			( pin "U2D1.AU76"
				( objectStatus "@baseboard_fab2_lib.baseboard_fab2(sch_1):page74_i23:vss(712)" )
			)
			( pin "U2D1.AU74"
				( objectStatus "@baseboard_fab2_lib.baseboard_fab2(sch_1):page74_i23:vss(713)" )
			)
			( pin "U2D1.AU68"
				( objectStatus "@baseboard_fab2_lib.baseboard_fab2(sch_1):page74_i23:vss(714)" )
			)
			( pin "U2D1.AU64"
				( objectStatus "@baseboard_fab2_lib.baseboard_fab2(sch_1):page74_i23:vss(715)" )
			)
			( pin "U2D1.AU62"
				( objectStatus "@baseboard_fab2_lib.baseboard_fab2(sch_1):page74_i23:vss(716)" )
			)
			( pin "U2D1.AU28"
				( objectStatus "@baseboard_fab2_lib.baseboard_fab2(sch_1):page74_i23:vss(717)" )
			)
			( pin "U2D1.AU26"
				( objectStatus "@baseboard_fab2_lib.baseboard_fab2(sch_1):page74_i23:vss(718)" )
			)
			( pin "U2D1.AU6"
				( objectStatus "@baseboard_fab2_lib.baseboard_fab2(sch_1):page74_i23:vss(719)" )
			)
			( pin "U2D1.AU2"
				( objectStatus "@baseboard_fab2_lib.baseboard_fab2(sch_1):page74_i23:vss(720)" )
			)
			( pin "U2D1.AT85"
				( objectStatus "@baseboard_fab2_lib.baseboard_fab2(sch_1):page74_i23:vss(721)" )
			)
			( pin "U2D1.AT83"
				( objectStatus "@baseboard_fab2_lib.baseboard_fab2(sch_1):page74_i23:vss(722)" )
			)
			( pin "U2D1.AT77"
				( objectStatus "@baseboard_fab2_lib.baseboard_fab2(sch_1):page74_i23:vss(723)" )
			)
			( pin "U2D1.AT73"
				( objectStatus "@baseboard_fab2_lib.baseboard_fab2(sch_1):page74_i23:vss(724)" )
			)
			( pin "U2D1.AT69"
				( objectStatus "@baseboard_fab2_lib.baseboard_fab2(sch_1):page74_i23:vss(725)" )
			)
			( pin "U2D1.AT63"
				( objectStatus "@baseboard_fab2_lib.baseboard_fab2(sch_1):page74_i23:vss(726)" )
			)
			( pin "U2D1.AT61"
				( objectStatus "@baseboard_fab2_lib.baseboard_fab2(sch_1):page74_i23:vss(727)" )
			)
			( pin "U2D1.AT27"
				( objectStatus "@baseboard_fab2_lib.baseboard_fab2(sch_1):page74_i23:vss(728)" )
			)
			( pin "U2D1.AT21"
				( objectStatus "@baseboard_fab2_lib.baseboard_fab2(sch_1):page74_i23:vss(729)" )
			)
			( pin "U2D1.AT17"
				( objectStatus "@baseboard_fab2_lib.baseboard_fab2(sch_1):page74_i23:vss(730)" )
			)
			( pin "U2D1.AT15"
				( objectStatus "@baseboard_fab2_lib.baseboard_fab2(sch_1):page74_i23:vss(731)" )
			)
			( pin "U2D1.P63"
				( objectStatus "@baseboard_fab2_lib.baseboard_fab2(sch_1):page74_i23:vss(732)" )
			)
			( pin "U2D1.AC48"
				( objectStatus "@baseboard_fab2_lib.baseboard_fab2(sch_1):page74_i23:vss(733)" )
			)
			( pin "U2D1.AR78"
				( objectStatus "@baseboard_fab2_lib.baseboard_fab2(sch_1):page74_i23:vss(734)" )
			)
			( pin "U2D1.AR72"
				( objectStatus "@baseboard_fab2_lib.baseboard_fab2(sch_1):page74_i23:vss(735)" )
			)
			( pin "U2D1.AR60"
				( objectStatus "@baseboard_fab2_lib.baseboard_fab2(sch_1):page74_i23:vss(736)" )
			)
			( pin "U2D1.AR30"
				( objectStatus "@baseboard_fab2_lib.baseboard_fab2(sch_1):page74_i23:vss(737)" )
			)
			( pin "U2D1.AR24"
				( objectStatus "@baseboard_fab2_lib.baseboard_fab2(sch_1):page74_i23:vss(738)" )
			)
			( pin "U2D1.AR10"
				( objectStatus "@baseboard_fab2_lib.baseboard_fab2(sch_1):page74_i23:vss(739)" )
			)
			( pin "U2D1.AP85"
				( objectStatus "@baseboard_fab2_lib.baseboard_fab2(sch_1):page74_i23:vss(740)" )
			)
			( pin "U2D1.AP83"
				( objectStatus "@baseboard_fab2_lib.baseboard_fab2(sch_1):page74_i23:vss(741)" )
			)
			( pin "U2D1.AP81"
				( objectStatus "@baseboard_fab2_lib.baseboard_fab2(sch_1):page74_i23:vss(742)" )
			)
			( pin "U2D1.AP75"
				( objectStatus "@baseboard_fab2_lib.baseboard_fab2(sch_1):page74_i23:vss(743)" )
			)
			( pin "U2D1.AP73"
				( objectStatus "@baseboard_fab2_lib.baseboard_fab2(sch_1):page74_i23:vss(744)" )
			)
			( pin "U2D1.AP69"
				( objectStatus "@baseboard_fab2_lib.baseboard_fab2(sch_1):page74_i23:vss(745)" )
			)
			( pin "U2D1.AP67"
				( objectStatus "@baseboard_fab2_lib.baseboard_fab2(sch_1):page74_i23:vss(746)" )
			)
			( pin "U2D1.AP65"
				( objectStatus "@baseboard_fab2_lib.baseboard_fab2(sch_1):page74_i23:vss(747)" )
			)
			( pin "U2D1.AP63"
				( objectStatus "@baseboard_fab2_lib.baseboard_fab2(sch_1):page74_i23:vss(748)" )
			)
			( pin "U2D1.AP59"
				( objectStatus "@baseboard_fab2_lib.baseboard_fab2(sch_1):page74_i23:vss(749)" )
			)
			( pin "U2D1.AP31"
				( objectStatus "@baseboard_fab2_lib.baseboard_fab2(sch_1):page74_i23:vss(750)" )
			)
			( pin "U2D1.AP19"
				( objectStatus "@baseboard_fab2_lib.baseboard_fab2(sch_1):page74_i23:vss(751)" )
			)
			( pin "U2D1.AP13"
				( objectStatus "@baseboard_fab2_lib.baseboard_fab2(sch_1):page74_i23:vss(752)" )
			)
			( pin "U2D1.AP9"
				( objectStatus "@baseboard_fab2_lib.baseboard_fab2(sch_1):page74_i23:vss(753)" )
			)
			( pin "U2D1.AP5"
				( objectStatus "@baseboard_fab2_lib.baseboard_fab2(sch_1):page74_i23:vss(754)" )
			)
			( pin "U2D1.AN78"
				( objectStatus "@baseboard_fab2_lib.baseboard_fab2(sch_1):page74_i23:vss(755)" )
			)
			( pin "U2D1.AN58"
				( objectStatus "@baseboard_fab2_lib.baseboard_fab2(sch_1):page74_i23:vss(756)" )
			)
			( pin "U2D1.AN28"
				( objectStatus "@baseboard_fab2_lib.baseboard_fab2(sch_1):page74_i23:vss(757)" )
			)
			( pin "U2D1.AN6"
				( objectStatus "@baseboard_fab2_lib.baseboard_fab2(sch_1):page74_i23:vss(758)" )
			)
			( pin "U2D1.AN2"
				( objectStatus "@baseboard_fab2_lib.baseboard_fab2(sch_1):page74_i23:vss(759)" )
			)
			( pin "U2D1.AM83"
				( objectStatus "@baseboard_fab2_lib.baseboard_fab2(sch_1):page74_i23:vss(760)" )
			)
			( pin "U2D1.AM79"
				( objectStatus "@baseboard_fab2_lib.baseboard_fab2(sch_1):page74_i23:vss(761)" )
			)
			( pin "U2D1.AM73"
				( objectStatus "@baseboard_fab2_lib.baseboard_fab2(sch_1):page74_i23:vss(762)" )
			)
			( pin "U2D1.AM69"
				( objectStatus "@baseboard_fab2_lib.baseboard_fab2(sch_1):page74_i23:vss(763)" )
			)
			( pin "U2D1.AM63"
				( objectStatus "@baseboard_fab2_lib.baseboard_fab2(sch_1):page74_i23:vss(764)" )
			)
			( pin "U2D1.AM57"
				( objectStatus "@baseboard_fab2_lib.baseboard_fab2(sch_1):page74_i23:vss(765)" )
			)
			( pin "U2D1.AM31"
				( objectStatus "@baseboard_fab2_lib.baseboard_fab2(sch_1):page74_i23:vss(766)" )
			)
			( pin "U2D1.AC50"
				( objectStatus "@baseboard_fab2_lib.baseboard_fab2(sch_1):page74_i23:vss(767)" )
			)
			( pin "U2D1.AM1"
				( objectStatus "@baseboard_fab2_lib.baseboard_fab2(sch_1):page74_i23:vss(768)" )
			)
			( pin "U2D1.AL86"
				( objectStatus "@baseboard_fab2_lib.baseboard_fab2(sch_1):page74_i23:vss(769)" )
			)
			( pin "U2D1.AL82"
				( objectStatus "@baseboard_fab2_lib.baseboard_fab2(sch_1):page74_i23:vss(770)" )
			)
			( pin "U2D1.AL80"
				( objectStatus "@baseboard_fab2_lib.baseboard_fab2(sch_1):page74_i23:vss(771)" )
			)
			( pin "U2D1.AL78"
				( objectStatus "@baseboard_fab2_lib.baseboard_fab2(sch_1):page74_i23:vss(772)" )
			)
			( pin "U2D1.AL76"
				( objectStatus "@baseboard_fab2_lib.baseboard_fab2(sch_1):page74_i23:vss(773)" )
			)
			( pin "U2D1.P49"
				( objectStatus "@baseboard_fab2_lib.baseboard_fab2(sch_1):page75_i17:vss(454)" )
			)
			( pin "U2D1.CJ12"
				( objectStatus "@baseboard_fab2_lib.baseboard_fab2(sch_1):page75_i17:vss(455)" )
			)
			( pin "U2D1.CJ10"
				( objectStatus "@baseboard_fab2_lib.baseboard_fab2(sch_1):page75_i17:vss(456)" )
			)
			( pin "U2D1.CJ8"
				( objectStatus "@baseboard_fab2_lib.baseboard_fab2(sch_1):page75_i17:vss(457)" )
			)
			( pin "U2D1.CJ6"
				( objectStatus "@baseboard_fab2_lib.baseboard_fab2(sch_1):page75_i17:vss(458)" )
			)
			( pin "U2D1.CJ2"
				( objectStatus "@baseboard_fab2_lib.baseboard_fab2(sch_1):page75_i17:vss(459)" )
			)
			( pin "U2D1.CH83"
				( objectStatus "@baseboard_fab2_lib.baseboard_fab2(sch_1):page75_i17:vss(460)" )
			)
			( pin "U2D1.CH81"
				( objectStatus "@baseboard_fab2_lib.baseboard_fab2(sch_1):page75_i17:vss(461)" )
			)
			( pin "U2D1.CH79"
				( objectStatus "@baseboard_fab2_lib.baseboard_fab2(sch_1):page75_i17:vss(462)" )
			)
			( pin "U2D1.CH73"
				( objectStatus "@baseboard_fab2_lib.baseboard_fab2(sch_1):page75_i17:vss(463)" )
			)
			( pin "U2D1.CH67"
				( objectStatus "@baseboard_fab2_lib.baseboard_fab2(sch_1):page75_i17:vss(464)" )
			)
			( pin "U2D1.CH63"
				( objectStatus "@baseboard_fab2_lib.baseboard_fab2(sch_1):page75_i17:vss(465)" )
			)
			( pin "U2D1.CH19"
				( objectStatus "@baseboard_fab2_lib.baseboard_fab2(sch_1):page75_i17:vss(466)" )
			)
			( pin "U2D1.CH15"
				( objectStatus "@baseboard_fab2_lib.baseboard_fab2(sch_1):page75_i17:vss(467)" )
			)
			( pin "U2D1.CH3"
				( objectStatus "@baseboard_fab2_lib.baseboard_fab2(sch_1):page75_i17:vss(468)" )
			)
			( pin "U2D1.CH1"
				( objectStatus "@baseboard_fab2_lib.baseboard_fab2(sch_1):page75_i17:vss(469)" )
			)
			( pin "U2D1.CG80"
				( objectStatus "@baseboard_fab2_lib.baseboard_fab2(sch_1):page75_i17:vss(470)" )
			)
			( pin "U2D1.CG72"
				( objectStatus "@baseboard_fab2_lib.baseboard_fab2(sch_1):page75_i17:vss(471)" )
			)
			( pin "U2D1.CG68"
				( objectStatus "@baseboard_fab2_lib.baseboard_fab2(sch_1):page75_i17:vss(472)" )
			)
			( pin "U2D1.CG62"
				( objectStatus "@baseboard_fab2_lib.baseboard_fab2(sch_1):page75_i17:vss(473)" )
			)
			( pin "U2D1.CG22"
				( objectStatus "@baseboard_fab2_lib.baseboard_fab2(sch_1):page75_i17:vss(474)" )
			)
			( pin "U2D1.CG18"
				( objectStatus "@baseboard_fab2_lib.baseboard_fab2(sch_1):page75_i17:vss(475)" )
			)
			( pin "U2D1.P51"
				( objectStatus "@baseboard_fab2_lib.baseboard_fab2(sch_1):page75_i17:vss(476)" )
			)
			( pin "U2D1.CF83"
				( objectStatus "@baseboard_fab2_lib.baseboard_fab2(sch_1):page75_i17:vss(477)" )
			)
			( pin "U2D1.CF77"
				( objectStatus "@baseboard_fab2_lib.baseboard_fab2(sch_1):page75_i17:vss(478)" )
			)
			( pin "U2D1.CF71"
				( objectStatus "@baseboard_fab2_lib.baseboard_fab2(sch_1):page75_i17:vss(479)" )
			)
			( pin "U2D1.CF69"
				( objectStatus "@baseboard_fab2_lib.baseboard_fab2(sch_1):page75_i17:vss(480)" )
			)
			( pin "U2D1.CF63"
				( objectStatus "@baseboard_fab2_lib.baseboard_fab2(sch_1):page75_i17:vss(481)" )
			)
			( pin "U2D1.CF9"
				( objectStatus "@baseboard_fab2_lib.baseboard_fab2(sch_1):page75_i17:vss(482)" )
			)
			( pin "U2D1.P53"
				( objectStatus "@baseboard_fab2_lib.baseboard_fab2(sch_1):page75_i17:vss(483)" )
			)
			( pin "U2D1.CE82"
				( objectStatus "@baseboard_fab2_lib.baseboard_fab2(sch_1):page75_i17:vss(484)" )
			)
			( pin "U2D1.CE70"
				( objectStatus "@baseboard_fab2_lib.baseboard_fab2(sch_1):page75_i17:vss(485)" )
			)
			( pin "U2D1.CE62"
				( objectStatus "@baseboard_fab2_lib.baseboard_fab2(sch_1):page75_i17:vss(486)" )
			)
			( pin "U2D1.CE26"
				( objectStatus "@baseboard_fab2_lib.baseboard_fab2(sch_1):page75_i17:vss(487)" )
			)
			( pin "U2D1.CE20"
				( objectStatus "@baseboard_fab2_lib.baseboard_fab2(sch_1):page75_i17:vss(488)" )
			)
			( pin "U2D1.CE14"
				( objectStatus "@baseboard_fab2_lib.baseboard_fab2(sch_1):page75_i17:vss(489)" )
			)
			( pin "U2D1.CE10"
				( objectStatus "@baseboard_fab2_lib.baseboard_fab2(sch_1):page75_i17:vss(490)" )
			)
			( pin "U2D1.CD81"
				( objectStatus "@baseboard_fab2_lib.baseboard_fab2(sch_1):page75_i17:vss(491)" )
			)
			( pin "U2D1.CD79"
				( objectStatus "@baseboard_fab2_lib.baseboard_fab2(sch_1):page75_i17:vss(492)" )
			)
			( pin "U2D1.CD77"
				( objectStatus "@baseboard_fab2_lib.baseboard_fab2(sch_1):page75_i17:vss(493)" )
			)
			( pin "U2D1.CD75"
				( objectStatus "@baseboard_fab2_lib.baseboard_fab2(sch_1):page75_i17:vss(494)" )
			)
			( pin "U2D1.CD73"
				( objectStatus "@baseboard_fab2_lib.baseboard_fab2(sch_1):page75_i17:vss(495)" )
			)
			( pin "U2D1.CD63"
				( objectStatus "@baseboard_fab2_lib.baseboard_fab2(sch_1):page75_i17:vss(496)" )
			)
			( pin "U2D1.CD13"
				( objectStatus "@baseboard_fab2_lib.baseboard_fab2(sch_1):page75_i17:vss(497)" )
			)
			( pin "U2D1.CD5"
				( objectStatus "@baseboard_fab2_lib.baseboard_fab2(sch_1):page75_i17:vss(498)" )
			)
			( pin "U2D1.CC82"
				( objectStatus "@baseboard_fab2_lib.baseboard_fab2(sch_1):page75_i17:vss(499)" )
			)
			( pin "U2D1.CC80"
				( objectStatus "@baseboard_fab2_lib.baseboard_fab2(sch_1):page75_i17:vss(500)" )
			)
			( pin "U2D1.CC78"
				( objectStatus "@baseboard_fab2_lib.baseboard_fab2(sch_1):page75_i17:vss(501)" )
			)
			( pin "U2D1.CC76"
				( objectStatus "@baseboard_fab2_lib.baseboard_fab2(sch_1):page75_i17:vss(502)" )
			)
			( pin "U2D1.CC74"
				( objectStatus "@baseboard_fab2_lib.baseboard_fab2(sch_1):page75_i17:vss(503)" )
			)
			( pin "U2D1.CC72"
				( objectStatus "@baseboard_fab2_lib.baseboard_fab2(sch_1):page75_i17:vss(504)" )
			)
			( pin "U2D1.CC64"
				( objectStatus "@baseboard_fab2_lib.baseboard_fab2(sch_1):page75_i17:vss(505)" )
			)
			( pin "U2D1.CC24"
				( objectStatus "@baseboard_fab2_lib.baseboard_fab2(sch_1):page75_i17:vss(506)" )
			)
			( pin "U2D1.CC18"
				( objectStatus "@baseboard_fab2_lib.baseboard_fab2(sch_1):page75_i17:vss(507)" )
			)
			( pin "U2D1.CC16"
				( objectStatus "@baseboard_fab2_lib.baseboard_fab2(sch_1):page75_i17:vss(508)" )
			)
			( pin "U2D1.CC4"
				( objectStatus "@baseboard_fab2_lib.baseboard_fab2(sch_1):page75_i17:vss(509)" )
			)
			( pin "U2D1.CB71"
				( objectStatus "@baseboard_fab2_lib.baseboard_fab2(sch_1):page75_i17:vss(510)" )
			)
			( pin "U2D1.CB63"
				( objectStatus "@baseboard_fab2_lib.baseboard_fab2(sch_1):page75_i17:vss(511)" )
			)
			( pin "U2D1.CB27"
				( objectStatus "@baseboard_fab2_lib.baseboard_fab2(sch_1):page75_i17:vss(512)" )
			)
			( pin "U2D1.CB9"
				( objectStatus "@baseboard_fab2_lib.baseboard_fab2(sch_1):page75_i17:vss(513)" )
			)
			( pin "U2D1.CB7"
				( objectStatus "@baseboard_fab2_lib.baseboard_fab2(sch_1):page75_i17:vss(514)" )
			)
			( pin "U2D1.CA70"
				( objectStatus "@baseboard_fab2_lib.baseboard_fab2(sch_1):page75_i17:vss(515)" )
			)
			( pin "U2D1.CA68"
				( objectStatus "@baseboard_fab2_lib.baseboard_fab2(sch_1):page75_i17:vss(516)" )
			)
			( pin "U2D1.CA66"
				( objectStatus "@baseboard_fab2_lib.baseboard_fab2(sch_1):page75_i17:vss(517)" )
			)
			( pin "U2D1.CA64"
				( objectStatus "@baseboard_fab2_lib.baseboard_fab2(sch_1):page75_i17:vss(518)" )
			)
			( pin "U2D1.CA26"
				( objectStatus "@baseboard_fab2_lib.baseboard_fab2(sch_1):page75_i17:vss(519)" )
			)
			( pin "U2D1.CA18"
				( objectStatus "@baseboard_fab2_lib.baseboard_fab2(sch_1):page75_i17:vss(520)" )
			)
			( pin "U2D1.CA14"
				( objectStatus "@baseboard_fab2_lib.baseboard_fab2(sch_1):page75_i17:vss(521)" )
			)
			( pin "U2D1.CA10"
				( objectStatus "@baseboard_fab2_lib.baseboard_fab2(sch_1):page75_i17:vss(522)" )
			)
			( pin "U2D1.CA8"
				( objectStatus "@baseboard_fab2_lib.baseboard_fab2(sch_1):page75_i17:vss(523)" )
			)
			( pin "U2D1.CA6"
				( objectStatus "@baseboard_fab2_lib.baseboard_fab2(sch_1):page75_i17:vss(524)" )
			)
			( pin "U2D1.CA2"
				( objectStatus "@baseboard_fab2_lib.baseboard_fab2(sch_1):page75_i17:vss(525)" )
			)
			( pin "U2D1.BY71"
				( objectStatus "@baseboard_fab2_lib.baseboard_fab2(sch_1):page75_i17:vss(526)" )
			)
			( pin "U2D1.BY69"
				( objectStatus "@baseboard_fab2_lib.baseboard_fab2(sch_1):page75_i17:vss(527)" )
			)
			( pin "U2D1.BY67"
				( objectStatus "@baseboard_fab2_lib.baseboard_fab2(sch_1):page75_i17:vss(528)" )
			)
			( pin "U2D1.BY65"
				( objectStatus "@baseboard_fab2_lib.baseboard_fab2(sch_1):page75_i17:vss(529)" )
			)
			( pin "U2D1.BY63"
				( objectStatus "@baseboard_fab2_lib.baseboard_fab2(sch_1):page75_i17:vss(530)" )
			)
			( pin "U2D1.BY23"
				( objectStatus "@baseboard_fab2_lib.baseboard_fab2(sch_1):page75_i17:vss(531)" )
			)
			( pin "U2D1.BY13"
				( objectStatus "@baseboard_fab2_lib.baseboard_fab2(sch_1):page75_i17:vss(532)" )
			)
			( pin "U2D1.BY11"
				( objectStatus "@baseboard_fab2_lib.baseboard_fab2(sch_1):page75_i17:vss(533)" )
			)
			( pin "U2D1.BW82"
				( objectStatus "@baseboard_fab2_lib.baseboard_fab2(sch_1):page75_i17:vss(534)" )
			)
			( pin "U2D1.BW80"
				( objectStatus "@baseboard_fab2_lib.baseboard_fab2(sch_1):page75_i17:vss(535)" )
			)
			( pin "U2D1.BW78"
				( objectStatus "@baseboard_fab2_lib.baseboard_fab2(sch_1):page75_i17:vss(536)" )
			)
			( pin "U2D1.BW76"
				( objectStatus "@baseboard_fab2_lib.baseboard_fab2(sch_1):page75_i17:vss(537)" )
			)
			( pin "U2D1.BW74"
				( objectStatus "@baseboard_fab2_lib.baseboard_fab2(sch_1):page75_i17:vss(538)" )
			)
			( pin "U2D1.BW72"
				( objectStatus "@baseboard_fab2_lib.baseboard_fab2(sch_1):page75_i17:vss(539)" )
			)
			( pin "U2D1.BW26"
				( objectStatus "@baseboard_fab2_lib.baseboard_fab2(sch_1):page75_i17:vss(540)" )
			)
			( pin "U2D1.BW18"
				( objectStatus "@baseboard_fab2_lib.baseboard_fab2(sch_1):page75_i17:vss(541)" )
			)
			( pin "U2D1.BW16"
				( objectStatus "@baseboard_fab2_lib.baseboard_fab2(sch_1):page75_i17:vss(542)" )
			)
			( pin "U2D1.BW14"
				( objectStatus "@baseboard_fab2_lib.baseboard_fab2(sch_1):page75_i17:vss(543)" )
			)
			( pin "U2D1.BW12"
				( objectStatus "@baseboard_fab2_lib.baseboard_fab2(sch_1):page75_i17:vss(544)" )
			)
			( pin "U2D1.P55"
				( objectStatus "@baseboard_fab2_lib.baseboard_fab2(sch_1):page75_i17:vss(545)" )
			)
			( pin "U2D1.BW6"
				( objectStatus "@baseboard_fab2_lib.baseboard_fab2(sch_1):page75_i17:vss(546)" )
			)
			( pin "U2D1.BV25"
				( objectStatus "@baseboard_fab2_lib.baseboard_fab2(sch_1):page75_i17:vss(547)" )
			)
			( pin "U2D1.BV17"
				( objectStatus "@baseboard_fab2_lib.baseboard_fab2(sch_1):page75_i17:vss(548)" )
			)
			( pin "U2D1.BU10"
				( objectStatus "@baseboard_fab2_lib.baseboard_fab2(sch_1):page75_i17:vss(549)" )
			)
			( pin "U2D1.BV5"
				( objectStatus "@baseboard_fab2_lib.baseboard_fab2(sch_1):page75_i17:vss(550)" )
			)
			( pin "U2D1.BU8"
				( objectStatus "@baseboard_fab2_lib.baseboard_fab2(sch_1):page75_i17:vss(551)" )
			)
			( pin "U2D1.BT25"
				( objectStatus "@baseboard_fab2_lib.baseboard_fab2(sch_1):page75_i17:vss(552)" )
			)
			( pin "U2D1.BT23"
				( objectStatus "@baseboard_fab2_lib.baseboard_fab2(sch_1):page75_i17:vss(553)" )
			)
			( pin "U2D1.BT21"
				( objectStatus "@baseboard_fab2_lib.baseboard_fab2(sch_1):page75_i17:vss(554)" )
			)
			( pin "U2D1.BT5"
				( objectStatus "@baseboard_fab2_lib.baseboard_fab2(sch_1):page75_i17:vss(555)" )
			)
			( pin "U2D1.BT3"
				( objectStatus "@baseboard_fab2_lib.baseboard_fab2(sch_1):page75_i17:vss(556)" )
			)
			( pin "U2D1.BR82"
				( objectStatus "@baseboard_fab2_lib.baseboard_fab2(sch_1):page75_i17:vss(557)" )
			)
			( pin "U2D1.BR80"
				( objectStatus "@baseboard_fab2_lib.baseboard_fab2(sch_1):page75_i17:vss(558)" )
			)
			( pin "U2D1.BR78"
				( objectStatus "@baseboard_fab2_lib.baseboard_fab2(sch_1):page75_i17:vss(559)" )
			)
			( pin "U2D1.BR76"
				( objectStatus "@baseboard_fab2_lib.baseboard_fab2(sch_1):page75_i17:vss(560)" )
			)
			( pin "U2D1.BR74"
				( objectStatus "@baseboard_fab2_lib.baseboard_fab2(sch_1):page75_i17:vss(561)" )
			)
			( pin "U2D1.BR72"
				( objectStatus "@baseboard_fab2_lib.baseboard_fab2(sch_1):page75_i17:vss(562)" )
			)
			( pin "U2D1.BR70"
				( objectStatus "@baseboard_fab2_lib.baseboard_fab2(sch_1):page75_i17:vss(563)" )
			)
			( pin "U2D1.BR68"
				( objectStatus "@baseboard_fab2_lib.baseboard_fab2(sch_1):page75_i17:vss(564)" )
			)
			( pin "U2D1.BR66"
				( objectStatus "@baseboard_fab2_lib.baseboard_fab2(sch_1):page75_i17:vss(565)" )
			)
			( pin "U2D1.BR64"
				( objectStatus "@baseboard_fab2_lib.baseboard_fab2(sch_1):page75_i17:vss(566)" )
			)
			( pin "U2D1.P57"
				( objectStatus "@baseboard_fab2_lib.baseboard_fab2(sch_1):page75_i17:vss(567)" )
			)
			( pin "U2D1.BR16"
				( objectStatus "@baseboard_fab2_lib.baseboard_fab2(sch_1):page75_i17:vss(568)" )
			)
			( pin "U2D1.BR10"
				( objectStatus "@baseboard_fab2_lib.baseboard_fab2(sch_1):page75_i17:vss(569)" )
			)
			( pin "U2D1.BR6"
				( objectStatus "@baseboard_fab2_lib.baseboard_fab2(sch_1):page75_i17:vss(570)" )
			)
			( pin "U2D1.BP27"
				( objectStatus "@baseboard_fab2_lib.baseboard_fab2(sch_1):page75_i17:vss(571)" )
			)
			( pin "U2D1.BP3"
				( objectStatus "@baseboard_fab2_lib.baseboard_fab2(sch_1):page75_i17:vss(572)" )
			)
			( pin "U2D1.BN26"
				( objectStatus "@baseboard_fab2_lib.baseboard_fab2(sch_1):page75_i17:vss(573)" )
			)
			( pin "U2D1.BN20"
				( objectStatus "@baseboard_fab2_lib.baseboard_fab2(sch_1):page75_i17:vss(574)" )
			)
			( pin "U2D1.BN10"
				( objectStatus "@baseboard_fab2_lib.baseboard_fab2(sch_1):page75_i17:vss(575)" )
			)
			( pin "U2D1.BN6"
				( objectStatus "@baseboard_fab2_lib.baseboard_fab2(sch_1):page75_i17:vss(576)" )
			)
			( pin "U2D1.BM25"
				( objectStatus "@baseboard_fab2_lib.baseboard_fab2(sch_1):page75_i17:vss(577)" )
			)
			( pin "U2D1.P59"
				( objectStatus "@baseboard_fab2_lib.baseboard_fab2(sch_1):page75_i17:vss(578)" )
			)
			( pin "U2D1.BM15"
				( objectStatus "@baseboard_fab2_lib.baseboard_fab2(sch_1):page75_i17:vss(579)" )
			)
			( pin "U2D1.BM13"
				( objectStatus "@baseboard_fab2_lib.baseboard_fab2(sch_1):page75_i17:vss(580)" )
			)
			( pin "U2D1.BM9"
				( objectStatus "@baseboard_fab2_lib.baseboard_fab2(sch_1):page75_i17:vss(581)" )
			)
			( pin "U2D1.BL82"
				( objectStatus "@baseboard_fab2_lib.baseboard_fab2(sch_1):page75_i17:vss(582)" )
			)
			( pin "U2D1.BL80"
				( objectStatus "@baseboard_fab2_lib.baseboard_fab2(sch_1):page75_i17:vss(583)" )
			)
			( pin "U2D1.BL78"
				( objectStatus "@baseboard_fab2_lib.baseboard_fab2(sch_1):page75_i17:vss(584)" )
			)
			( pin "U2D1.BL76"
				( objectStatus "@baseboard_fab2_lib.baseboard_fab2(sch_1):page75_i17:vss(585)" )
			)
			( pin "U2D1.BL74"
				( objectStatus "@baseboard_fab2_lib.baseboard_fab2(sch_1):page75_i17:vss(586)" )
			)
			( pin "U2D1.BL72"
				( objectStatus "@baseboard_fab2_lib.baseboard_fab2(sch_1):page75_i17:vss(587)" )
			)
			( pin "U2D1.BL70"
				( objectStatus "@baseboard_fab2_lib.baseboard_fab2(sch_1):page75_i17:vss(588)" )
			)
			( pin "U2D1.BL68"
				( objectStatus "@baseboard_fab2_lib.baseboard_fab2(sch_1):page75_i17:vss(589)" )
			)
			( pin "U2D1.BL66"
				( objectStatus "@baseboard_fab2_lib.baseboard_fab2(sch_1):page75_i17:vss(590)" )
			)
			( pin "U2D1.BL64"
				( objectStatus "@baseboard_fab2_lib.baseboard_fab2(sch_1):page75_i17:vss(591)" )
			)
			( pin "U2D1.BL24"
				( objectStatus "@baseboard_fab2_lib.baseboard_fab2(sch_1):page75_i17:vss(592)" )
			)
			( pin "U2D1.BL22"
				( objectStatus "@baseboard_fab2_lib.baseboard_fab2(sch_1):page75_i17:vss(593)" )
			)
			( pin "U2D1.P61"
				( objectStatus "@baseboard_fab2_lib.baseboard_fab2(sch_1):page75_i17:vss(594)" )
			)
			( pin "U2D1.BL12"
				( objectStatus "@baseboard_fab2_lib.baseboard_fab2(sch_1):page75_i17:vss(595)" )
			)
			( pin "U2D1.BL10"
				( objectStatus "@baseboard_fab2_lib.baseboard_fab2(sch_1):page75_i17:vss(596)" )
			)
			( pin "U2D1.BL6"
				( objectStatus "@baseboard_fab2_lib.baseboard_fab2(sch_1):page75_i17:vss(597)" )
			)
			( pin "U2D1.BK19"
				( objectStatus "@baseboard_fab2_lib.baseboard_fab2(sch_1):page75_i17:vss(598)" )
			)
			( pin "U2D1.BK11"
				( objectStatus "@baseboard_fab2_lib.baseboard_fab2(sch_1):page75_i17:vss(599)" )
			)
			( pin "U2D1.BK7"
				( objectStatus "@baseboard_fab2_lib.baseboard_fab2(sch_1):page75_i17:vss(600)" )
			)
			( pin "U2D1.BK3"
				( objectStatus "@baseboard_fab2_lib.baseboard_fab2(sch_1):page75_i17:vss(601)" )
			)
			( pin "U2D1.BJ6"
				( objectStatus "@baseboard_fab2_lib.baseboard_fab2(sch_1):page75_i17:vss(602)" )
			)
			( pin "U2D1.BJ4"
				( objectStatus "@baseboard_fab2_lib.baseboard_fab2(sch_1):page75_i17:vss(603)" )
			)
			( pin "U2D1.BH21"
				( objectStatus "@baseboard_fab2_lib.baseboard_fab2(sch_1):page75_i17:vss(604)" )
			)
			( pin "U2D1.BH15"
				( objectStatus "@baseboard_fab2_lib.baseboard_fab2(sch_1):page75_i17:vss(605)" )
			)
			( pin "U2D1.BH11"
				( objectStatus "@baseboard_fab2_lib.baseboard_fab2(sch_1):page75_i17:vss(606)" )
			)
			( pin "U2D1.BH9"
				( objectStatus "@baseboard_fab2_lib.baseboard_fab2(sch_1):page75_i17:vss(607)" )
			)
			( pin "U2D1.BH7"
				( objectStatus "@baseboard_fab2_lib.baseboard_fab2(sch_1):page75_i17:vss(608)" )
			)
			( pin "U2D1.BG82"
				( objectStatus "@baseboard_fab2_lib.baseboard_fab2(sch_1):page75_i17:vss(609)" )
			)
			( pin "U2D1.BG80"
				( objectStatus "@baseboard_fab2_lib.baseboard_fab2(sch_1):page75_i17:vss(610)" )
			)
			( pin "U2D1.BG78"
				( objectStatus "@baseboard_fab2_lib.baseboard_fab2(sch_1):page75_i17:vss(611)" )
			)
			( pin "U2D1.BG76"
				( objectStatus "@baseboard_fab2_lib.baseboard_fab2(sch_1):page75_i17:vss(612)" )
			)
			( pin "U2D1.BG74"
				( objectStatus "@baseboard_fab2_lib.baseboard_fab2(sch_1):page75_i17:vss(613)" )
			)
			( pin "U2D1.DA46"
				( objectStatus "@baseboard_fab2_lib.baseboard_fab2(sch_1):page75_i18:vss(294)" )
			)
			( pin "U2D1.DA44"
				( objectStatus "@baseboard_fab2_lib.baseboard_fab2(sch_1):page75_i18:vss(295)" )
			)
			( pin "U2D1.DA38"
				( objectStatus "@baseboard_fab2_lib.baseboard_fab2(sch_1):page75_i18:vss(296)" )
			)
			( pin "U2D1.DA36"
				( objectStatus "@baseboard_fab2_lib.baseboard_fab2(sch_1):page75_i18:vss(297)" )
			)
			( pin "U2D1.DA34"
				( objectStatus "@baseboard_fab2_lib.baseboard_fab2(sch_1):page75_i18:vss(298)" )
			)
			( pin "U2D1.DA32"
				( objectStatus "@baseboard_fab2_lib.baseboard_fab2(sch_1):page75_i18:vss(299)" )
			)
			( pin "U2D1.DA30"
				( objectStatus "@baseboard_fab2_lib.baseboard_fab2(sch_1):page75_i18:vss(300)" )
			)
			( pin "U2D1.DA28"
				( objectStatus "@baseboard_fab2_lib.baseboard_fab2(sch_1):page75_i18:vss(301)" )
			)
			( pin "U2D1.DA26"
				( objectStatus "@baseboard_fab2_lib.baseboard_fab2(sch_1):page75_i18:vss(302)" )
			)
			( pin "U2D1.DA18"
				( objectStatus "@baseboard_fab2_lib.baseboard_fab2(sch_1):page75_i18:vss(303)" )
			)
			( pin "U2D1.H53"
				( objectStatus "@baseboard_fab2_lib.baseboard_fab2(sch_1):page75_i18:vss(304)" )
			)
			( pin "U2D1.DA6"
				( objectStatus "@baseboard_fab2_lib.baseboard_fab2(sch_1):page75_i18:vss(305)" )
			)
			( pin "U2D1.CY85"
				( objectStatus "@baseboard_fab2_lib.baseboard_fab2(sch_1):page75_i18:vss(306)" )
			)
			( pin "U2D1.CY83"
				( objectStatus "@baseboard_fab2_lib.baseboard_fab2(sch_1):page75_i18:vss(307)" )
			)
			( pin "U2D1.CY77"
				( objectStatus "@baseboard_fab2_lib.baseboard_fab2(sch_1):page75_i18:vss(308)" )
			)
			( pin "U2D1.CY75"
				( objectStatus "@baseboard_fab2_lib.baseboard_fab2(sch_1):page75_i18:vss(309)" )
			)
			( pin "U2D1.CY69"
				( objectStatus "@baseboard_fab2_lib.baseboard_fab2(sch_1):page75_i18:vss(310)" )
			)
			( pin "U2D1.CY65"
				( objectStatus "@baseboard_fab2_lib.baseboard_fab2(sch_1):page75_i18:vss(311)" )
			)
			( pin "U2D1.CY61"
				( objectStatus "@baseboard_fab2_lib.baseboard_fab2(sch_1):page75_i18:vss(312)" )
			)
			( pin "U2D1.CY59"
				( objectStatus "@baseboard_fab2_lib.baseboard_fab2(sch_1):page75_i18:vss(313)" )
			)
			( pin "U2D1.CY51"
				( objectStatus "@baseboard_fab2_lib.baseboard_fab2(sch_1):page75_i18:vss(314)" )
			)
			( pin "U2D1.CY45"
				( objectStatus "@baseboard_fab2_lib.baseboard_fab2(sch_1):page75_i18:vss(315)" )
			)
			( pin "U2D1.CY41"
				( objectStatus "@baseboard_fab2_lib.baseboard_fab2(sch_1):page75_i18:vss(316)" )
			)
			( pin "U2D1.CY21"
				( objectStatus "@baseboard_fab2_lib.baseboard_fab2(sch_1):page75_i18:vss(317)" )
			)
			( pin "U2D1.CY15"
				( objectStatus "@baseboard_fab2_lib.baseboard_fab2(sch_1):page75_i18:vss(318)" )
			)
			( pin "U2D1.CY13"
				( objectStatus "@baseboard_fab2_lib.baseboard_fab2(sch_1):page75_i18:vss(319)" )
			)
			( pin "U2D1.CY9"
				( objectStatus "@baseboard_fab2_lib.baseboard_fab2(sch_1):page75_i18:vss(320)" )
			)
			( pin "U2D1.CY1"
				( objectStatus "@baseboard_fab2_lib.baseboard_fab2(sch_1):page75_i18:vss(321)" )
			)
			( pin "U2D1.CW82"
				( objectStatus "@baseboard_fab2_lib.baseboard_fab2(sch_1):page75_i18:vss(322)" )
			)
			( pin "U2D1.CW78"
				( objectStatus "@baseboard_fab2_lib.baseboard_fab2(sch_1):page75_i18:vss(323)" )
			)
			( pin "U2D1.CW74"
				( objectStatus "@baseboard_fab2_lib.baseboard_fab2(sch_1):page75_i18:vss(324)" )
			)
			( pin "U2D1.CW68"
				( objectStatus "@baseboard_fab2_lib.baseboard_fab2(sch_1):page75_i18:vss(325)" )
			)
			( pin "U2D1.CW66"
				( objectStatus "@baseboard_fab2_lib.baseboard_fab2(sch_1):page75_i18:vss(326)" )
			)
			( pin "U2D1.CW64"
				( objectStatus "@baseboard_fab2_lib.baseboard_fab2(sch_1):page75_i18:vss(327)" )
			)
			( pin "U2D1.CW54"
				( objectStatus "@baseboard_fab2_lib.baseboard_fab2(sch_1):page75_i18:vss(328)" )
			)
			( pin "U2D1.CW52"
				( objectStatus "@baseboard_fab2_lib.baseboard_fab2(sch_1):page75_i18:vss(329)" )
			)
			( pin "U2D1.CW42"
				( objectStatus "@baseboard_fab2_lib.baseboard_fab2(sch_1):page75_i18:vss(330)" )
			)
			( pin "U2D1.CW40"
				( objectStatus "@baseboard_fab2_lib.baseboard_fab2(sch_1):page75_i18:vss(331)" )
			)
			( pin "U2D1.CW38"
				( objectStatus "@baseboard_fab2_lib.baseboard_fab2(sch_1):page75_i18:vss(332)" )
			)
			( pin "U2D1.CW32"
				( objectStatus "@baseboard_fab2_lib.baseboard_fab2(sch_1):page75_i18:vss(333)" )
			)
			( pin "U2D1.CW26"
				( objectStatus "@baseboard_fab2_lib.baseboard_fab2(sch_1):page75_i18:vss(334)" )
			)
			( pin "U2D1.CW12"
				( objectStatus "@baseboard_fab2_lib.baseboard_fab2(sch_1):page75_i18:vss(335)" )
			)
			( pin "U2D1.CV83"
				( objectStatus "@baseboard_fab2_lib.baseboard_fab2(sch_1):page75_i18:vss(336)" )
			)
			( pin "U2D1.CV81"
				( objectStatus "@baseboard_fab2_lib.baseboard_fab2(sch_1):page75_i18:vss(337)" )
			)
			( pin "U2D1.CV79"
				( objectStatus "@baseboard_fab2_lib.baseboard_fab2(sch_1):page75_i18:vss(338)" )
			)
			( pin "U2D1.CV73"
				( objectStatus "@baseboard_fab2_lib.baseboard_fab2(sch_1):page75_i18:vss(339)" )
			)
			( pin "U2D1.CV67"
				( objectStatus "@baseboard_fab2_lib.baseboard_fab2(sch_1):page75_i18:vss(340)" )
			)
			( pin "U2D1.CV63"
				( objectStatus "@baseboard_fab2_lib.baseboard_fab2(sch_1):page75_i18:vss(341)" )
			)
			( pin "U2D1.CV55"
				( objectStatus "@baseboard_fab2_lib.baseboard_fab2(sch_1):page75_i18:vss(342)" )
			)
			( pin "U2D1.CV53"
				( objectStatus "@baseboard_fab2_lib.baseboard_fab2(sch_1):page75_i18:vss(343)" )
			)
			( pin "U2D1.CV41"
				( objectStatus "@baseboard_fab2_lib.baseboard_fab2(sch_1):page75_i18:vss(344)" )
			)
			( pin "U2D1.CV39"
				( objectStatus "@baseboard_fab2_lib.baseboard_fab2(sch_1):page75_i18:vss(345)" )
			)
			( pin "U2D1.CV37"
				( objectStatus "@baseboard_fab2_lib.baseboard_fab2(sch_1):page75_i18:vss(346)" )
			)
			( pin "U2D1.CV33"
				( objectStatus "@baseboard_fab2_lib.baseboard_fab2(sch_1):page75_i18:vss(347)" )
			)
			( pin "U2D1.CV31"
				( objectStatus "@baseboard_fab2_lib.baseboard_fab2(sch_1):page75_i18:vss(348)" )
			)
			( pin "U2D1.CV27"
				( objectStatus "@baseboard_fab2_lib.baseboard_fab2(sch_1):page75_i18:vss(349)" )
			)
			( pin "U2D1.CV25"
				( objectStatus "@baseboard_fab2_lib.baseboard_fab2(sch_1):page75_i18:vss(350)" )
			)
			( pin "U2D1.CV17"
				( objectStatus "@baseboard_fab2_lib.baseboard_fab2(sch_1):page75_i18:vss(351)" )
			)
			( pin "U2D1.H55"
				( objectStatus "@baseboard_fab2_lib.baseboard_fab2(sch_1):page75_i18:vss(352)" )
			)
			( pin "U2D1.CV1"
				( objectStatus "@baseboard_fab2_lib.baseboard_fab2(sch_1):page75_i18:vss(353)" )
			)
			( pin "U2D1.CU86"
				( objectStatus "@baseboard_fab2_lib.baseboard_fab2(sch_1):page75_i18:vss(354)" )
			)
			( pin "U2D1.CU82"
				( objectStatus "@baseboard_fab2_lib.baseboard_fab2(sch_1):page75_i18:vss(355)" )
			)
			( pin "U2D1.CU80"
				( objectStatus "@baseboard_fab2_lib.baseboard_fab2(sch_1):page75_i18:vss(356)" )
			)
			( pin "U2D1.CU78"
				( objectStatus "@baseboard_fab2_lib.baseboard_fab2(sch_1):page75_i18:vss(357)" )
			)
			( pin "U2D1.CU76"
				( objectStatus "@baseboard_fab2_lib.baseboard_fab2(sch_1):page75_i18:vss(358)" )
			)
			( pin "U2D1.CU68"
				( objectStatus "@baseboard_fab2_lib.baseboard_fab2(sch_1):page75_i18:vss(359)" )
			)
			( pin "U2D1.CU62"
				( objectStatus "@baseboard_fab2_lib.baseboard_fab2(sch_1):page75_i18:vss(360)" )
			)
			( pin "U2D1.CU56"
				( objectStatus "@baseboard_fab2_lib.baseboard_fab2(sch_1):page75_i18:vss(361)" )
			)
			( pin "U2D1.CU36"
				( objectStatus "@baseboard_fab2_lib.baseboard_fab2(sch_1):page75_i18:vss(362)" )
			)
			( pin "U2D1.CU34"
				( objectStatus "@baseboard_fab2_lib.baseboard_fab2(sch_1):page75_i18:vss(363)" )
			)
			( pin "U2D1.CU30"
				( objectStatus "@baseboard_fab2_lib.baseboard_fab2(sch_1):page75_i18:vss(364)" )
			)
			( pin "U2D1.CU28"
				( objectStatus "@baseboard_fab2_lib.baseboard_fab2(sch_1):page75_i18:vss(365)" )
			)
			( pin "U2D1.CU22"
				( objectStatus "@baseboard_fab2_lib.baseboard_fab2(sch_1):page75_i18:vss(366)" )
			)
			( pin "U2D1.CU4"
				( objectStatus "@baseboard_fab2_lib.baseboard_fab2(sch_1):page75_i18:vss(367)" )
			)
			( pin "U2D1.CT85"
				( objectStatus "@baseboard_fab2_lib.baseboard_fab2(sch_1):page75_i18:vss(368)" )
			)
			( pin "U2D1.CT83"
				( objectStatus "@baseboard_fab2_lib.baseboard_fab2(sch_1):page75_i18:vss(369)" )
			)
			( pin "U2D1.CT79"
				( objectStatus "@baseboard_fab2_lib.baseboard_fab2(sch_1):page75_i18:vss(370)" )
			)
			( pin "U2D1.CT73"
				( objectStatus "@baseboard_fab2_lib.baseboard_fab2(sch_1):page75_i18:vss(371)" )
			)
			( pin "U2D1.CT57"
				( objectStatus "@baseboard_fab2_lib.baseboard_fab2(sch_1):page75_i18:vss(372)" )
			)
			( pin "U2D1.CT35"
				( objectStatus "@baseboard_fab2_lib.baseboard_fab2(sch_1):page75_i18:vss(373)" )
			)
			( pin "U2D1.CT33"
				( objectStatus "@baseboard_fab2_lib.baseboard_fab2(sch_1):page75_i18:vss(374)" )
			)
			( pin "U2D1.CT29"
				( objectStatus "@baseboard_fab2_lib.baseboard_fab2(sch_1):page75_i18:vss(375)" )
			)
			( pin "U2D1.CT27"
				( objectStatus "@baseboard_fab2_lib.baseboard_fab2(sch_1):page75_i18:vss(376)" )
			)
			( pin "U2D1.CT19"
				( objectStatus "@baseboard_fab2_lib.baseboard_fab2(sch_1):page75_i18:vss(377)" )
			)
			( pin "U2D1.CT13"
				( objectStatus "@baseboard_fab2_lib.baseboard_fab2(sch_1):page75_i18:vss(378)" )
			)
			( pin "U2D1.H57"
				( objectStatus "@baseboard_fab2_lib.baseboard_fab2(sch_1):page75_i18:vss(379)" )
			)
			( pin "U2D1.CR86"
				( objectStatus "@baseboard_fab2_lib.baseboard_fab2(sch_1):page75_i18:vss(380)" )
			)
			( pin "U2D1.CR78"
				( objectStatus "@baseboard_fab2_lib.baseboard_fab2(sch_1):page75_i18:vss(381)" )
			)
			( pin "U2D1.CR68"
				( objectStatus "@baseboard_fab2_lib.baseboard_fab2(sch_1):page75_i18:vss(382)" )
			)
			( pin "U2D1.CR66"
				( objectStatus "@baseboard_fab2_lib.baseboard_fab2(sch_1):page75_i18:vss(383)" )
			)
			( pin "U2D1.CR64"
				( objectStatus "@baseboard_fab2_lib.baseboard_fab2(sch_1):page75_i18:vss(384)" )
			)
			( pin "U2D1.CR62"
				( objectStatus "@baseboard_fab2_lib.baseboard_fab2(sch_1):page75_i18:vss(385)" )
			)
			( pin "U2D1.CR58"
				( objectStatus "@baseboard_fab2_lib.baseboard_fab2(sch_1):page75_i18:vss(386)" )
			)
			( pin "U2D1.CR32"
				( objectStatus "@baseboard_fab2_lib.baseboard_fab2(sch_1):page75_i18:vss(387)" )
			)
			( pin "U2D1.CR24"
				( objectStatus "@baseboard_fab2_lib.baseboard_fab2(sch_1):page75_i18:vss(388)" )
			)
			( pin "U2D1.CR22"
				( objectStatus "@baseboard_fab2_lib.baseboard_fab2(sch_1):page75_i18:vss(389)" )
			)
			( pin "U2D1.CR10"
				( objectStatus "@baseboard_fab2_lib.baseboard_fab2(sch_1):page75_i18:vss(390)" )
			)
			( pin "U2D1.CR6"
				( objectStatus "@baseboard_fab2_lib.baseboard_fab2(sch_1):page75_i18:vss(391)" )
			)
			( pin "U2D1.CP83"
				( objectStatus "@baseboard_fab2_lib.baseboard_fab2(sch_1):page75_i18:vss(392)" )
			)
			( pin "U2D1.CP81"
				( objectStatus "@baseboard_fab2_lib.baseboard_fab2(sch_1):page75_i18:vss(393)" )
			)
			( pin "U2D1.CP75"
				( objectStatus "@baseboard_fab2_lib.baseboard_fab2(sch_1):page75_i18:vss(394)" )
			)
			( pin "U2D1.CP73"
				( objectStatus "@baseboard_fab2_lib.baseboard_fab2(sch_1):page75_i18:vss(395)" )
			)
			( pin "U2D1.CP69"
				( objectStatus "@baseboard_fab2_lib.baseboard_fab2(sch_1):page75_i18:vss(396)" )
			)
			( pin "U2D1.CP59"
				( objectStatus "@baseboard_fab2_lib.baseboard_fab2(sch_1):page75_i18:vss(397)" )
			)
			( pin "U2D1.CP25"
				( objectStatus "@baseboard_fab2_lib.baseboard_fab2(sch_1):page75_i18:vss(398)" )
			)
			( pin "U2D1.H59"
				( objectStatus "@baseboard_fab2_lib.baseboard_fab2(sch_1):page75_i18:vss(399)" )
			)
			( pin "U2D1.CP1"
				( objectStatus "@baseboard_fab2_lib.baseboard_fab2(sch_1):page75_i18:vss(400)" )
			)
			( pin "U2D1.CN78"
				( objectStatus "@baseboard_fab2_lib.baseboard_fab2(sch_1):page75_i18:vss(401)" )
			)
			( pin "U2D1.CN68"
				( objectStatus "@baseboard_fab2_lib.baseboard_fab2(sch_1):page75_i18:vss(402)" )
			)
			( pin "U2D1.CN62"
				( objectStatus "@baseboard_fab2_lib.baseboard_fab2(sch_1):page75_i18:vss(403)" )
			)
			( pin "U2D1.CN60"
				( objectStatus "@baseboard_fab2_lib.baseboard_fab2(sch_1):page75_i18:vss(404)" )
			)
			( pin "U2D1.CN32"
				( objectStatus "@baseboard_fab2_lib.baseboard_fab2(sch_1):page75_i18:vss(405)" )
			)
			( pin "U2D1.CN26"
				( objectStatus "@baseboard_fab2_lib.baseboard_fab2(sch_1):page75_i18:vss(406)" )
			)
			( pin "U2D1.H61"
				( objectStatus "@baseboard_fab2_lib.baseboard_fab2(sch_1):page75_i18:vss(407)" )
			)
			( pin "U2D1.CN12"
				( objectStatus "@baseboard_fab2_lib.baseboard_fab2(sch_1):page75_i18:vss(408)" )
			)
			( pin "U2D1.CN2"
				( objectStatus "@baseboard_fab2_lib.baseboard_fab2(sch_1):page75_i18:vss(409)" )
			)
			( pin "U2D1.CM85"
				( objectStatus "@baseboard_fab2_lib.baseboard_fab2(sch_1):page75_i18:vss(410)" )
			)
			( pin "U2D1.CM83"
				( objectStatus "@baseboard_fab2_lib.baseboard_fab2(sch_1):page75_i18:vss(411)" )
			)
			( pin "U2D1.CM77"
				( objectStatus "@baseboard_fab2_lib.baseboard_fab2(sch_1):page75_i18:vss(412)" )
			)
			( pin "U2D1.CM73"
				( objectStatus "@baseboard_fab2_lib.baseboard_fab2(sch_1):page75_i18:vss(413)" )
			)
			( pin "U2D1.CM67"
				( objectStatus "@baseboard_fab2_lib.baseboard_fab2(sch_1):page75_i18:vss(414)" )
			)
			( pin "U2D1.CM63"
				( objectStatus "@baseboard_fab2_lib.baseboard_fab2(sch_1):page75_i18:vss(415)" )
			)
			( pin "U2D1.CM61"
				( objectStatus "@baseboard_fab2_lib.baseboard_fab2(sch_1):page75_i18:vss(416)" )
			)
			( pin "U2D1.CM31"
				( objectStatus "@baseboard_fab2_lib.baseboard_fab2(sch_1):page75_i18:vss(417)" )
			)
			( pin "U2D1.CM5"
				( objectStatus "@baseboard_fab2_lib.baseboard_fab2(sch_1):page75_i18:vss(418)" )
			)
			( pin "U2D1.CM29"
				( objectStatus "@baseboard_fab2_lib.baseboard_fab2(sch_1):page75_i18:vss(419)" )
			)
			( pin "U2D1.CM19"
				( objectStatus "@baseboard_fab2_lib.baseboard_fab2(sch_1):page75_i18:vss(420)" )
			)
			( pin "U2D1.CL80"
				( objectStatus "@baseboard_fab2_lib.baseboard_fab2(sch_1):page75_i18:vss(421)" )
			)
			( pin "U2D1.CL78"
				( objectStatus "@baseboard_fab2_lib.baseboard_fab2(sch_1):page75_i18:vss(422)" )
			)
			( pin "U2D1.CL76"
				( objectStatus "@baseboard_fab2_lib.baseboard_fab2(sch_1):page75_i18:vss(423)" )
			)
			( pin "U2D1.CL74"
				( objectStatus "@baseboard_fab2_lib.baseboard_fab2(sch_1):page75_i18:vss(424)" )
			)
			( pin "U2D1.CL66"
				( objectStatus "@baseboard_fab2_lib.baseboard_fab2(sch_1):page75_i18:vss(425)" )
			)
			( pin "U2D1.CL64"
				( objectStatus "@baseboard_fab2_lib.baseboard_fab2(sch_1):page75_i18:vss(426)" )
			)
			( pin "U2D1.CL62"
				( objectStatus "@baseboard_fab2_lib.baseboard_fab2(sch_1):page75_i18:vss(427)" )
			)
			( pin "U2D1.H63"
				( objectStatus "@baseboard_fab2_lib.baseboard_fab2(sch_1):page75_i18:vss(428)" )
			)
			( pin "U2D1.P45"
				( objectStatus "@baseboard_fab2_lib.baseboard_fab2(sch_1):page75_i18:vss(429)" )
			)
			( pin "U2D1.CL18"
				( objectStatus "@baseboard_fab2_lib.baseboard_fab2(sch_1):page75_i18:vss(430)" )
			)
			( pin "U2D1.CL14"
				( objectStatus "@baseboard_fab2_lib.baseboard_fab2(sch_1):page75_i18:vss(431)" )
			)
			( pin "U2D1.CL8"
				( objectStatus "@baseboard_fab2_lib.baseboard_fab2(sch_1):page75_i18:vss(432)" )
			)
			( pin "U2D1.CK85"
				( objectStatus "@baseboard_fab2_lib.baseboard_fab2(sch_1):page75_i18:vss(433)" )
			)
			( pin "U2D1.CK83"
				( objectStatus "@baseboard_fab2_lib.baseboard_fab2(sch_1):page75_i18:vss(434)" )
			)
			( pin "U2D1.CK75"
				( objectStatus "@baseboard_fab2_lib.baseboard_fab2(sch_1):page75_i18:vss(435)" )
			)
			( pin "U2D1.CK73"
				( objectStatus "@baseboard_fab2_lib.baseboard_fab2(sch_1):page75_i18:vss(436)" )
			)
			( pin "U2D1.CK71"
				( objectStatus "@baseboard_fab2_lib.baseboard_fab2(sch_1):page75_i18:vss(437)" )
			)
			( pin "U2D1.CK69"
				( objectStatus "@baseboard_fab2_lib.baseboard_fab2(sch_1):page75_i18:vss(438)" )
			)
			( pin "U2D1.CK67"
				( objectStatus "@baseboard_fab2_lib.baseboard_fab2(sch_1):page75_i18:vss(439)" )
			)
			( pin "U2D1.CK65"
				( objectStatus "@baseboard_fab2_lib.baseboard_fab2(sch_1):page75_i18:vss(440)" )
			)
			( pin "U2D1.CK63"
				( objectStatus "@baseboard_fab2_lib.baseboard_fab2(sch_1):page75_i18:vss(441)" )
			)
			( pin "U2D1.CK27"
				( objectStatus "@baseboard_fab2_lib.baseboard_fab2(sch_1):page75_i18:vss(442)" )
			)
			( pin "U2D1.CK21"
				( objectStatus "@baseboard_fab2_lib.baseboard_fab2(sch_1):page75_i18:vss(443)" )
			)
			( pin "U2D1.CK15"
				( objectStatus "@baseboard_fab2_lib.baseboard_fab2(sch_1):page75_i18:vss(444)" )
			)
			( pin "U2D1.CK11"
				( objectStatus "@baseboard_fab2_lib.baseboard_fab2(sch_1):page75_i18:vss(445)" )
			)
			( pin "U2D1.CJ86"
				( objectStatus "@baseboard_fab2_lib.baseboard_fab2(sch_1):page75_i18:vss(446)" )
			)
			( pin "U2D1.CJ84"
				( objectStatus "@baseboard_fab2_lib.baseboard_fab2(sch_1):page75_i18:vss(447)" )
			)
			( pin "U2D1.CJ82"
				( objectStatus "@baseboard_fab2_lib.baseboard_fab2(sch_1):page75_i18:vss(448)" )
			)
			( pin "U2D1.CJ78"
				( objectStatus "@baseboard_fab2_lib.baseboard_fab2(sch_1):page75_i18:vss(449)" )
			)
			( pin "U2D1.CJ76"
				( objectStatus "@baseboard_fab2_lib.baseboard_fab2(sch_1):page75_i18:vss(450)" )
			)
			( pin "U2D1.CJ74"
				( objectStatus "@baseboard_fab2_lib.baseboard_fab2(sch_1):page75_i18:vss(451)" )
			)
			( pin "U2D1.CJ62"
				( objectStatus "@baseboard_fab2_lib.baseboard_fab2(sch_1):page75_i18:vss(452)" )
			)
			( pin "U2D1.P47"
				( objectStatus "@baseboard_fab2_lib.baseboard_fab2(sch_1):page75_i18:vss(453)" )
			)
			( pin "U2D1.DN72"
				( objectStatus "@baseboard_fab2_lib.baseboard_fab2(sch_1):page75_i19:vss(134)" )
			)
			( pin "U2D1.DN68"
				( objectStatus "@baseboard_fab2_lib.baseboard_fab2(sch_1):page75_i19:vss(135)" )
			)
			( pin "U2D1.DN38"
				( objectStatus "@baseboard_fab2_lib.baseboard_fab2(sch_1):page75_i19:vss(136)" )
			)
			( pin "U2D1.DN32"
				( objectStatus "@baseboard_fab2_lib.baseboard_fab2(sch_1):page75_i19:vss(137)" )
			)
			( pin "U2D1.DN26"
				( objectStatus "@baseboard_fab2_lib.baseboard_fab2(sch_1):page75_i19:vss(138)" )
			)
			( pin "U2D1.DN22"
				( objectStatus "@baseboard_fab2_lib.baseboard_fab2(sch_1):page75_i19:vss(139)" )
			)
			( pin "U2D1.DN12"
				( objectStatus "@baseboard_fab2_lib.baseboard_fab2(sch_1):page75_i19:vss(140)" )
			)
			( pin "U2D1.BH17"
				( objectStatus "@baseboard_fab2_lib.baseboard_fab2(sch_1):page75_i19:vss(141)" )
			)
			( pin "U2D1.DN2"
				( objectStatus "@baseboard_fab2_lib.baseboard_fab2(sch_1):page75_i19:vss(142)" )
			)
			( pin "U2D1.DM83"
				( objectStatus "@baseboard_fab2_lib.baseboard_fab2(sch_1):page75_i19:vss(143)" )
			)
			( pin "U2D1.DM77"
				( objectStatus "@baseboard_fab2_lib.baseboard_fab2(sch_1):page75_i19:vss(144)" )
			)
			( pin "U2D1.DM73"
				( objectStatus "@baseboard_fab2_lib.baseboard_fab2(sch_1):page75_i19:vss(145)" )
			)
			( pin "U2D1.DM65"
				( objectStatus "@baseboard_fab2_lib.baseboard_fab2(sch_1):page75_i19:vss(146)" )
			)
			( pin "U2D1.DM39"
				( objectStatus "@baseboard_fab2_lib.baseboard_fab2(sch_1):page75_i19:vss(147)" )
			)
			( pin "U2D1.DM37"
				( objectStatus "@baseboard_fab2_lib.baseboard_fab2(sch_1):page75_i19:vss(148)" )
			)
			( pin "U2D1.DM33"
				( objectStatus "@baseboard_fab2_lib.baseboard_fab2(sch_1):page75_i19:vss(149)" )
			)
			( pin "U2D1.DM31"
				( objectStatus "@baseboard_fab2_lib.baseboard_fab2(sch_1):page75_i19:vss(150)" )
			)
			( pin "U2D1.DM27"
				( objectStatus "@baseboard_fab2_lib.baseboard_fab2(sch_1):page75_i19:vss(151)" )
			)
			( pin "U2D1.DM25"
				( objectStatus "@baseboard_fab2_lib.baseboard_fab2(sch_1):page75_i19:vss(152)" )
			)
			( pin "U2D1.H45"
				( objectStatus "@baseboard_fab2_lib.baseboard_fab2(sch_1):page75_i19:vss(153)" )
			)
			( pin "U2D1.DM15"
				( objectStatus "@baseboard_fab2_lib.baseboard_fab2(sch_1):page75_i19:vss(154)" )
			)
			( pin "U2D1.DL80"
				( objectStatus "@baseboard_fab2_lib.baseboard_fab2(sch_1):page75_i19:vss(155)" )
			)
			( pin "U2D1.DL78"
				( objectStatus "@baseboard_fab2_lib.baseboard_fab2(sch_1):page75_i19:vss(156)" )
			)
			( pin "U2D1.DL76"
				( objectStatus "@baseboard_fab2_lib.baseboard_fab2(sch_1):page75_i19:vss(157)" )
			)
			( pin "U2D1.DL74"
				( objectStatus "@baseboard_fab2_lib.baseboard_fab2(sch_1):page75_i19:vss(158)" )
			)
			( pin "U2D1.DL70"
				( objectStatus "@baseboard_fab2_lib.baseboard_fab2(sch_1):page75_i19:vss(159)" )
			)
			( pin "U2D1.DL68"
				( objectStatus "@baseboard_fab2_lib.baseboard_fab2(sch_1):page75_i19:vss(160)" )
			)
			( pin "U2D1.DL40"
				( objectStatus "@baseboard_fab2_lib.baseboard_fab2(sch_1):page75_i19:vss(161)" )
			)
			( pin "U2D1.DL36"
				( objectStatus "@baseboard_fab2_lib.baseboard_fab2(sch_1):page75_i19:vss(162)" )
			)
			( pin "U2D1.DL34"
				( objectStatus "@baseboard_fab2_lib.baseboard_fab2(sch_1):page75_i19:vss(163)" )
			)
			( pin "U2D1.DL30"
				( objectStatus "@baseboard_fab2_lib.baseboard_fab2(sch_1):page75_i19:vss(164)" )
			)
			( pin "U2D1.DL28"
				( objectStatus "@baseboard_fab2_lib.baseboard_fab2(sch_1):page75_i19:vss(165)" )
			)
			( pin "U2D1.DL24"
				( objectStatus "@baseboard_fab2_lib.baseboard_fab2(sch_1):page75_i19:vss(166)" )
			)
			( pin "U2D1.DL22"
				( objectStatus "@baseboard_fab2_lib.baseboard_fab2(sch_1):page75_i19:vss(167)" )
			)
			( pin "U2D1.DL4"
				( objectStatus "@baseboard_fab2_lib.baseboard_fab2(sch_1):page75_i19:vss(168)" )
			)
			( pin "U2D1.DL18"
				( objectStatus "@baseboard_fab2_lib.baseboard_fab2(sch_1):page75_i19:vss(169)" )
			)
			( pin "U2D1.DL16"
				( objectStatus "@baseboard_fab2_lib.baseboard_fab2(sch_1):page75_i19:vss(170)" )
			)
			( pin "U2D1.DK85"
				( objectStatus "@baseboard_fab2_lib.baseboard_fab2(sch_1):page75_i19:vss(171)" )
			)
			( pin "U2D1.DK83"
				( objectStatus "@baseboard_fab2_lib.baseboard_fab2(sch_1):page75_i19:vss(172)" )
			)
			( pin "U2D1.DK77"
				( objectStatus "@baseboard_fab2_lib.baseboard_fab2(sch_1):page75_i19:vss(173)" )
			)
			( pin "U2D1.DK75"
				( objectStatus "@baseboard_fab2_lib.baseboard_fab2(sch_1):page75_i19:vss(174)" )
			)
			( pin "U2D1.DK73"
				( objectStatus "@baseboard_fab2_lib.baseboard_fab2(sch_1):page75_i19:vss(175)" )
			)
			( pin "U2D1.DK41"
				( objectStatus "@baseboard_fab2_lib.baseboard_fab2(sch_1):page75_i19:vss(176)" )
			)
			( pin "U2D1.DK39"
				( objectStatus "@baseboard_fab2_lib.baseboard_fab2(sch_1):page75_i19:vss(177)" )
			)
			( pin "U2D1.DK35"
				( objectStatus "@baseboard_fab2_lib.baseboard_fab2(sch_1):page75_i19:vss(178)" )
			)
			( pin "U2D1.DK29"
				( objectStatus "@baseboard_fab2_lib.baseboard_fab2(sch_1):page75_i19:vss(179)" )
			)
			( pin "U2D1.DK23"
				( objectStatus "@baseboard_fab2_lib.baseboard_fab2(sch_1):page75_i19:vss(180)" )
			)
			( pin "U2D1.DK7"
				( objectStatus "@baseboard_fab2_lib.baseboard_fab2(sch_1):page75_i19:vss(181)" )
			)
			( pin "U2D1.DJ84"
				( objectStatus "@baseboard_fab2_lib.baseboard_fab2(sch_1):page75_i19:vss(182)" )
			)
			( pin "U2D1.DJ82"
				( objectStatus "@baseboard_fab2_lib.baseboard_fab2(sch_1):page75_i19:vss(183)" )
			)
			( pin "U2D1.DJ78"
				( objectStatus "@baseboard_fab2_lib.baseboard_fab2(sch_1):page75_i19:vss(184)" )
			)
			( pin "U2D1.DJ74"
				( objectStatus "@baseboard_fab2_lib.baseboard_fab2(sch_1):page75_i19:vss(185)" )
			)
			( pin "U2D1.DJ68"
				( objectStatus "@baseboard_fab2_lib.baseboard_fab2(sch_1):page75_i19:vss(186)" )
			)
			( pin "U2D1.DJ42"
				( objectStatus "@baseboard_fab2_lib.baseboard_fab2(sch_1):page75_i19:vss(187)" )
			)
			( pin "U2D1.DJ38"
				( objectStatus "@baseboard_fab2_lib.baseboard_fab2(sch_1):page75_i19:vss(188)" )
			)
			( pin "U2D1.DJ22"
				( objectStatus "@baseboard_fab2_lib.baseboard_fab2(sch_1):page75_i19:vss(189)" )
			)
			( pin "U2D1.H47"
				( objectStatus "@baseboard_fab2_lib.baseboard_fab2(sch_1):page75_i19:vss(190)" )
			)
			( pin "U2D1.DJ10"
				( objectStatus "@baseboard_fab2_lib.baseboard_fab2(sch_1):page75_i19:vss(191)" )
			)
			( pin "U2D1.DJ2"
				( objectStatus "@baseboard_fab2_lib.baseboard_fab2(sch_1):page75_i19:vss(192)" )
			)
			( pin "U2D1.DH83"
				( objectStatus "@baseboard_fab2_lib.baseboard_fab2(sch_1):page75_i19:vss(193)" )
			)
			( pin "U2D1.DH81"
				( objectStatus "@baseboard_fab2_lib.baseboard_fab2(sch_1):page75_i19:vss(194)" )
			)
			( pin "U2D1.DH79"
				( objectStatus "@baseboard_fab2_lib.baseboard_fab2(sch_1):page75_i19:vss(195)" )
			)
			( pin "U2D1.DH73"
				( objectStatus "@baseboard_fab2_lib.baseboard_fab2(sch_1):page75_i19:vss(196)" )
			)
			( pin "U2D1.DH71"
				( objectStatus "@baseboard_fab2_lib.baseboard_fab2(sch_1):page75_i19:vss(197)" )
			)
			( pin "U2D1.DH67"
				( objectStatus "@baseboard_fab2_lib.baseboard_fab2(sch_1):page75_i19:vss(198)" )
			)
			( pin "U2D1.DH41"
				( objectStatus "@baseboard_fab2_lib.baseboard_fab2(sch_1):page75_i19:vss(199)" )
			)
			( pin "U2D1.DH37"
				( objectStatus "@baseboard_fab2_lib.baseboard_fab2(sch_1):page75_i19:vss(200)" )
			)
			( pin "U2D1.DH35"
				( objectStatus "@baseboard_fab2_lib.baseboard_fab2(sch_1):page75_i19:vss(201)" )
			)
			( pin "U2D1.DH33"
				( objectStatus "@baseboard_fab2_lib.baseboard_fab2(sch_1):page75_i19:vss(202)" )
			)
			( pin "U2D1.DH31"
				( objectStatus "@baseboard_fab2_lib.baseboard_fab2(sch_1):page75_i19:vss(203)" )
			)
			( pin "U2D1.DH29"
				( objectStatus "@baseboard_fab2_lib.baseboard_fab2(sch_1):page75_i19:vss(204)" )
			)
			( pin "U2D1.DH27"
				( objectStatus "@baseboard_fab2_lib.baseboard_fab2(sch_1):page75_i19:vss(205)" )
			)
			( pin "U2D1.DH25"
				( objectStatus "@baseboard_fab2_lib.baseboard_fab2(sch_1):page75_i19:vss(206)" )
			)
			( pin "U2D1.DH23"
				( objectStatus "@baseboard_fab2_lib.baseboard_fab2(sch_1):page75_i19:vss(207)" )
			)
			( pin "U2D1.DH15"
				( objectStatus "@baseboard_fab2_lib.baseboard_fab2(sch_1):page75_i19:vss(208)" )
			)
			( pin "U2D1.DH13"
				( objectStatus "@baseboard_fab2_lib.baseboard_fab2(sch_1):page75_i19:vss(209)" )
			)
			( pin "U2D1.DG82"
				( objectStatus "@baseboard_fab2_lib.baseboard_fab2(sch_1):page75_i19:vss(210)" )
			)
			( pin "U2D1.DG80"
				( objectStatus "@baseboard_fab2_lib.baseboard_fab2(sch_1):page75_i19:vss(211)" )
			)
			( pin "U2D1.DG78"
				( objectStatus "@baseboard_fab2_lib.baseboard_fab2(sch_1):page75_i19:vss(212)" )
			)
			( pin "U2D1.DG76"
				( objectStatus "@baseboard_fab2_lib.baseboard_fab2(sch_1):page75_i19:vss(213)" )
			)
			( pin "U2D1.DG68"
				( objectStatus "@baseboard_fab2_lib.baseboard_fab2(sch_1):page75_i19:vss(214)" )
			)
			( pin "U2D1.DG66"
				( objectStatus "@baseboard_fab2_lib.baseboard_fab2(sch_1):page75_i19:vss(215)" )
			)
			( pin "U2D1.DG24"
				( objectStatus "@baseboard_fab2_lib.baseboard_fab2(sch_1):page75_i19:vss(216)" )
			)
			( pin "U2D1.DG16"
				( objectStatus "@baseboard_fab2_lib.baseboard_fab2(sch_1):page75_i19:vss(217)" )
			)
			( pin "U2D1.DG14"
				( objectStatus "@baseboard_fab2_lib.baseboard_fab2(sch_1):page75_i19:vss(218)" )
			)
			( pin "U2D1.H49"
				( objectStatus "@baseboard_fab2_lib.baseboard_fab2(sch_1):page75_i19:vss(219)" )
			)
			( pin "U2D1.DG2"
				( objectStatus "@baseboard_fab2_lib.baseboard_fab2(sch_1):page75_i19:vss(220)" )
			)
			( pin "U2D1.DF85"
				( objectStatus "@baseboard_fab2_lib.baseboard_fab2(sch_1):page75_i19:vss(221)" )
			)
			( pin "U2D1.DF83"
				( objectStatus "@baseboard_fab2_lib.baseboard_fab2(sch_1):page75_i19:vss(222)" )
			)
			( pin "U2D1.DF79"
				( objectStatus "@baseboard_fab2_lib.baseboard_fab2(sch_1):page75_i19:vss(223)" )
			)
			( pin "U2D1.DF73"
				( objectStatus "@baseboard_fab2_lib.baseboard_fab2(sch_1):page75_i19:vss(224)" )
			)
			( pin "U2D1.DF69"
				( objectStatus "@baseboard_fab2_lib.baseboard_fab2(sch_1):page75_i19:vss(225)" )
			)
			( pin "U2D1.DF65"
				( objectStatus "@baseboard_fab2_lib.baseboard_fab2(sch_1):page75_i19:vss(226)" )
			)
			( pin "U2D1.DF41"
				( objectStatus "@baseboard_fab2_lib.baseboard_fab2(sch_1):page75_i19:vss(227)" )
			)
			( pin "U2D1.DF39"
				( objectStatus "@baseboard_fab2_lib.baseboard_fab2(sch_1):page75_i19:vss(228)" )
			)
			( pin "U2D1.DF37"
				( objectStatus "@baseboard_fab2_lib.baseboard_fab2(sch_1):page75_i19:vss(229)" )
			)
			( pin "U2D1.DF35"
				( objectStatus "@baseboard_fab2_lib.baseboard_fab2(sch_1):page75_i19:vss(230)" )
			)
			( pin "U2D1.DF29"
				( objectStatus "@baseboard_fab2_lib.baseboard_fab2(sch_1):page75_i19:vss(231)" )
			)
			( pin "U2D1.DF19"
				( objectStatus "@baseboard_fab2_lib.baseboard_fab2(sch_1):page75_i19:vss(232)" )
			)
			( pin "U2D1.H51"
				( objectStatus "@baseboard_fab2_lib.baseboard_fab2(sch_1):page75_i19:vss(233)" )
			)
			( pin "U2D1.DF7"
				( objectStatus "@baseboard_fab2_lib.baseboard_fab2(sch_1):page75_i19:vss(234)" )
			)
			( pin "U2D1.DF5"
				( objectStatus "@baseboard_fab2_lib.baseboard_fab2(sch_1):page75_i19:vss(235)" )
			)
			( pin "U2D1.DE78"
				( objectStatus "@baseboard_fab2_lib.baseboard_fab2(sch_1):page75_i19:vss(236)" )
			)
			( pin "U2D1.DE72"
				( objectStatus "@baseboard_fab2_lib.baseboard_fab2(sch_1):page75_i19:vss(237)" )
			)
			( pin "U2D1.DE70"
				( objectStatus "@baseboard_fab2_lib.baseboard_fab2(sch_1):page75_i19:vss(238)" )
			)
			( pin "U2D1.DE64"
				( objectStatus "@baseboard_fab2_lib.baseboard_fab2(sch_1):page75_i19:vss(239)" )
			)
			( pin "U2D1.DE36"
				( objectStatus "@baseboard_fab2_lib.baseboard_fab2(sch_1):page75_i19:vss(240)" )
			)
			( pin "U2D1.DE34"
				( objectStatus "@baseboard_fab2_lib.baseboard_fab2(sch_1):page75_i19:vss(241)" )
			)
			( pin "U2D1.DE30"
				( objectStatus "@baseboard_fab2_lib.baseboard_fab2(sch_1):page75_i19:vss(242)" )
			)
			( pin "U2D1.DE28"
				( objectStatus "@baseboard_fab2_lib.baseboard_fab2(sch_1):page75_i19:vss(243)" )
			)
			( pin "U2D1.DE24"
				( objectStatus "@baseboard_fab2_lib.baseboard_fab2(sch_1):page75_i19:vss(244)" )
			)
			( pin "U2D1.DE20"
				( objectStatus "@baseboard_fab2_lib.baseboard_fab2(sch_1):page75_i19:vss(245)" )
			)
			( pin "U2D1.DE18"
				( objectStatus "@baseboard_fab2_lib.baseboard_fab2(sch_1):page75_i19:vss(246)" )
			)
			( pin "U2D1.DE8"
				( objectStatus "@baseboard_fab2_lib.baseboard_fab2(sch_1):page75_i19:vss(247)" )
			)
			( pin "U2D1.DE6"
				( objectStatus "@baseboard_fab2_lib.baseboard_fab2(sch_1):page75_i19:vss(248)" )
			)
			( pin "U2D1.DD83"
				( objectStatus "@baseboard_fab2_lib.baseboard_fab2(sch_1):page75_i19:vss(249)" )
			)
			( pin "U2D1.DD81"
				( objectStatus "@baseboard_fab2_lib.baseboard_fab2(sch_1):page75_i19:vss(250)" )
			)
			( pin "U2D1.DD75"
				( objectStatus "@baseboard_fab2_lib.baseboard_fab2(sch_1):page75_i19:vss(251)" )
			)
			( pin "U2D1.DD73"
				( objectStatus "@baseboard_fab2_lib.baseboard_fab2(sch_1):page75_i19:vss(252)" )
			)
			( pin "U2D1.DD71"
				( objectStatus "@baseboard_fab2_lib.baseboard_fab2(sch_1):page75_i19:vss(253)" )
			)
			( pin "U2D1.DD37"
				( objectStatus "@baseboard_fab2_lib.baseboard_fab2(sch_1):page75_i19:vss(254)" )
			)
			( pin "U2D1.DD33"
				( objectStatus "@baseboard_fab2_lib.baseboard_fab2(sch_1):page75_i19:vss(255)" )
			)
			( pin "U2D1.DD31"
				( objectStatus "@baseboard_fab2_lib.baseboard_fab2(sch_1):page75_i19:vss(256)" )
			)
			( pin "U2D1.DD27"
				( objectStatus "@baseboard_fab2_lib.baseboard_fab2(sch_1):page75_i19:vss(257)" )
			)
			( pin "U2D1.DD23"
				( objectStatus "@baseboard_fab2_lib.baseboard_fab2(sch_1):page75_i19:vss(258)" )
			)
			( pin "U2D1.DD11"
				( objectStatus "@baseboard_fab2_lib.baseboard_fab2(sch_1):page75_i19:vss(259)" )
			)
			( pin "U2D1.DC86"
				( objectStatus "@baseboard_fab2_lib.baseboard_fab2(sch_1):page75_i19:vss(260)" )
			)
			( pin "U2D1.DC84"
				( objectStatus "@baseboard_fab2_lib.baseboard_fab2(sch_1):page75_i19:vss(261)" )
			)
			( pin "U2D1.DC78"
				( objectStatus "@baseboard_fab2_lib.baseboard_fab2(sch_1):page75_i19:vss(262)" )
			)
			( pin "U2D1.DC70"
				( objectStatus "@baseboard_fab2_lib.baseboard_fab2(sch_1):page75_i19:vss(263)" )
			)
			( pin "U2D1.DC68"
				( objectStatus "@baseboard_fab2_lib.baseboard_fab2(sch_1):page75_i19:vss(264)" )
			)
			( pin "U2D1.DC66"
				( objectStatus "@baseboard_fab2_lib.baseboard_fab2(sch_1):page75_i19:vss(265)" )
			)
			( pin "U2D1.DC64"
				( objectStatus "@baseboard_fab2_lib.baseboard_fab2(sch_1):page75_i19:vss(266)" )
			)
			( pin "U2D1.DC42"
				( objectStatus "@baseboard_fab2_lib.baseboard_fab2(sch_1):page75_i19:vss(267)" )
			)
			( pin "U2D1.DC38"
				( objectStatus "@baseboard_fab2_lib.baseboard_fab2(sch_1):page75_i19:vss(268)" )
			)
			( pin "U2D1.DC32"
				( objectStatus "@baseboard_fab2_lib.baseboard_fab2(sch_1):page75_i19:vss(269)" )
			)
			( pin "U2D1.DC26"
				( objectStatus "@baseboard_fab2_lib.baseboard_fab2(sch_1):page75_i19:vss(270)" )
			)
			( pin "U2D1.DC24"
				( objectStatus "@baseboard_fab2_lib.baseboard_fab2(sch_1):page75_i19:vss(271)" )
			)
			( pin "U2D1.DC14"
				( objectStatus "@baseboard_fab2_lib.baseboard_fab2(sch_1):page75_i19:vss(272)" )
			)
			( pin "U2D1.DB85"
				( objectStatus "@baseboard_fab2_lib.baseboard_fab2(sch_1):page75_i19:vss(273)" )
			)
			( pin "U2D1.DB83"
				( objectStatus "@baseboard_fab2_lib.baseboard_fab2(sch_1):page75_i19:vss(274)" )
			)
			( pin "U2D1.DB77"
				( objectStatus "@baseboard_fab2_lib.baseboard_fab2(sch_1):page75_i19:vss(275)" )
			)
			( pin "U2D1.DB73"
				( objectStatus "@baseboard_fab2_lib.baseboard_fab2(sch_1):page75_i19:vss(276)" )
			)
			( pin "U2D1.DB49"
				( objectStatus "@baseboard_fab2_lib.baseboard_fab2(sch_1):page75_i19:vss(277)" )
			)
			( pin "U2D1.DB47"
				( objectStatus "@baseboard_fab2_lib.baseboard_fab2(sch_1):page75_i19:vss(278)" )
			)
			( pin "U2D1.DB41"
				( objectStatus "@baseboard_fab2_lib.baseboard_fab2(sch_1):page75_i19:vss(279)" )
			)
			( pin "U2D1.DB39"
				( objectStatus "@baseboard_fab2_lib.baseboard_fab2(sch_1):page75_i19:vss(280)" )
			)
			( pin "U2D1.DB25"
				( objectStatus "@baseboard_fab2_lib.baseboard_fab2(sch_1):page75_i19:vss(281)" )
			)
			( pin "U2D1.DB23"
				( objectStatus "@baseboard_fab2_lib.baseboard_fab2(sch_1):page75_i19:vss(282)" )
			)
			( pin "U2D1.DB17"
				( objectStatus "@baseboard_fab2_lib.baseboard_fab2(sch_1):page75_i19:vss(283)" )
			)
			( pin "U2D1.DB13"
				( objectStatus "@baseboard_fab2_lib.baseboard_fab2(sch_1):page75_i19:vss(284)" )
			)
			( pin "U2D1.DB3"
				( objectStatus "@baseboard_fab2_lib.baseboard_fab2(sch_1):page75_i19:vss(285)" )
			)
			( pin "U2D1.DA80"
				( objectStatus "@baseboard_fab2_lib.baseboard_fab2(sch_1):page75_i19:vss(286)" )
			)
			( pin "U2D1.DA78"
				( objectStatus "@baseboard_fab2_lib.baseboard_fab2(sch_1):page75_i19:vss(287)" )
			)
			( pin "U2D1.DA76"
				( objectStatus "@baseboard_fab2_lib.baseboard_fab2(sch_1):page75_i19:vss(288)" )
			)
			( pin "U2D1.DA74"
				( objectStatus "@baseboard_fab2_lib.baseboard_fab2(sch_1):page75_i19:vss(289)" )
			)
			( pin "U2D1.DA70"
				( objectStatus "@baseboard_fab2_lib.baseboard_fab2(sch_1):page75_i19:vss(290)" )
			)
			( pin "U2D1.DA64"
				( objectStatus "@baseboard_fab2_lib.baseboard_fab2(sch_1):page75_i19:vss(291)" )
			)
			( pin "U2D1.DA50"
				( objectStatus "@baseboard_fab2_lib.baseboard_fab2(sch_1):page75_i19:vss(292)" )
			)
			( pin "U2D1.DA48"
				( objectStatus "@baseboard_fab2_lib.baseboard_fab2(sch_1):page75_i19:vss(293)" )
			)
			( pin "U2D1.EF79"
				( objectStatus "@baseboard_fab2_lib.baseboard_fab2(sch_1):page75_i20:vss(0)" )
			)
			( pin "U2D1.EF75"
				( objectStatus "@baseboard_fab2_lib.baseboard_fab2(sch_1):page75_i20:vss(1)" )
			)
			( pin "U2D1.EF71"
				( objectStatus "@baseboard_fab2_lib.baseboard_fab2(sch_1):page75_i20:vss(2)" )
			)
			( pin "U2D1.EE78"
				( objectStatus "@baseboard_fab2_lib.baseboard_fab2(sch_1):page75_i20:vss(3)" )
			)
			( pin "U2D1.EE76"
				( objectStatus "@baseboard_fab2_lib.baseboard_fab2(sch_1):page75_i20:vss(4)" )
			)
			( pin "U2D1.EE70"
				( objectStatus "@baseboard_fab2_lib.baseboard_fab2(sch_1):page75_i20:vss(5)" )
			)
			( pin "U2D1.EE36"
				( objectStatus "@baseboard_fab2_lib.baseboard_fab2(sch_1):page75_i20:vss(6)" )
			)
			( pin "U2D1.EE34"
				( objectStatus "@baseboard_fab2_lib.baseboard_fab2(sch_1):page75_i20:vss(7)" )
			)
			( pin "U2D1.EE30"
				( objectStatus "@baseboard_fab2_lib.baseboard_fab2(sch_1):page75_i20:vss(8)" )
			)
			( pin "U2D1.EE28"
				( objectStatus "@baseboard_fab2_lib.baseboard_fab2(sch_1):page75_i20:vss(9)" )
			)
			( pin "U2D1.EE24"
				( objectStatus "@baseboard_fab2_lib.baseboard_fab2(sch_1):page75_i20:vss(10)" )
			)
			( pin "U2D1.ED77"
				( objectStatus "@baseboard_fab2_lib.baseboard_fab2(sch_1):page75_i20:vss(11)" )
			)
			( pin "U2D1.ED35"
				( objectStatus "@baseboard_fab2_lib.baseboard_fab2(sch_1):page75_i20:vss(12)" )
			)
			( pin "U2D1.ED29"
				( objectStatus "@baseboard_fab2_lib.baseboard_fab2(sch_1):page75_i20:vss(13)" )
			)
			( pin "U2D1.ED23"
				( objectStatus "@baseboard_fab2_lib.baseboard_fab2(sch_1):page75_i20:vss(14)" )
			)
			( pin "U2D1.ED15"
				( objectStatus "@baseboard_fab2_lib.baseboard_fab2(sch_1):page75_i20:vss(15)" )
			)
			( pin "U2D1.ED11"
				( objectStatus "@baseboard_fab2_lib.baseboard_fab2(sch_1):page75_i20:vss(16)" )
			)
			( pin "U2D1.EC76"
				( objectStatus "@baseboard_fab2_lib.baseboard_fab2(sch_1):page75_i20:vss(17)" )
			)
			( pin "U2D1.EC74"
				( objectStatus "@baseboard_fab2_lib.baseboard_fab2(sch_1):page75_i20:vss(18)" )
			)
			( pin "U2D1.EC72"
				( objectStatus "@baseboard_fab2_lib.baseboard_fab2(sch_1):page75_i20:vss(19)" )
			)
			( pin "U2D1.EC70"
				( objectStatus "@baseboard_fab2_lib.baseboard_fab2(sch_1):page75_i20:vss(20)" )
			)
			( pin "U2D1.EC10"
				( objectStatus "@baseboard_fab2_lib.baseboard_fab2(sch_1):page75_i20:vss(21)" )
			)
			( pin "U2D1.EB69"
				( objectStatus "@baseboard_fab2_lib.baseboard_fab2(sch_1):page75_i20:vss(22)" )
			)
			( pin "U2D1.EB65"
				( objectStatus "@baseboard_fab2_lib.baseboard_fab2(sch_1):page75_i20:vss(23)" )
			)
			( pin "U2D1.EB41"
				( objectStatus "@baseboard_fab2_lib.baseboard_fab2(sch_1):page75_i20:vss(24)" )
			)
			( pin "U2D1.EB39"
				( objectStatus "@baseboard_fab2_lib.baseboard_fab2(sch_1):page75_i20:vss(25)" )
			)
			( pin "U2D1.EB37"
				( objectStatus "@baseboard_fab2_lib.baseboard_fab2(sch_1):page75_i20:vss(26)" )
			)
			( pin "U2D1.EB35"
				( objectStatus "@baseboard_fab2_lib.baseboard_fab2(sch_1):page75_i20:vss(27)" )
			)
			( pin "U2D1.EB33"
				( objectStatus "@baseboard_fab2_lib.baseboard_fab2(sch_1):page75_i20:vss(28)" )
			)
			( pin "U2D1.EB31"
				( objectStatus "@baseboard_fab2_lib.baseboard_fab2(sch_1):page75_i20:vss(29)" )
			)
			( pin "U2D1.EB29"
				( objectStatus "@baseboard_fab2_lib.baseboard_fab2(sch_1):page75_i20:vss(30)" )
			)
			( pin "U2D1.EB27"
				( objectStatus "@baseboard_fab2_lib.baseboard_fab2(sch_1):page75_i20:vss(31)" )
			)
			( pin "U2D1.EB25"
				( objectStatus "@baseboard_fab2_lib.baseboard_fab2(sch_1):page75_i20:vss(32)" )
			)
			( pin "U2D1.EB23"
				( objectStatus "@baseboard_fab2_lib.baseboard_fab2(sch_1):page75_i20:vss(33)" )
			)
			( pin "U2D1.BR18"
				( objectStatus "@baseboard_fab2_lib.baseboard_fab2(sch_1):page75_i20:vss(34)" )
			)
			( pin "U2D1.EB13"
				( objectStatus "@baseboard_fab2_lib.baseboard_fab2(sch_1):page75_i20:vss(35)" )
			)
			( pin "U2D1.EA82"
				( objectStatus "@baseboard_fab2_lib.baseboard_fab2(sch_1):page75_i20:vss(36)" )
			)
			( pin "U2D1.EA80"
				( objectStatus "@baseboard_fab2_lib.baseboard_fab2(sch_1):page75_i20:vss(37)" )
			)
			( pin "U2D1.EA78"
				( objectStatus "@baseboard_fab2_lib.baseboard_fab2(sch_1):page75_i20:vss(38)" )
			)
			( pin "U2D1.EA76"
				( objectStatus "@baseboard_fab2_lib.baseboard_fab2(sch_1):page75_i20:vss(39)" )
			)
			( pin "U2D1.EA70"
				( objectStatus "@baseboard_fab2_lib.baseboard_fab2(sch_1):page75_i20:vss(40)" )
			)
			( pin "U2D1.EA64"
				( objectStatus "@baseboard_fab2_lib.baseboard_fab2(sch_1):page75_i20:vss(41)" )
			)
			( pin "U2D1.EA42"
				( objectStatus "@baseboard_fab2_lib.baseboard_fab2(sch_1):page75_i20:vss(42)" )
			)
			( pin "U2D1.EA22"
				( objectStatus "@baseboard_fab2_lib.baseboard_fab2(sch_1):page75_i20:vss(43)" )
			)
			( pin "U2D1.EA20"
				( objectStatus "@baseboard_fab2_lib.baseboard_fab2(sch_1):page75_i20:vss(44)" )
			)
			( pin "U2D1.EA16"
				( objectStatus "@baseboard_fab2_lib.baseboard_fab2(sch_1):page75_i20:vss(45)" )
			)
			( pin "U2D1.J16"
				( objectStatus "@baseboard_fab2_lib.baseboard_fab2(sch_1):page75_i20:vss(46)" )
			)
			( pin "U2D1.EA6"
				( objectStatus "@baseboard_fab2_lib.baseboard_fab2(sch_1):page75_i20:vss(47)" )
			)
			( pin "U2D1.DY75"
				( objectStatus "@baseboard_fab2_lib.baseboard_fab2(sch_1):page75_i20:vss(48)" )
			)
			( pin "U2D1.DY71"
				( objectStatus "@baseboard_fab2_lib.baseboard_fab2(sch_1):page75_i20:vss(49)" )
			)
			( pin "U2D1.DY41"
				( objectStatus "@baseboard_fab2_lib.baseboard_fab2(sch_1):page75_i20:vss(50)" )
			)
			( pin "U2D1.DY35"
				( objectStatus "@baseboard_fab2_lib.baseboard_fab2(sch_1):page75_i20:vss(51)" )
			)
			( pin "U2D1.DY29"
				( objectStatus "@baseboard_fab2_lib.baseboard_fab2(sch_1):page75_i20:vss(52)" )
			)
			( pin "U2D1.DY23"
				( objectStatus "@baseboard_fab2_lib.baseboard_fab2(sch_1):page75_i20:vss(53)" )
			)
			( pin "U2D1.DY19"
				( objectStatus "@baseboard_fab2_lib.baseboard_fab2(sch_1):page75_i20:vss(54)" )
			)
			( pin "U2D1.DY5"
				( objectStatus "@baseboard_fab2_lib.baseboard_fab2(sch_1):page75_i20:vss(55)" )
			)
			( pin "U2D1.DW84"
				( objectStatus "@baseboard_fab2_lib.baseboard_fab2(sch_1):page75_i20:vss(56)" )
			)
			( pin "U2D1.DW82"
				( objectStatus "@baseboard_fab2_lib.baseboard_fab2(sch_1):page75_i20:vss(57)" )
			)
			( pin "U2D1.DW8"
				( objectStatus "@baseboard_fab2_lib.baseboard_fab2(sch_1):page75_i20:vss(58)" )
			)
			( pin "U2D1.DW76"
				( objectStatus "@baseboard_fab2_lib.baseboard_fab2(sch_1):page75_i20:vss(59)" )
			)
			( pin "U2D1.DW74"
				( objectStatus "@baseboard_fab2_lib.baseboard_fab2(sch_1):page75_i20:vss(60)" )
			)
			( pin "U2D1.DW72"
				( objectStatus "@baseboard_fab2_lib.baseboard_fab2(sch_1):page75_i20:vss(61)" )
			)
			( pin "U2D1.DW70"
				( objectStatus "@baseboard_fab2_lib.baseboard_fab2(sch_1):page75_i20:vss(62)" )
			)
			( pin "U2D1.DW68"
				( objectStatus "@baseboard_fab2_lib.baseboard_fab2(sch_1):page75_i20:vss(63)" )
			)
			( pin "U2D1.DW66"
				( objectStatus "@baseboard_fab2_lib.baseboard_fab2(sch_1):page75_i20:vss(64)" )
			)
			( pin "U2D1.DW64"
				( objectStatus "@baseboard_fab2_lib.baseboard_fab2(sch_1):page75_i20:vss(65)" )
			)
			( pin "U2D1.DW40"
				( objectStatus "@baseboard_fab2_lib.baseboard_fab2(sch_1):page75_i20:vss(66)" )
			)
			( pin "U2D1.DW36"
				( objectStatus "@baseboard_fab2_lib.baseboard_fab2(sch_1):page75_i20:vss(67)" )
			)
			( pin "U2D1.DW34"
				( objectStatus "@baseboard_fab2_lib.baseboard_fab2(sch_1):page75_i20:vss(68)" )
			)
			( pin "U2D1.DW30"
				( objectStatus "@baseboard_fab2_lib.baseboard_fab2(sch_1):page75_i20:vss(69)" )
			)
			( pin "U2D1.DW28"
				( objectStatus "@baseboard_fab2_lib.baseboard_fab2(sch_1):page75_i20:vss(70)" )
			)
			( pin "U2D1.DW24"
				( objectStatus "@baseboard_fab2_lib.baseboard_fab2(sch_1):page75_i20:vss(71)" )
			)
			( pin "U2D1.DW20"
				( objectStatus "@baseboard_fab2_lib.baseboard_fab2(sch_1):page75_i20:vss(72)" )
			)
			( pin "U2D1.DW12"
				( objectStatus "@baseboard_fab2_lib.baseboard_fab2(sch_1):page75_i20:vss(73)" )
			)
			( pin "U2D1.DV81"
				( objectStatus "@baseboard_fab2_lib.baseboard_fab2(sch_1):page75_i20:vss(74)" )
			)
			( pin "U2D1.DV77"
				( objectStatus "@baseboard_fab2_lib.baseboard_fab2(sch_1):page75_i20:vss(75)" )
			)
			( pin "U2D1.DV73"
				( objectStatus "@baseboard_fab2_lib.baseboard_fab2(sch_1):page75_i20:vss(76)" )
			)
			( pin "U2D1.DV39"
				( objectStatus "@baseboard_fab2_lib.baseboard_fab2(sch_1):page75_i20:vss(77)" )
			)
			( pin "U2D1.DV37"
				( objectStatus "@baseboard_fab2_lib.baseboard_fab2(sch_1):page75_i20:vss(78)" )
			)
			( pin "U2D1.DV33"
				( objectStatus "@baseboard_fab2_lib.baseboard_fab2(sch_1):page75_i20:vss(79)" )
			)
			( pin "U2D1.DV31"
				( objectStatus "@baseboard_fab2_lib.baseboard_fab2(sch_1):page75_i20:vss(80)" )
			)
			( pin "U2D1.DV27"
				( objectStatus "@baseboard_fab2_lib.baseboard_fab2(sch_1):page75_i20:vss(81)" )
			)
			( pin "U2D1.DV25"
				( objectStatus "@baseboard_fab2_lib.baseboard_fab2(sch_1):page75_i20:vss(82)" )
			)
			( pin "U2D1.DV21"
				( objectStatus "@baseboard_fab2_lib.baseboard_fab2(sch_1):page75_i20:vss(83)" )
			)
			( pin "U2D1.DU84"
				( objectStatus "@baseboard_fab2_lib.baseboard_fab2(sch_1):page75_i20:vss(84)" )
			)
			( pin "U2D1.DU82"
				( objectStatus "@baseboard_fab2_lib.baseboard_fab2(sch_1):page75_i20:vss(85)" )
			)
			( pin "U2D1.DU80"
				( objectStatus "@baseboard_fab2_lib.baseboard_fab2(sch_1):page75_i20:vss(86)" )
			)
			( pin "U2D1.DU78"
				( objectStatus "@baseboard_fab2_lib.baseboard_fab2(sch_1):page75_i20:vss(87)" )
			)
			( pin "U2D1.DU72"
				( objectStatus "@baseboard_fab2_lib.baseboard_fab2(sch_1):page75_i20:vss(88)" )
			)
			( pin "U2D1.DU70"
				( objectStatus "@baseboard_fab2_lib.baseboard_fab2(sch_1):page75_i20:vss(89)" )
			)
			( pin "U2D1.DU38"
				( objectStatus "@baseboard_fab2_lib.baseboard_fab2(sch_1):page75_i20:vss(90)" )
			)
			( pin "U2D1.DU32"
				( objectStatus "@baseboard_fab2_lib.baseboard_fab2(sch_1):page75_i20:vss(91)" )
			)
			( pin "U2D1.DU26"
				( objectStatus "@baseboard_fab2_lib.baseboard_fab2(sch_1):page75_i20:vss(92)" )
			)
			( pin "U2D1.DU22"
				( objectStatus "@baseboard_fab2_lib.baseboard_fab2(sch_1):page75_i20:vss(93)" )
			)
			( pin "U2D1.CN14"
				( objectStatus "@baseboard_fab2_lib.baseboard_fab2(sch_1):page75_i20:vss(94)" )
			)
			( pin "U2D1.DU14"
				( objectStatus "@baseboard_fab2_lib.baseboard_fab2(sch_1):page75_i20:vss(95)" )
			)
			( pin "U2D1.DU10"
				( objectStatus "@baseboard_fab2_lib.baseboard_fab2(sch_1):page75_i20:vss(96)" )
			)
			( pin "U2D1.DT85"
				( objectStatus "@baseboard_fab2_lib.baseboard_fab2(sch_1):page75_i20:vss(97)" )
			)
			( pin "U2D1.DT83"
				( objectStatus "@baseboard_fab2_lib.baseboard_fab2(sch_1):page75_i20:vss(98)" )
			)
			( pin "U2D1.DT79"
				( objectStatus "@baseboard_fab2_lib.baseboard_fab2(sch_1):page75_i20:vss(99)" )
			)
			( pin "U2D1.DT69"
				( objectStatus "@baseboard_fab2_lib.baseboard_fab2(sch_1):page75_i20:vss(100)" )
			)
			( pin "U2D1.DT65"
				( objectStatus "@baseboard_fab2_lib.baseboard_fab2(sch_1):page75_i20:vss(101)" )
			)
			( pin "U2D1.DH21"
				( objectStatus "@baseboard_fab2_lib.baseboard_fab2(sch_1):page75_i20:vss(102)" )
			)
			( pin "U2D1.DT17"
				( objectStatus "@baseboard_fab2_lib.baseboard_fab2(sch_1):page75_i20:vss(103)" )
			)
			( pin "U2D1.DT3"
				( objectStatus "@baseboard_fab2_lib.baseboard_fab2(sch_1):page75_i20:vss(104)" )
			)
			( pin "U2D1.DR78"
				( objectStatus "@baseboard_fab2_lib.baseboard_fab2(sch_1):page75_i20:vss(105)" )
			)
			( pin "U2D1.DR76"
				( objectStatus "@baseboard_fab2_lib.baseboard_fab2(sch_1):page75_i20:vss(106)" )
			)
			( pin "U2D1.DR74"
				( objectStatus "@baseboard_fab2_lib.baseboard_fab2(sch_1):page75_i20:vss(107)" )
			)
			( pin "U2D1.DR72"
				( objectStatus "@baseboard_fab2_lib.baseboard_fab2(sch_1):page75_i20:vss(108)" )
			)
			( pin "U2D1.DR70"
				( objectStatus "@baseboard_fab2_lib.baseboard_fab2(sch_1):page75_i20:vss(109)" )
			)
			( pin "U2D1.DR68"
				( objectStatus "@baseboard_fab2_lib.baseboard_fab2(sch_1):page75_i20:vss(110)" )
			)
			( pin "U2D1.DR66"
				( objectStatus "@baseboard_fab2_lib.baseboard_fab2(sch_1):page75_i20:vss(111)" )
			)
			( pin "U2D1.DR42"
				( objectStatus "@baseboard_fab2_lib.baseboard_fab2(sch_1):page75_i20:vss(112)" )
			)
			( pin "U2D1.DR40"
				( objectStatus "@baseboard_fab2_lib.baseboard_fab2(sch_1):page75_i20:vss(113)" )
			)
			( pin "U2D1.DR38"
				( objectStatus "@baseboard_fab2_lib.baseboard_fab2(sch_1):page75_i20:vss(114)" )
			)
			( pin "U2D1.DR36"
				( objectStatus "@baseboard_fab2_lib.baseboard_fab2(sch_1):page75_i20:vss(115)" )
			)
			( pin "U2D1.DR34"
				( objectStatus "@baseboard_fab2_lib.baseboard_fab2(sch_1):page75_i20:vss(116)" )
			)
			( pin "U2D1.DR32"
				( objectStatus "@baseboard_fab2_lib.baseboard_fab2(sch_1):page75_i20:vss(117)" )
			)
			( pin "U2D1.DR30"
				( objectStatus "@baseboard_fab2_lib.baseboard_fab2(sch_1):page75_i20:vss(118)" )
			)
			( pin "U2D1.DR28"
				( objectStatus "@baseboard_fab2_lib.baseboard_fab2(sch_1):page75_i20:vss(119)" )
			)
			( pin "U2D1.DR26"
				( objectStatus "@baseboard_fab2_lib.baseboard_fab2(sch_1):page75_i20:vss(120)" )
			)
			( pin "U2D1.DR24"
				( objectStatus "@baseboard_fab2_lib.baseboard_fab2(sch_1):page75_i20:vss(121)" )
			)
			( pin "U2D1.DR22"
				( objectStatus "@baseboard_fab2_lib.baseboard_fab2(sch_1):page75_i20:vss(122)" )
			)
			( pin "U2D1.DR20"
				( objectStatus "@baseboard_fab2_lib.baseboard_fab2(sch_1):page75_i20:vss(123)" )
			)
			( pin "U2D1.CL22"
				( objectStatus "@baseboard_fab2_lib.baseboard_fab2(sch_1):page75_i20:vss(124)" )
			)
			( pin "U2D1.CA20"
				( objectStatus "@baseboard_fab2_lib.baseboard_fab2(sch_1):page75_i20:vss(125)" )
			)
			( pin "U2D1.DR6"
				( objectStatus "@baseboard_fab2_lib.baseboard_fab2(sch_1):page75_i20:vss(126)" )
			)
			( pin "U2D1.BR26"
				( objectStatus "@baseboard_fab2_lib.baseboard_fab2(sch_1):page75_i20:vss(127)" )
			)
			( pin "U2D1.DP83"
				( objectStatus "@baseboard_fab2_lib.baseboard_fab2(sch_1):page75_i20:vss(128)" )
			)
			( pin "U2D1.DP81"
				( objectStatus "@baseboard_fab2_lib.baseboard_fab2(sch_1):page75_i20:vss(129)" )
			)
			( pin "U2D1.DP71"
				( objectStatus "@baseboard_fab2_lib.baseboard_fab2(sch_1):page75_i20:vss(130)" )
			)
			( pin "U2D1.DP69"
				( objectStatus "@baseboard_fab2_lib.baseboard_fab2(sch_1):page75_i20:vss(131)" )
			)
			( pin "U2D1.DP67"
				( objectStatus "@baseboard_fab2_lib.baseboard_fab2(sch_1):page75_i20:vss(132)" )
			)
			( pin "U2D1.DN78"
				( objectStatus "@baseboard_fab2_lib.baseboard_fab2(sch_1):page75_i20:vss(133)" )
			)
			( pin "C3D21.1"
				( objectStatus "@baseboard_fab2_lib.baseboard_fab2(sch_1):page76_i1:a" )
			)
			( pin "C3D21.2"
				( objectStatus "@baseboard_fab2_lib.baseboard_fab2(sch_1):page76_i1:b" )
			)
			( pin "C3D5.1"
				( objectStatus "@baseboard_fab2_lib.baseboard_fab2(sch_1):page76_i3:a" )
			)
			( pin "C3D5.2"
				( objectStatus "@baseboard_fab2_lib.baseboard_fab2(sch_1):page76_i3:b" )
			)
			( pin "C3D12.1"
				( objectStatus "@baseboard_fab2_lib.baseboard_fab2(sch_1):page76_i4:a" )
			)
			( pin "C3D12.2"
				( objectStatus "@baseboard_fab2_lib.baseboard_fab2(sch_1):page76_i4:b" )
			)
			( pin "C3D4.1"
				( objectStatus "@baseboard_fab2_lib.baseboard_fab2(sch_1):page76_i5:a" )
			)
			( pin "C3D4.2"
				( objectStatus "@baseboard_fab2_lib.baseboard_fab2(sch_1):page76_i5:b" )
			)
			( pin "C3D11.1"
				( objectStatus "@baseboard_fab2_lib.baseboard_fab2(sch_1):page76_i7:a" )
			)
			( pin "C3D11.2"
				( objectStatus "@baseboard_fab2_lib.baseboard_fab2(sch_1):page76_i7:b" )
			)
			( pin "C3D13.1"
				( objectStatus "@baseboard_fab2_lib.baseboard_fab2(sch_1):page76_i8:a" )
			)
			( pin "C3D13.2"
				( objectStatus "@baseboard_fab2_lib.baseboard_fab2(sch_1):page76_i8:b" )
			)
			( pin "C2D40.1"
				( objectStatus "@baseboard_fab2_lib.baseboard_fab2(sch_1):page76_i10:a" )
			)
			( pin "C2D40.2"
				( objectStatus "@baseboard_fab2_lib.baseboard_fab2(sch_1):page76_i10:b" )
			)
			( pin "C3D9.1"
				( objectStatus "@baseboard_fab2_lib.baseboard_fab2(sch_1):page76_i15:a" )
			)
			( pin "C3D9.2"
				( objectStatus "@baseboard_fab2_lib.baseboard_fab2(sch_1):page76_i15:b" )
			)
			( pin "C3D8.1"
				( objectStatus "@baseboard_fab2_lib.baseboard_fab2(sch_1):page76_i18:a" )
			)
			( pin "C3D8.2"
				( objectStatus "@baseboard_fab2_lib.baseboard_fab2(sch_1):page76_i18:b" )
			)
			( pin "C7P4.1"
				( objectStatus "@baseboard_fab2_lib.baseboard_fab2(sch_1):page76_i271:a" )
			)
			( pin "C7P4.2"
				( objectStatus "@baseboard_fab2_lib.baseboard_fab2(sch_1):page76_i271:b" )
			)
			( pin "C8P15.1"
				( objectStatus "@baseboard_fab2_lib.baseboard_fab2(sch_1):page76_i270:a" )
			)
			( pin "C8P15.2"
				( objectStatus "@baseboard_fab2_lib.baseboard_fab2(sch_1):page76_i270:b" )
			)
			( pin "C7P13.1"
				( objectStatus "@baseboard_fab2_lib.baseboard_fab2(sch_1):page76_i269:a" )
			)
			( pin "C7P13.2"
				( objectStatus "@baseboard_fab2_lib.baseboard_fab2(sch_1):page76_i269:b" )
			)
			( pin "C7P17.1"
				( objectStatus "@baseboard_fab2_lib.baseboard_fab2(sch_1):page76_i29:a" )
			)
			( pin "C7P17.2"
				( objectStatus "@baseboard_fab2_lib.baseboard_fab2(sch_1):page76_i29:b" )
			)
			( pin "C2D8.1"
				( objectStatus "@baseboard_fab2_lib.baseboard_fab2(sch_1):page76_i33:a" )
			)
			( pin "C2D8.2"
				( objectStatus "@baseboard_fab2_lib.baseboard_fab2(sch_1):page76_i33:b" )
			)
			( pin "C2D10.1"
				( objectStatus "@baseboard_fab2_lib.baseboard_fab2(sch_1):page76_i37:a" )
			)
			( pin "C2D10.2"
				( objectStatus "@baseboard_fab2_lib.baseboard_fab2(sch_1):page76_i37:b" )
			)
			( pin "C2D11.1"
				( objectStatus "@baseboard_fab2_lib.baseboard_fab2(sch_1):page76_i42:a" )
			)
			( pin "C2D11.2"
				( objectStatus "@baseboard_fab2_lib.baseboard_fab2(sch_1):page76_i42:b" )
			)
			( pin "C2D9.1"
				( objectStatus "@baseboard_fab2_lib.baseboard_fab2(sch_1):page76_i43:a" )
			)
			( pin "C2D9.2"
				( objectStatus "@baseboard_fab2_lib.baseboard_fab2(sch_1):page76_i43:b" )
			)
			( pin "C7P8.1"
				( objectStatus "@baseboard_fab2_lib.baseboard_fab2(sch_1):page76_i265:a" )
			)
			( pin "C7P8.2"
				( objectStatus "@baseboard_fab2_lib.baseboard_fab2(sch_1):page76_i265:b" )
			)
			( pin "C7P15.1"
				( objectStatus "@baseboard_fab2_lib.baseboard_fab2(sch_1):page76_i263:a" )
			)
			( pin "C7P15.2"
				( objectStatus "@baseboard_fab2_lib.baseboard_fab2(sch_1):page76_i263:b" )
			)
			( pin "C7P11.1"
				( objectStatus "@baseboard_fab2_lib.baseboard_fab2(sch_1):page76_i262:a" )
			)
			( pin "C7P11.2"
				( objectStatus "@baseboard_fab2_lib.baseboard_fab2(sch_1):page76_i262:b" )
			)
			( pin "C8P25.1"
				( objectStatus "@baseboard_fab2_lib.baseboard_fab2(sch_1):page76_i251:a" )
			)
			( pin "C8P25.2"
				( objectStatus "@baseboard_fab2_lib.baseboard_fab2(sch_1):page76_i251:b" )
			)
			( pin "C7P18.1"
				( objectStatus "@baseboard_fab2_lib.baseboard_fab2(sch_1):page76_i51:a" )
			)
			( pin "C7P18.2"
				( objectStatus "@baseboard_fab2_lib.baseboard_fab2(sch_1):page76_i51:b" )
			)
			( pin "C7P3.1"
				( objectStatus "@baseboard_fab2_lib.baseboard_fab2(sch_1):page76_i52:a" )
			)
			( pin "C7P3.2"
				( objectStatus "@baseboard_fab2_lib.baseboard_fab2(sch_1):page76_i52:b" )
			)
			( pin "C8P27.1"
				( objectStatus "@baseboard_fab2_lib.baseboard_fab2(sch_1):page76_i250:a" )
			)
			( pin "C8P27.2"
				( objectStatus "@baseboard_fab2_lib.baseboard_fab2(sch_1):page76_i250:b" )
			)
			( pin "C8P21.1"
				( objectStatus "@baseboard_fab2_lib.baseboard_fab2(sch_1):page76_i249:a" )
			)
			( pin "C8P21.2"
				( objectStatus "@baseboard_fab2_lib.baseboard_fab2(sch_1):page76_i249:b" )
			)
			( pin "C2D12.1"
				( objectStatus "@baseboard_fab2_lib.baseboard_fab2(sch_1):page76_i59:a" )
			)
			( pin "C2D12.2"
				( objectStatus "@baseboard_fab2_lib.baseboard_fab2(sch_1):page76_i59:b" )
			)
			( pin "C2D22.1"
				( objectStatus "@baseboard_fab2_lib.baseboard_fab2(sch_1):page76_i61:a" )
			)
			( pin "C2D22.2"
				( objectStatus "@baseboard_fab2_lib.baseboard_fab2(sch_1):page76_i61:b" )
			)
			( pin "C2D31.1"
				( objectStatus "@baseboard_fab2_lib.baseboard_fab2(sch_1):page76_i63:a" )
			)
			( pin "C2D31.2"
				( objectStatus "@baseboard_fab2_lib.baseboard_fab2(sch_1):page76_i63:b" )
			)
			( pin "C2D21.1"
				( objectStatus "@baseboard_fab2_lib.baseboard_fab2(sch_1):page76_i65:a" )
			)
			( pin "C2D21.2"
				( objectStatus "@baseboard_fab2_lib.baseboard_fab2(sch_1):page76_i65:b" )
			)
			( pin "C2D27.1"
				( objectStatus "@baseboard_fab2_lib.baseboard_fab2(sch_1):page76_i66:a" )
			)
			( pin "C2D27.2"
				( objectStatus "@baseboard_fab2_lib.baseboard_fab2(sch_1):page76_i66:b" )
			)
			( pin "C3D2.1"
				( objectStatus "@baseboard_fab2_lib.baseboard_fab2(sch_1):page76_i69:a" )
			)
			( pin "C3D2.2"
				( objectStatus "@baseboard_fab2_lib.baseboard_fab2(sch_1):page76_i69:b" )
			)
			( pin "C2D36.1"
				( objectStatus "@baseboard_fab2_lib.baseboard_fab2(sch_1):page76_i70:a" )
			)
			( pin "C2D36.2"
				( objectStatus "@baseboard_fab2_lib.baseboard_fab2(sch_1):page76_i70:b" )
			)
			( pin "C2D13.1"
				( objectStatus "@baseboard_fab2_lib.baseboard_fab2(sch_1):page76_i73:a" )
			)
			( pin "C2D13.2"
				( objectStatus "@baseboard_fab2_lib.baseboard_fab2(sch_1):page76_i73:b" )
			)
			( pin "C2D19.1"
				( objectStatus "@baseboard_fab2_lib.baseboard_fab2(sch_1):page76_i75:a" )
			)
			( pin "C2D19.2"
				( objectStatus "@baseboard_fab2_lib.baseboard_fab2(sch_1):page76_i75:b" )
			)
			( pin "C2D14.1"
				( objectStatus "@baseboard_fab2_lib.baseboard_fab2(sch_1):page76_i76:a" )
			)
			( pin "C2D14.2"
				( objectStatus "@baseboard_fab2_lib.baseboard_fab2(sch_1):page76_i76:b" )
			)
			( pin "C2D20.1"
				( objectStatus "@baseboard_fab2_lib.baseboard_fab2(sch_1):page76_i79:a" )
			)
			( pin "C2D20.2"
				( objectStatus "@baseboard_fab2_lib.baseboard_fab2(sch_1):page76_i79:b" )
			)
			( pin "C2D24.1"
				( objectStatus "@baseboard_fab2_lib.baseboard_fab2(sch_1):page76_i80:a" )
			)
			( pin "C2D24.2"
				( objectStatus "@baseboard_fab2_lib.baseboard_fab2(sch_1):page76_i80:b" )
			)
			( pin "C2D25.1"
				( objectStatus "@baseboard_fab2_lib.baseboard_fab2(sch_1):page76_i82:a" )
			)
			( pin "C2D25.2"
				( objectStatus "@baseboard_fab2_lib.baseboard_fab2(sch_1):page76_i82:b" )
			)
			( pin "C2D30.1"
				( objectStatus "@baseboard_fab2_lib.baseboard_fab2(sch_1):page76_i83:a" )
			)
			( pin "C2D30.2"
				( objectStatus "@baseboard_fab2_lib.baseboard_fab2(sch_1):page76_i83:b" )
			)
			( pin "C2D33.1"
				( objectStatus "@baseboard_fab2_lib.baseboard_fab2(sch_1):page76_i85:a" )
			)
			( pin "C2D33.2"
				( objectStatus "@baseboard_fab2_lib.baseboard_fab2(sch_1):page76_i85:b" )
			)
			( pin "C8P20.1"
				( objectStatus "@baseboard_fab2_lib.baseboard_fab2(sch_1):page76_i89:a" )
			)
			( pin "C8P20.2"
				( objectStatus "@baseboard_fab2_lib.baseboard_fab2(sch_1):page76_i89:b" )
			)
			( pin "C2D32.1"
				( objectStatus "@baseboard_fab2_lib.baseboard_fab2(sch_1):page76_i90:a" )
			)
			( pin "C2D32.2"
				( objectStatus "@baseboard_fab2_lib.baseboard_fab2(sch_1):page76_i90:b" )
			)
			( pin "C8P18.1"
				( objectStatus "@baseboard_fab2_lib.baseboard_fab2(sch_1):page76_i92:a" )
			)
			( pin "C8P18.2"
				( objectStatus "@baseboard_fab2_lib.baseboard_fab2(sch_1):page76_i92:b" )
			)
			( pin "C8P19.1"
				( objectStatus "@baseboard_fab2_lib.baseboard_fab2(sch_1):page76_i103:a" )
			)
			( pin "C8P19.2"
				( objectStatus "@baseboard_fab2_lib.baseboard_fab2(sch_1):page76_i103:b" )
			)
			( pin "U7W1.4"
				( objectStatus "@baseboard_fab2_lib.baseboard_fab2(sch_1):page166_i34:a" )
			)
			( pin "U7W1.3"
				( objectStatus "@baseboard_fab2_lib.baseboard_fab2(sch_1):page166_i34:b0" )
			)
			( pin "U7W1.1"
				( objectStatus "@baseboard_fab2_lib.baseboard_fab2(sch_1):page166_i34:b1" )
			)
			( pin "U7W1.2"
				( objectStatus "@baseboard_fab2_lib.baseboard_fab2(sch_1):page166_i34:gnd" )
			)
			( pin "U7W1.6"
				( objectStatus "@baseboard_fab2_lib.baseboard_fab2(sch_1):page166_i34:s" )
			)
			( pin "U7W1.5"
				( objectStatus "@baseboard_fab2_lib.baseboard_fab2(sch_1):page166_i34:vcc" )
			)
			( pin "C8P12.1"
				( objectStatus "@baseboard_fab2_lib.baseboard_fab2(sch_1):page76_i107:a" )
			)
			( pin "C8P12.2"
				( objectStatus "@baseboard_fab2_lib.baseboard_fab2(sch_1):page76_i107:b" )
			)
			( pin "C2D26.1"
				( objectStatus "@baseboard_fab2_lib.baseboard_fab2(sch_1):page76_i108:a" )
			)
			( pin "C2D26.2"
				( objectStatus "@baseboard_fab2_lib.baseboard_fab2(sch_1):page76_i108:b" )
			)
			( pin "C2D23.1"
				( objectStatus "@baseboard_fab2_lib.baseboard_fab2(sch_1):page76_i112:a" )
			)
			( pin "C2D23.2"
				( objectStatus "@baseboard_fab2_lib.baseboard_fab2(sch_1):page76_i112:b" )
			)
			( pin "C2D17.1"
				( objectStatus "@baseboard_fab2_lib.baseboard_fab2(sch_1):page76_i114:a" )
			)
			( pin "C2D17.2"
				( objectStatus "@baseboard_fab2_lib.baseboard_fab2(sch_1):page76_i114:b" )
			)
			( pin "C2D2.1"
				( objectStatus "@baseboard_fab2_lib.baseboard_fab2(sch_1):page228_i257:a" )
			)
			( pin "C2D2.2"
				( objectStatus "@baseboard_fab2_lib.baseboard_fab2(sch_1):page228_i257:b" )
			)
			( pin "C8P26.1"
				( objectStatus "@baseboard_fab2_lib.baseboard_fab2(sch_1):page76_i118:a" )
			)
			( pin "C8P26.2"
				( objectStatus "@baseboard_fab2_lib.baseboard_fab2(sch_1):page76_i118:b" )
			)
			( pin "C2D37.1"
				( objectStatus "@baseboard_fab2_lib.baseboard_fab2(sch_1):page76_i119:a" )
			)
			( pin "C2D37.2"
				( objectStatus "@baseboard_fab2_lib.baseboard_fab2(sch_1):page76_i119:b" )
			)
			( pin "C2D34.1"
				( objectStatus "@baseboard_fab2_lib.baseboard_fab2(sch_1):page76_i122:a" )
			)
			( pin "C2D34.2"
				( objectStatus "@baseboard_fab2_lib.baseboard_fab2(sch_1):page76_i122:b" )
			)
			( pin "C2D1.1"
				( objectStatus "@baseboard_fab2_lib.baseboard_fab2(sch_1):page228_i258:a" )
			)
			( pin "C2D1.2"
				( objectStatus "@baseboard_fab2_lib.baseboard_fab2(sch_1):page228_i258:b" )
			)
			( pin "C2D16.1"
				( objectStatus "@baseboard_fab2_lib.baseboard_fab2(sch_1):page76_i124:a" )
			)
			( pin "C2D16.2"
				( objectStatus "@baseboard_fab2_lib.baseboard_fab2(sch_1):page76_i124:b" )
			)
			( pin "C8P29.1"
				( objectStatus "@baseboard_fab2_lib.baseboard_fab2(sch_1):page76_i125:a" )
			)
			( pin "C8P29.2"
				( objectStatus "@baseboard_fab2_lib.baseboard_fab2(sch_1):page76_i125:b" )
			)
			( pin "C8P10.1"
				( objectStatus "@baseboard_fab2_lib.baseboard_fab2(sch_1):page76_i127:a" )
			)
			( pin "C8P10.2"
				( objectStatus "@baseboard_fab2_lib.baseboard_fab2(sch_1):page76_i127:b" )
			)
			( pin "C8P16.1"
				( objectStatus "@baseboard_fab2_lib.baseboard_fab2(sch_1):page76_i129:a" )
			)
			( pin "C8P16.2"
				( objectStatus "@baseboard_fab2_lib.baseboard_fab2(sch_1):page76_i129:b" )
			)
			( pin "C7W1.1"
				( objectStatus "@baseboard_fab2_lib.baseboard_fab2(sch_1):page166_i36:a" )
			)
			( pin "C7W1.2"
				( objectStatus "@baseboard_fab2_lib.baseboard_fab2(sch_1):page166_i36:b" )
			)
			( pin "C8P13.1"
				( objectStatus "@baseboard_fab2_lib.baseboard_fab2(sch_1):page76_i132:a" )
			)
			( pin "C8P13.2"
				( objectStatus "@baseboard_fab2_lib.baseboard_fab2(sch_1):page76_i132:b" )
			)
			( pin "C8P28.1"
				( objectStatus "@baseboard_fab2_lib.baseboard_fab2(sch_1):page76_i137:a" )
			)
			( pin "C8P28.2"
				( objectStatus "@baseboard_fab2_lib.baseboard_fab2(sch_1):page76_i137:b" )
			)
			( pin "C8P11.1"
				( objectStatus "@baseboard_fab2_lib.baseboard_fab2(sch_1):page76_i139:a" )
			)
			( pin "C8P11.2"
				( objectStatus "@baseboard_fab2_lib.baseboard_fab2(sch_1):page76_i139:b" )
			)
			( pin "R8D40.1"
				( objectStatus "@baseboard_fab2_lib.baseboard_fab2(sch_1):page196_i130:a" )
			)
			( pin "R8D40.2"
				( objectStatus "@baseboard_fab2_lib.baseboard_fab2(sch_1):page196_i130:b" )
			)
			( pin "C2D15.1"
				( objectStatus "@baseboard_fab2_lib.baseboard_fab2(sch_1):page76_i159:a" )
			)
			( pin "C2D15.2"
				( objectStatus "@baseboard_fab2_lib.baseboard_fab2(sch_1):page76_i159:b" )
			)
			( pin "C2D38.1"
				( objectStatus "@baseboard_fab2_lib.baseboard_fab2(sch_1):page76_i160:a" )
			)
			( pin "C2D38.2"
				( objectStatus "@baseboard_fab2_lib.baseboard_fab2(sch_1):page76_i160:b" )
			)
			( pin "C2D35.1"
				( objectStatus "@baseboard_fab2_lib.baseboard_fab2(sch_1):page76_i161:a" )
			)
			( pin "C2D35.2"
				( objectStatus "@baseboard_fab2_lib.baseboard_fab2(sch_1):page76_i161:b" )
			)
			( pin "C3D7.1"
				( objectStatus "@baseboard_fab2_lib.baseboard_fab2(sch_1):page76_i164:a" )
			)
			( pin "C3D7.2"
				( objectStatus "@baseboard_fab2_lib.baseboard_fab2(sch_1):page76_i164:b" )
			)
			( pin "C2D39.1"
				( objectStatus "@baseboard_fab2_lib.baseboard_fab2(sch_1):page76_i165:a" )
			)
			( pin "C2D39.2"
				( objectStatus "@baseboard_fab2_lib.baseboard_fab2(sch_1):page76_i165:b" )
			)
			( pin "C3D17.1"
				( objectStatus "@baseboard_fab2_lib.baseboard_fab2(sch_1):page76_i166:a" )
			)
			( pin "C3D17.2"
				( objectStatus "@baseboard_fab2_lib.baseboard_fab2(sch_1):page76_i166:b" )
			)
			( pin "C3D18.1"
				( objectStatus "@baseboard_fab2_lib.baseboard_fab2(sch_1):page76_i169:a" )
			)
			( pin "C3D18.2"
				( objectStatus "@baseboard_fab2_lib.baseboard_fab2(sch_1):page76_i169:b" )
			)
			( pin "C3D6.1"
				( objectStatus "@baseboard_fab2_lib.baseboard_fab2(sch_1):page76_i170:a" )
			)
			( pin "C3D6.2"
				( objectStatus "@baseboard_fab2_lib.baseboard_fab2(sch_1):page76_i170:b" )
			)
			( pin "C3D14.1"
				( objectStatus "@baseboard_fab2_lib.baseboard_fab2(sch_1):page76_i171:a" )
			)
			( pin "C3D14.2"
				( objectStatus "@baseboard_fab2_lib.baseboard_fab2(sch_1):page76_i171:b" )
			)
			( pin "C3D23.1"
				( objectStatus "@baseboard_fab2_lib.baseboard_fab2(sch_1):page76_i172:a" )
			)
			( pin "C3D23.2"
				( objectStatus "@baseboard_fab2_lib.baseboard_fab2(sch_1):page76_i172:b" )
			)
			( pin "C3D15.1"
				( objectStatus "@baseboard_fab2_lib.baseboard_fab2(sch_1):page76_i174:a" )
			)
			( pin "C3D15.2"
				( objectStatus "@baseboard_fab2_lib.baseboard_fab2(sch_1):page76_i174:b" )
			)
			( pin "C3D24.1"
				( objectStatus "@baseboard_fab2_lib.baseboard_fab2(sch_1):page76_i175:a" )
			)
			( pin "C3D24.2"
				( objectStatus "@baseboard_fab2_lib.baseboard_fab2(sch_1):page76_i175:b" )
			)
			( pin "C3D16.1"
				( objectStatus "@baseboard_fab2_lib.baseboard_fab2(sch_1):page76_i176:a" )
			)
			( pin "C3D16.2"
				( objectStatus "@baseboard_fab2_lib.baseboard_fab2(sch_1):page76_i176:b" )
			)
			( pin "C7P12.1"
				( objectStatus "@baseboard_fab2_lib.baseboard_fab2(sch_1):page76_i179:a" )
			)
			( pin "C7P12.2"
				( objectStatus "@baseboard_fab2_lib.baseboard_fab2(sch_1):page76_i179:b" )
			)
			( pin "C7P14.1"
				( objectStatus "@baseboard_fab2_lib.baseboard_fab2(sch_1):page76_i261:a" )
			)
			( pin "C7P14.2"
				( objectStatus "@baseboard_fab2_lib.baseboard_fab2(sch_1):page76_i261:b" )
			)
			( pin "C8P23.1"
				( objectStatus "@baseboard_fab2_lib.baseboard_fab2(sch_1):page76_i260:a" )
			)
			( pin "C8P23.2"
				( objectStatus "@baseboard_fab2_lib.baseboard_fab2(sch_1):page76_i260:b" )
			)
			( pin "C8P22.1"
				( objectStatus "@baseboard_fab2_lib.baseboard_fab2(sch_1):page76_i264:a" )
			)
			( pin "C8P22.2"
				( objectStatus "@baseboard_fab2_lib.baseboard_fab2(sch_1):page76_i264:b" )
			)
			( pin "C7P6.1"
				( objectStatus "@baseboard_fab2_lib.baseboard_fab2(sch_1):page76_i268:a" )
			)
			( pin "C7P6.2"
				( objectStatus "@baseboard_fab2_lib.baseboard_fab2(sch_1):page76_i268:b" )
			)
			( pin "C3D10.1"
				( objectStatus "@baseboard_fab2_lib.baseboard_fab2(sch_1):page76_i196:a" )
			)
			( pin "C3D10.2"
				( objectStatus "@baseboard_fab2_lib.baseboard_fab2(sch_1):page76_i196:b" )
			)
			( pin "C2D18.1"
				( objectStatus "@baseboard_fab2_lib.baseboard_fab2(sch_1):page76_i197:a" )
			)
			( pin "C2D18.2"
				( objectStatus "@baseboard_fab2_lib.baseboard_fab2(sch_1):page76_i197:b" )
			)
			( pin "C2D28.1"
				( objectStatus "@baseboard_fab2_lib.baseboard_fab2(sch_1):page76_i198:a" )
			)
			( pin "C2D28.2"
				( objectStatus "@baseboard_fab2_lib.baseboard_fab2(sch_1):page76_i198:b" )
			)
			( pin "C2D29.1"
				( objectStatus "@baseboard_fab2_lib.baseboard_fab2(sch_1):page76_i199:a" )
			)
			( pin "C2D29.2"
				( objectStatus "@baseboard_fab2_lib.baseboard_fab2(sch_1):page76_i199:b" )
			)
			( pin "C8W3.1"
				( objectStatus "@baseboard_fab2_lib.baseboard_fab2(sch_1):page42_i211:a" )
			)
			( pin "C8W3.2"
				( objectStatus "@baseboard_fab2_lib.baseboard_fab2(sch_1):page42_i211:b" )
			)
			( pin "C5U1.1"
				( objectStatus "@baseboard_fab2_lib.baseboard_fab2(sch_1):page217_i316:a" )
			)
			( pin "C5U1.2"
				( objectStatus "@baseboard_fab2_lib.baseboard_fab2(sch_1):page217_i316:b" )
			)
			( pin "C2D46.1"
				( objectStatus "@baseboard_fab2_lib.baseboard_fab2(sch_1):page225_i264:a" )
			)
			( pin "C2D46.2"
				( objectStatus "@baseboard_fab2_lib.baseboard_fab2(sch_1):page225_i264:b" )
			)
			( pin "C2D47.1"
				( objectStatus "@baseboard_fab2_lib.baseboard_fab2(sch_1):page225_i263:a" )
			)
			( pin "C2D47.2"
				( objectStatus "@baseboard_fab2_lib.baseboard_fab2(sch_1):page225_i263:b" )
			)
			( pin "C3D25.1"
				( objectStatus "@baseboard_fab2_lib.baseboard_fab2(sch_1):page225_i262:a" )
			)
			( pin "C3D25.2"
				( objectStatus "@baseboard_fab2_lib.baseboard_fab2(sch_1):page225_i262:b" )
			)
			( pin "C7P16.1"
				( objectStatus "@baseboard_fab2_lib.baseboard_fab2(sch_1):page76_i206:a" )
			)
			( pin "C7P16.2"
				( objectStatus "@baseboard_fab2_lib.baseboard_fab2(sch_1):page76_i206:b" )
			)
			( pin "C3D20.1"
				( objectStatus "@baseboard_fab2_lib.baseboard_fab2(sch_1):page76_i207:a" )
			)
			( pin "C3D20.2"
				( objectStatus "@baseboard_fab2_lib.baseboard_fab2(sch_1):page76_i207:b" )
			)
			( pin "C3D19.1"
				( objectStatus "@baseboard_fab2_lib.baseboard_fab2(sch_1):page76_i208:a" )
			)
			( pin "C3D19.2"
				( objectStatus "@baseboard_fab2_lib.baseboard_fab2(sch_1):page76_i208:b" )
			)
			( pin "C7P19.1"
				( objectStatus "@baseboard_fab2_lib.baseboard_fab2(sch_1):page76_i215:a" )
			)
			( pin "C7P19.2"
				( objectStatus "@baseboard_fab2_lib.baseboard_fab2(sch_1):page76_i215:b" )
			)
			( pin "C8P24.1"
				( objectStatus "@baseboard_fab2_lib.baseboard_fab2(sch_1):page76_i217:a" )
			)
			( pin "C8P24.2"
				( objectStatus "@baseboard_fab2_lib.baseboard_fab2(sch_1):page76_i217:b" )
			)
			( pin "J1G1.283"
				( objectStatus "@baseboard_fab2_lib.baseboard_fab2(sch_1):page77_i43:vss(0)" )
			)
			( pin "J1G1.281"
				( objectStatus "@baseboard_fab2_lib.baseboard_fab2(sch_1):page77_i43:vss(1)" )
			)
			( pin "J1G1.279"
				( objectStatus "@baseboard_fab2_lib.baseboard_fab2(sch_1):page77_i43:vss(2)" )
			)
			( pin "J1G1.276"
				( objectStatus "@baseboard_fab2_lib.baseboard_fab2(sch_1):page77_i43:vss(3)" )
			)
			( pin "J1G1.274"
				( objectStatus "@baseboard_fab2_lib.baseboard_fab2(sch_1):page77_i43:vss(4)" )
			)
			( pin "J1G1.272"
				( objectStatus "@baseboard_fab2_lib.baseboard_fab2(sch_1):page77_i43:vss(5)" )
			)
			( pin "J1G1.270"
				( objectStatus "@baseboard_fab2_lib.baseboard_fab2(sch_1):page77_i43:vss(6)" )
			)
			( pin "J1G1.268"
				( objectStatus "@baseboard_fab2_lib.baseboard_fab2(sch_1):page77_i43:vss(7)" )
			)
			( pin "J1G1.265"
				( objectStatus "@baseboard_fab2_lib.baseboard_fab2(sch_1):page77_i43:vss(8)" )
			)
			( pin "J1G1.263"
				( objectStatus "@baseboard_fab2_lib.baseboard_fab2(sch_1):page77_i43:vss(9)" )
			)
			( pin "J1G1.261"
				( objectStatus "@baseboard_fab2_lib.baseboard_fab2(sch_1):page77_i43:vss(10)" )
			)
			( pin "J1G1.259"
				( objectStatus "@baseboard_fab2_lib.baseboard_fab2(sch_1):page77_i43:vss(11)" )
			)
			( pin "J1G1.257"
				( objectStatus "@baseboard_fab2_lib.baseboard_fab2(sch_1):page77_i43:vss(12)" )
			)
			( pin "J1G1.254"
				( objectStatus "@baseboard_fab2_lib.baseboard_fab2(sch_1):page77_i43:vss(13)" )
			)
			( pin "J1G1.252"
				( objectStatus "@baseboard_fab2_lib.baseboard_fab2(sch_1):page77_i43:vss(14)" )
			)
			( pin "J1G1.250"
				( objectStatus "@baseboard_fab2_lib.baseboard_fab2(sch_1):page77_i43:vss(15)" )
			)
			( pin "J1G1.248"
				( objectStatus "@baseboard_fab2_lib.baseboard_fab2(sch_1):page77_i43:vss(16)" )
			)
			( pin "J1G1.246"
				( objectStatus "@baseboard_fab2_lib.baseboard_fab2(sch_1):page77_i43:vss(17)" )
			)
			( pin "J1G1.243"
				( objectStatus "@baseboard_fab2_lib.baseboard_fab2(sch_1):page77_i43:vss(18)" )
			)
			( pin "J1G1.241"
				( objectStatus "@baseboard_fab2_lib.baseboard_fab2(sch_1):page77_i43:vss(19)" )
			)
			( pin "J1G1.239"
				( objectStatus "@baseboard_fab2_lib.baseboard_fab2(sch_1):page77_i43:vss(20)" )
			)
			( pin "J1G1.202"
				( objectStatus "@baseboard_fab2_lib.baseboard_fab2(sch_1):page77_i43:vss(21)" )
			)
			( pin "J1G1.200"
				( objectStatus "@baseboard_fab2_lib.baseboard_fab2(sch_1):page77_i43:vss(22)" )
			)
			( pin "J1G1.198"
				( objectStatus "@baseboard_fab2_lib.baseboard_fab2(sch_1):page77_i43:vss(23)" )
			)
			( pin "J1G1.195"
				( objectStatus "@baseboard_fab2_lib.baseboard_fab2(sch_1):page77_i43:vss(24)" )
			)
			( pin "J1G1.193"
				( objectStatus "@baseboard_fab2_lib.baseboard_fab2(sch_1):page77_i43:vss(25)" )
			)
			( pin "J1G1.191"
				( objectStatus "@baseboard_fab2_lib.baseboard_fab2(sch_1):page77_i43:vss(26)" )
			)
			( pin "J1G1.189"
				( objectStatus "@baseboard_fab2_lib.baseboard_fab2(sch_1):page77_i43:vss(27)" )
			)
			( pin "J1G1.187"
				( objectStatus "@baseboard_fab2_lib.baseboard_fab2(sch_1):page77_i43:vss(28)" )
			)
			( pin "J1G1.184"
				( objectStatus "@baseboard_fab2_lib.baseboard_fab2(sch_1):page77_i43:vss(29)" )
			)
			( pin "J1G1.182"
				( objectStatus "@baseboard_fab2_lib.baseboard_fab2(sch_1):page77_i43:vss(30)" )
			)
			( pin "J1G1.180"
				( objectStatus "@baseboard_fab2_lib.baseboard_fab2(sch_1):page77_i43:vss(31)" )
			)
			( pin "J1G1.178"
				( objectStatus "@baseboard_fab2_lib.baseboard_fab2(sch_1):page77_i43:vss(32)" )
			)
			( pin "J1G1.176"
				( objectStatus "@baseboard_fab2_lib.baseboard_fab2(sch_1):page77_i43:vss(33)" )
			)
			( pin "J1G1.173"
				( objectStatus "@baseboard_fab2_lib.baseboard_fab2(sch_1):page77_i43:vss(34)" )
			)
			( pin "J1G1.171"
				( objectStatus "@baseboard_fab2_lib.baseboard_fab2(sch_1):page77_i43:vss(35)" )
			)
			( pin "J1G1.169"
				( objectStatus "@baseboard_fab2_lib.baseboard_fab2(sch_1):page77_i43:vss(36)" )
			)
			( pin "J1G1.167"
				( objectStatus "@baseboard_fab2_lib.baseboard_fab2(sch_1):page77_i43:vss(37)" )
			)
			( pin "J1G1.165"
				( objectStatus "@baseboard_fab2_lib.baseboard_fab2(sch_1):page77_i43:vss(38)" )
			)
			( pin "J1G1.162"
				( objectStatus "@baseboard_fab2_lib.baseboard_fab2(sch_1):page77_i43:vss(39)" )
			)
			( pin "J1G1.160"
				( objectStatus "@baseboard_fab2_lib.baseboard_fab2(sch_1):page77_i43:vss(40)" )
			)
			( pin "J1G1.158"
				( objectStatus "@baseboard_fab2_lib.baseboard_fab2(sch_1):page77_i43:vss(41)" )
			)
			( pin "J1G1.156"
				( objectStatus "@baseboard_fab2_lib.baseboard_fab2(sch_1):page77_i43:vss(42)" )
			)
			( pin "J1G1.154"
				( objectStatus "@baseboard_fab2_lib.baseboard_fab2(sch_1):page77_i43:vss(43)" )
			)
			( pin "J1G1.151"
				( objectStatus "@baseboard_fab2_lib.baseboard_fab2(sch_1):page77_i43:vss(44)" )
			)
			( pin "J1G1.149"
				( objectStatus "@baseboard_fab2_lib.baseboard_fab2(sch_1):page77_i43:vss(45)" )
			)
			( pin "J1G1.147"
				( objectStatus "@baseboard_fab2_lib.baseboard_fab2(sch_1):page77_i43:vss(46)" )
			)
			( pin "J1G1.138"
				( objectStatus "@baseboard_fab2_lib.baseboard_fab2(sch_1):page77_i43:vss(47)" )
			)
			( pin "J1G1.136"
				( objectStatus "@baseboard_fab2_lib.baseboard_fab2(sch_1):page77_i43:vss(48)" )
			)
			( pin "J1G1.134"
				( objectStatus "@baseboard_fab2_lib.baseboard_fab2(sch_1):page77_i43:vss(49)" )
			)
			( pin "J1G1.131"
				( objectStatus "@baseboard_fab2_lib.baseboard_fab2(sch_1):page77_i43:vss(50)" )
			)
			( pin "J1G1.129"
				( objectStatus "@baseboard_fab2_lib.baseboard_fab2(sch_1):page77_i43:vss(51)" )
			)
			( pin "J1G1.127"
				( objectStatus "@baseboard_fab2_lib.baseboard_fab2(sch_1):page77_i43:vss(52)" )
			)
			( pin "J1G1.125"
				( objectStatus "@baseboard_fab2_lib.baseboard_fab2(sch_1):page77_i43:vss(53)" )
			)
			( pin "J1G1.123"
				( objectStatus "@baseboard_fab2_lib.baseboard_fab2(sch_1):page77_i43:vss(54)" )
			)
			( pin "J1G1.120"
				( objectStatus "@baseboard_fab2_lib.baseboard_fab2(sch_1):page77_i43:vss(55)" )
			)
			( pin "J1G1.118"
				( objectStatus "@baseboard_fab2_lib.baseboard_fab2(sch_1):page77_i43:vss(56)" )
			)
			( pin "J1G1.116"
				( objectStatus "@baseboard_fab2_lib.baseboard_fab2(sch_1):page77_i43:vss(57)" )
			)
			( pin "J1G1.114"
				( objectStatus "@baseboard_fab2_lib.baseboard_fab2(sch_1):page77_i43:vss(58)" )
			)
			( pin "J1G1.112"
				( objectStatus "@baseboard_fab2_lib.baseboard_fab2(sch_1):page77_i43:vss(59)" )
			)
			( pin "J1G1.109"
				( objectStatus "@baseboard_fab2_lib.baseboard_fab2(sch_1):page77_i43:vss(60)" )
			)
			( pin "J1G1.107"
				( objectStatus "@baseboard_fab2_lib.baseboard_fab2(sch_1):page77_i43:vss(61)" )
			)
			( pin "J1G1.105"
				( objectStatus "@baseboard_fab2_lib.baseboard_fab2(sch_1):page77_i43:vss(62)" )
			)
			( pin "J1G1.103"
				( objectStatus "@baseboard_fab2_lib.baseboard_fab2(sch_1):page77_i43:vss(63)" )
			)
			( pin "J1G1.101"
				( objectStatus "@baseboard_fab2_lib.baseboard_fab2(sch_1):page77_i43:vss(64)" )
			)
			( pin "J1G1.98"
				( objectStatus "@baseboard_fab2_lib.baseboard_fab2(sch_1):page77_i43:vss(65)" )
			)
			( pin "J1G1.96"
				( objectStatus "@baseboard_fab2_lib.baseboard_fab2(sch_1):page77_i43:vss(66)" )
			)
			( pin "J1G1.94"
				( objectStatus "@baseboard_fab2_lib.baseboard_fab2(sch_1):page77_i43:vss(67)" )
			)
			( pin "J1G1.57"
				( objectStatus "@baseboard_fab2_lib.baseboard_fab2(sch_1):page77_i43:vss(68)" )
			)
			( pin "J1G1.55"
				( objectStatus "@baseboard_fab2_lib.baseboard_fab2(sch_1):page77_i43:vss(69)" )
			)
			( pin "J1G1.53"
				( objectStatus "@baseboard_fab2_lib.baseboard_fab2(sch_1):page77_i43:vss(70)" )
			)
			( pin "J1G1.50"
				( objectStatus "@baseboard_fab2_lib.baseboard_fab2(sch_1):page77_i43:vss(71)" )
			)
			( pin "J1G1.48"
				( objectStatus "@baseboard_fab2_lib.baseboard_fab2(sch_1):page77_i43:vss(72)" )
			)
			( pin "J1G1.46"
				( objectStatus "@baseboard_fab2_lib.baseboard_fab2(sch_1):page77_i43:vss(73)" )
			)
			( pin "J1G1.44"
				( objectStatus "@baseboard_fab2_lib.baseboard_fab2(sch_1):page77_i43:vss(74)" )
			)
			( pin "J1G1.42"
				( objectStatus "@baseboard_fab2_lib.baseboard_fab2(sch_1):page77_i43:vss(75)" )
			)
			( pin "J1G1.39"
				( objectStatus "@baseboard_fab2_lib.baseboard_fab2(sch_1):page77_i43:vss(76)" )
			)
			( pin "J1G1.37"
				( objectStatus "@baseboard_fab2_lib.baseboard_fab2(sch_1):page77_i43:vss(77)" )
			)
			( pin "J1G1.35"
				( objectStatus "@baseboard_fab2_lib.baseboard_fab2(sch_1):page77_i43:vss(78)" )
			)
			( pin "J1G1.33"
				( objectStatus "@baseboard_fab2_lib.baseboard_fab2(sch_1):page77_i43:vss(79)" )
			)
			( pin "J1G1.31"
				( objectStatus "@baseboard_fab2_lib.baseboard_fab2(sch_1):page77_i43:vss(80)" )
			)
			( pin "J1G1.28"
				( objectStatus "@baseboard_fab2_lib.baseboard_fab2(sch_1):page77_i43:vss(81)" )
			)
			( pin "J1G1.26"
				( objectStatus "@baseboard_fab2_lib.baseboard_fab2(sch_1):page77_i43:vss(82)" )
			)
			( pin "J1G1.24"
				( objectStatus "@baseboard_fab2_lib.baseboard_fab2(sch_1):page77_i43:vss(83)" )
			)
			( pin "J1G1.22"
				( objectStatus "@baseboard_fab2_lib.baseboard_fab2(sch_1):page77_i43:vss(84)" )
			)
			( pin "J1G1.20"
				( objectStatus "@baseboard_fab2_lib.baseboard_fab2(sch_1):page77_i43:vss(85)" )
			)
			( pin "J1G1.17"
				( objectStatus "@baseboard_fab2_lib.baseboard_fab2(sch_1):page77_i43:vss(86)" )
			)
			( pin "J1G1.15"
				( objectStatus "@baseboard_fab2_lib.baseboard_fab2(sch_1):page77_i43:vss(87)" )
			)
			( pin "J1G1.13"
				( objectStatus "@baseboard_fab2_lib.baseboard_fab2(sch_1):page77_i43:vss(88)" )
			)
			( pin "J1G1.11"
				( objectStatus "@baseboard_fab2_lib.baseboard_fab2(sch_1):page77_i43:vss(89)" )
			)
			( pin "J1G1.9"
				( objectStatus "@baseboard_fab2_lib.baseboard_fab2(sch_1):page77_i43:vss(90)" )
			)
			( pin "J1G1.6"
				( objectStatus "@baseboard_fab2_lib.baseboard_fab2(sch_1):page77_i43:vss(91)" )
			)
			( pin "J1G1.4"
				( objectStatus "@baseboard_fab2_lib.baseboard_fab2(sch_1):page77_i43:vss(92)" )
			)
			( pin "J1G1.2"
				( objectStatus "@baseboard_fab2_lib.baseboard_fab2(sch_1):page77_i43:vss(93)" )
			)
			( pin "J1G1.152"
				( objectStatus "@baseboard_fab2_lib.baseboard_fab2(sch_1):page77_i66:dqs0n" )
			)
			( pin "J1G1.153"
				( objectStatus "@baseboard_fab2_lib.baseboard_fab2(sch_1):page77_i66:dqs0p" )
			)
			( pin "J1G1.163"
				( objectStatus "@baseboard_fab2_lib.baseboard_fab2(sch_1):page77_i66:dqs1n" )
			)
			( pin "J1G1.164"
				( objectStatus "@baseboard_fab2_lib.baseboard_fab2(sch_1):page77_i66:dqs1p" )
			)
			( pin "J1G1.174"
				( objectStatus "@baseboard_fab2_lib.baseboard_fab2(sch_1):page77_i66:dqs2n" )
			)
			( pin "J1G1.175"
				( objectStatus "@baseboard_fab2_lib.baseboard_fab2(sch_1):page77_i66:dqs2p" )
			)
			( pin "J1G1.185"
				( objectStatus "@baseboard_fab2_lib.baseboard_fab2(sch_1):page77_i66:dqs3n" )
			)
			( pin "J1G1.186"
				( objectStatus "@baseboard_fab2_lib.baseboard_fab2(sch_1):page77_i66:dqs3p" )
			)
			( pin "J1G1.244"
				( objectStatus "@baseboard_fab2_lib.baseboard_fab2(sch_1):page77_i66:dqs4n" )
			)
			( pin "J1G1.245"
				( objectStatus "@baseboard_fab2_lib.baseboard_fab2(sch_1):page77_i66:dqs4p" )
			)
			( pin "J1G1.255"
				( objectStatus "@baseboard_fab2_lib.baseboard_fab2(sch_1):page77_i66:dqs5n" )
			)
			( pin "J1G1.256"
				( objectStatus "@baseboard_fab2_lib.baseboard_fab2(sch_1):page77_i66:dqs5p" )
			)
			( pin "J1G1.266"
				( objectStatus "@baseboard_fab2_lib.baseboard_fab2(sch_1):page77_i66:dqs6n" )
			)
			( pin "J1G1.267"
				( objectStatus "@baseboard_fab2_lib.baseboard_fab2(sch_1):page77_i66:dqs6p" )
			)
			( pin "J1G1.277"
				( objectStatus "@baseboard_fab2_lib.baseboard_fab2(sch_1):page77_i66:dqs7n" )
			)
			( pin "J1G1.278"
				( objectStatus "@baseboard_fab2_lib.baseboard_fab2(sch_1):page77_i66:dqs7p" )
			)
			( pin "J1G1.196"
				( objectStatus "@baseboard_fab2_lib.baseboard_fab2(sch_1):page77_i66:dqs8n" )
			)
			( pin "J1G1.197"
				( objectStatus "@baseboard_fab2_lib.baseboard_fab2(sch_1):page77_i66:dqs8p" )
			)
			( pin "J1G1.8"
				( objectStatus "@baseboard_fab2_lib.baseboard_fab2(sch_1):page77_i66:dqs9n" )
			)
			( pin "J1G1.7"
				( objectStatus "@baseboard_fab2_lib.baseboard_fab2(sch_1):page77_i66:dqs9p" )
			)
			( pin "J1G1.19"
				( objectStatus "@baseboard_fab2_lib.baseboard_fab2(sch_1):page77_i66:dqs10n" )
			)
			( pin "J1G1.18"
				( objectStatus "@baseboard_fab2_lib.baseboard_fab2(sch_1):page77_i66:dqs10p" )
			)
			( pin "J1G1.30"
				( objectStatus "@baseboard_fab2_lib.baseboard_fab2(sch_1):page77_i66:dqs11n" )
			)
			( pin "J1G1.29"
				( objectStatus "@baseboard_fab2_lib.baseboard_fab2(sch_1):page77_i66:dqs11p" )
			)
			( pin "J1G1.41"
				( objectStatus "@baseboard_fab2_lib.baseboard_fab2(sch_1):page77_i66:dqs12n" )
			)
			( pin "J1G1.40"
				( objectStatus "@baseboard_fab2_lib.baseboard_fab2(sch_1):page77_i66:dqs12p" )
			)
			( pin "J1G1.100"
				( objectStatus "@baseboard_fab2_lib.baseboard_fab2(sch_1):page77_i66:dqs13n" )
			)
			( pin "J1G1.99"
				( objectStatus "@baseboard_fab2_lib.baseboard_fab2(sch_1):page77_i66:dqs13p" )
			)
			( pin "J1G1.111"
				( objectStatus "@baseboard_fab2_lib.baseboard_fab2(sch_1):page77_i66:dqs14n" )
			)
			( pin "J1G1.110"
				( objectStatus "@baseboard_fab2_lib.baseboard_fab2(sch_1):page77_i66:dqs14p" )
			)
			( pin "J1G1.122"
				( objectStatus "@baseboard_fab2_lib.baseboard_fab2(sch_1):page77_i66:dqs15n" )
			)
			( pin "J1G1.121"
				( objectStatus "@baseboard_fab2_lib.baseboard_fab2(sch_1):page77_i66:dqs15p" )
			)
			( pin "J1G1.133"
				( objectStatus "@baseboard_fab2_lib.baseboard_fab2(sch_1):page77_i66:dqs16n" )
			)
			( pin "J1G1.132"
				( objectStatus "@baseboard_fab2_lib.baseboard_fab2(sch_1):page77_i66:dqs16p" )
			)
			( pin "J1G1.52"
				( objectStatus "@baseboard_fab2_lib.baseboard_fab2(sch_1):page77_i66:dqs17n" )
			)
			( pin "J1G1.51"
				( objectStatus "@baseboard_fab2_lib.baseboard_fab2(sch_1):page77_i66:dqs17p" )
			)
			( pin "J1G1.79"
				( objectStatus "@baseboard_fab2_lib.baseboard_fab2(sch_1):page77_i111:a0" )
			)
			( pin "J1G1.72"
				( objectStatus "@baseboard_fab2_lib.baseboard_fab2(sch_1):page77_i111:a1" )
			)
			( pin "J1G1.216"
				( objectStatus "@baseboard_fab2_lib.baseboard_fab2(sch_1):page77_i111:a2" )
			)
			( pin "J1G1.71"
				( objectStatus "@baseboard_fab2_lib.baseboard_fab2(sch_1):page77_i111:a3" )
			)
			( pin "J1G1.214"
				( objectStatus "@baseboard_fab2_lib.baseboard_fab2(sch_1):page77_i111:a4" )
			)
			( pin "J1G1.213"
				( objectStatus "@baseboard_fab2_lib.baseboard_fab2(sch_1):page77_i111:a5" )
			)
			( pin "J1G1.69"
				( objectStatus "@baseboard_fab2_lib.baseboard_fab2(sch_1):page77_i111:a6" )
			)
			( pin "J1G1.211"
				( objectStatus "@baseboard_fab2_lib.baseboard_fab2(sch_1):page77_i111:a7" )
			)
			( pin "J1G1.68"
				( objectStatus "@baseboard_fab2_lib.baseboard_fab2(sch_1):page77_i111:a8" )
			)
			( pin "J1G1.66"
				( objectStatus "@baseboard_fab2_lib.baseboard_fab2(sch_1):page77_i111:a9" )
			)
			( pin "J1G1.225"
				( objectStatus "@baseboard_fab2_lib.baseboard_fab2(sch_1):page77_i111:a10" )
			)
			( pin "J1G1.210"
				( objectStatus "@baseboard_fab2_lib.baseboard_fab2(sch_1):page77_i111:a11" )
			)
			( pin "J1G1.65"
				( objectStatus "@baseboard_fab2_lib.baseboard_fab2(sch_1):page77_i111:a12" )
			)
			( pin "J1G1.232"
				( objectStatus "@baseboard_fab2_lib.baseboard_fab2(sch_1):page77_i111:a13" )
			)
			( pin "J1G1.228"
				( objectStatus "@baseboard_fab2_lib.baseboard_fab2(sch_1):page77_i111:a14_we_n" )
			)
			( pin "J1G1.86"
				( objectStatus "@baseboard_fab2_lib.baseboard_fab2(sch_1):page77_i111:a15_cas_n" )
			)
			( pin "J1G1.82"
				( objectStatus "@baseboard_fab2_lib.baseboard_fab2(sch_1):page77_i111:a16_ras_n" )
			)
			( pin "J1G1.234"
				( objectStatus "@baseboard_fab2_lib.baseboard_fab2(sch_1):page77_i111:a17" )
			)
			( pin "J1G1.62"
				( objectStatus "@baseboard_fab2_lib.baseboard_fab2(sch_1):page77_i111:act_n" )
			)
			( pin "J1G1.208"
				( objectStatus "@baseboard_fab2_lib.baseboard_fab2(sch_1):page77_i111:alert_n" )
			)
			( pin "J1G1.81"
				( objectStatus "@baseboard_fab2_lib.baseboard_fab2(sch_1):page77_i111:ba(0)" )
			)
			( pin "J1G1.224"
				( objectStatus "@baseboard_fab2_lib.baseboard_fab2(sch_1):page77_i111:ba(1)" )
			)
			( pin "J1G1.63"
				( objectStatus "@baseboard_fab2_lib.baseboard_fab2(sch_1):page77_i111:bg(0)" )
			)
			( pin "J1G1.207"
				( objectStatus "@baseboard_fab2_lib.baseboard_fab2(sch_1):page77_i111:bg(1)" )
			)
			( pin "J1G1.235"
				( objectStatus "@baseboard_fab2_lib.baseboard_fab2(sch_1):page77_i111:c(2)" )
			)
			( pin "J1G1.49"
				( objectStatus "@baseboard_fab2_lib.baseboard_fab2(sch_1):page77_i111:cb(0)" )
			)
			( pin "J1G1.194"
				( objectStatus "@baseboard_fab2_lib.baseboard_fab2(sch_1):page77_i111:cb(1)" )
			)
			( pin "J1G1.56"
				( objectStatus "@baseboard_fab2_lib.baseboard_fab2(sch_1):page77_i111:cb(2)" )
			)
			( pin "J1G1.201"
				( objectStatus "@baseboard_fab2_lib.baseboard_fab2(sch_1):page77_i111:cb(3)" )
			)
			( pin "J1G1.47"
				( objectStatus "@baseboard_fab2_lib.baseboard_fab2(sch_1):page77_i111:cb(4)" )
			)
			( pin "J1G1.192"
				( objectStatus "@baseboard_fab2_lib.baseboard_fab2(sch_1):page77_i111:cb(5)" )
			)
			( pin "J1G1.54"
				( objectStatus "@baseboard_fab2_lib.baseboard_fab2(sch_1):page77_i111:cb(6)" )
			)
			( pin "J1G1.199"
				( objectStatus "@baseboard_fab2_lib.baseboard_fab2(sch_1):page77_i111:cb(7)" )
			)
			( pin "J1G1.75"
				( objectStatus "@baseboard_fab2_lib.baseboard_fab2(sch_1):page77_i111:ck0n" )
			)
			( pin "J1G1.74"
				( objectStatus "@baseboard_fab2_lib.baseboard_fab2(sch_1):page77_i111:ck0p" )
			)
			( pin "J1G1.219"
				( objectStatus "@baseboard_fab2_lib.baseboard_fab2(sch_1):page77_i111:ck1n" )
			)
			( pin "J1G1.218"
				( objectStatus "@baseboard_fab2_lib.baseboard_fab2(sch_1):page77_i111:ck1p" )
			)
			( pin "J1G1.60"
				( objectStatus "@baseboard_fab2_lib.baseboard_fab2(sch_1):page77_i111:cke(0)" )
			)
			( pin "J1G1.203"
				( objectStatus "@baseboard_fab2_lib.baseboard_fab2(sch_1):page77_i111:cke(1)" )
			)
			( pin "J1G1.5"
				( objectStatus "@baseboard_fab2_lib.baseboard_fab2(sch_1):page77_i111:dq(0)" )
			)
			( pin "J1G1.150"
				( objectStatus "@baseboard_fab2_lib.baseboard_fab2(sch_1):page77_i111:dq(1)" )
			)
			( pin "J1G1.12"
				( objectStatus "@baseboard_fab2_lib.baseboard_fab2(sch_1):page77_i111:dq(2)" )
			)
			( pin "J1G1.157"
				( objectStatus "@baseboard_fab2_lib.baseboard_fab2(sch_1):page77_i111:dq(3)" )
			)
			( pin "J1G1.3"
				( objectStatus "@baseboard_fab2_lib.baseboard_fab2(sch_1):page77_i111:dq(4)" )
			)
			( pin "J1G1.148"
				( objectStatus "@baseboard_fab2_lib.baseboard_fab2(sch_1):page77_i111:dq(5)" )
			)
			( pin "J1G1.10"
				( objectStatus "@baseboard_fab2_lib.baseboard_fab2(sch_1):page77_i111:dq(6)" )
			)
			( pin "J1G1.155"
				( objectStatus "@baseboard_fab2_lib.baseboard_fab2(sch_1):page77_i111:dq(7)" )
			)
			( pin "J1G1.16"
				( objectStatus "@baseboard_fab2_lib.baseboard_fab2(sch_1):page77_i111:dq(8)" )
			)
			( pin "J1G1.161"
				( objectStatus "@baseboard_fab2_lib.baseboard_fab2(sch_1):page77_i111:dq(9)" )
			)
			( pin "J1G1.23"
				( objectStatus "@baseboard_fab2_lib.baseboard_fab2(sch_1):page77_i111:dq(10)" )
			)
			( pin "J1G1.168"
				( objectStatus "@baseboard_fab2_lib.baseboard_fab2(sch_1):page77_i111:dq(11)" )
			)
			( pin "J1G1.14"
				( objectStatus "@baseboard_fab2_lib.baseboard_fab2(sch_1):page77_i111:dq(12)" )
			)
			( pin "J1G1.159"
				( objectStatus "@baseboard_fab2_lib.baseboard_fab2(sch_1):page77_i111:dq(13)" )
			)
			( pin "J1G1.21"
				( objectStatus "@baseboard_fab2_lib.baseboard_fab2(sch_1):page77_i111:dq(14)" )
			)
			( pin "J1G1.166"
				( objectStatus "@baseboard_fab2_lib.baseboard_fab2(sch_1):page77_i111:dq(15)" )
			)
			( pin "J1G1.27"
				( objectStatus "@baseboard_fab2_lib.baseboard_fab2(sch_1):page77_i111:dq(16)" )
			)
			( pin "J1G1.172"
				( objectStatus "@baseboard_fab2_lib.baseboard_fab2(sch_1):page77_i111:dq(17)" )
			)
			( pin "J1G1.34"
				( objectStatus "@baseboard_fab2_lib.baseboard_fab2(sch_1):page77_i111:dq(18)" )
			)
			( pin "J1G1.179"
				( objectStatus "@baseboard_fab2_lib.baseboard_fab2(sch_1):page77_i111:dq(19)" )
			)
			( pin "J1G1.25"
				( objectStatus "@baseboard_fab2_lib.baseboard_fab2(sch_1):page77_i111:dq(20)" )
			)
			( pin "J1G1.170"
				( objectStatus "@baseboard_fab2_lib.baseboard_fab2(sch_1):page77_i111:dq(21)" )
			)
			( pin "J1G1.32"
				( objectStatus "@baseboard_fab2_lib.baseboard_fab2(sch_1):page77_i111:dq(22)" )
			)
			( pin "J1G1.177"
				( objectStatus "@baseboard_fab2_lib.baseboard_fab2(sch_1):page77_i111:dq(23)" )
			)
			( pin "J1G1.38"
				( objectStatus "@baseboard_fab2_lib.baseboard_fab2(sch_1):page77_i111:dq(24)" )
			)
			( pin "J1G1.183"
				( objectStatus "@baseboard_fab2_lib.baseboard_fab2(sch_1):page77_i111:dq(25)" )
			)
			( pin "J1G1.45"
				( objectStatus "@baseboard_fab2_lib.baseboard_fab2(sch_1):page77_i111:dq(26)" )
			)
			( pin "J1G1.190"
				( objectStatus "@baseboard_fab2_lib.baseboard_fab2(sch_1):page77_i111:dq(27)" )
			)
			( pin "J1G1.36"
				( objectStatus "@baseboard_fab2_lib.baseboard_fab2(sch_1):page77_i111:dq(28)" )
			)
			( pin "J1G1.181"
				( objectStatus "@baseboard_fab2_lib.baseboard_fab2(sch_1):page77_i111:dq(29)" )
			)
			( pin "J1G1.43"
				( objectStatus "@baseboard_fab2_lib.baseboard_fab2(sch_1):page77_i111:dq(30)" )
			)
			( pin "J1G1.188"
				( objectStatus "@baseboard_fab2_lib.baseboard_fab2(sch_1):page77_i111:dq(31)" )
			)
			( pin "J1G1.97"
				( objectStatus "@baseboard_fab2_lib.baseboard_fab2(sch_1):page77_i111:dq(32)" )
			)
			( pin "J1G1.242"
				( objectStatus "@baseboard_fab2_lib.baseboard_fab2(sch_1):page77_i111:dq(33)" )
			)
			( pin "J1G1.104"
				( objectStatus "@baseboard_fab2_lib.baseboard_fab2(sch_1):page77_i111:dq(34)" )
			)
			( pin "J1G1.249"
				( objectStatus "@baseboard_fab2_lib.baseboard_fab2(sch_1):page77_i111:dq(35)" )
			)
			( pin "J1G1.95"
				( objectStatus "@baseboard_fab2_lib.baseboard_fab2(sch_1):page77_i111:dq(36)" )
			)
			( pin "J1G1.240"
				( objectStatus "@baseboard_fab2_lib.baseboard_fab2(sch_1):page77_i111:dq(37)" )
			)
			( pin "J1G1.102"
				( objectStatus "@baseboard_fab2_lib.baseboard_fab2(sch_1):page77_i111:dq(38)" )
			)
			( pin "J1G1.247"
				( objectStatus "@baseboard_fab2_lib.baseboard_fab2(sch_1):page77_i111:dq(39)" )
			)
			( pin "J1G1.108"
				( objectStatus "@baseboard_fab2_lib.baseboard_fab2(sch_1):page77_i111:dq(40)" )
			)
			( pin "J1G1.253"
				( objectStatus "@baseboard_fab2_lib.baseboard_fab2(sch_1):page77_i111:dq(41)" )
			)
			( pin "J1G1.115"
				( objectStatus "@baseboard_fab2_lib.baseboard_fab2(sch_1):page77_i111:dq(42)" )
			)
			( pin "J1G1.260"
				( objectStatus "@baseboard_fab2_lib.baseboard_fab2(sch_1):page77_i111:dq(43)" )
			)
			( pin "J1G1.106"
				( objectStatus "@baseboard_fab2_lib.baseboard_fab2(sch_1):page77_i111:dq(44)" )
			)
			( pin "J1G1.251"
				( objectStatus "@baseboard_fab2_lib.baseboard_fab2(sch_1):page77_i111:dq(45)" )
			)
			( pin "J1G1.113"
				( objectStatus "@baseboard_fab2_lib.baseboard_fab2(sch_1):page77_i111:dq(46)" )
			)
			( pin "J1G1.258"
				( objectStatus "@baseboard_fab2_lib.baseboard_fab2(sch_1):page77_i111:dq(47)" )
			)
			( pin "J1G1.119"
				( objectStatus "@baseboard_fab2_lib.baseboard_fab2(sch_1):page77_i111:dq(48)" )
			)
			( pin "J1G1.264"
				( objectStatus "@baseboard_fab2_lib.baseboard_fab2(sch_1):page77_i111:dq(49)" )
			)
			( pin "J1G1.126"
				( objectStatus "@baseboard_fab2_lib.baseboard_fab2(sch_1):page77_i111:dq(50)" )
			)
			( pin "J1G1.271"
				( objectStatus "@baseboard_fab2_lib.baseboard_fab2(sch_1):page77_i111:dq(51)" )
			)
			( pin "J1G1.117"
				( objectStatus "@baseboard_fab2_lib.baseboard_fab2(sch_1):page77_i111:dq(52)" )
			)
			( pin "J1G1.262"
				( objectStatus "@baseboard_fab2_lib.baseboard_fab2(sch_1):page77_i111:dq(53)" )
			)
			( pin "J1G1.124"
				( objectStatus "@baseboard_fab2_lib.baseboard_fab2(sch_1):page77_i111:dq(54)" )
			)
			( pin "J1G1.269"
				( objectStatus "@baseboard_fab2_lib.baseboard_fab2(sch_1):page77_i111:dq(55)" )
			)
			( pin "J1G1.130"
				( objectStatus "@baseboard_fab2_lib.baseboard_fab2(sch_1):page77_i111:dq(56)" )
			)
			( pin "J1G1.275"
				( objectStatus "@baseboard_fab2_lib.baseboard_fab2(sch_1):page77_i111:dq(57)" )
			)
			( pin "J1G1.137"
				( objectStatus "@baseboard_fab2_lib.baseboard_fab2(sch_1):page77_i111:dq(58)" )
			)
			( pin "J1G1.282"
				( objectStatus "@baseboard_fab2_lib.baseboard_fab2(sch_1):page77_i111:dq(59)" )
			)
			( pin "J1G1.128"
				( objectStatus "@baseboard_fab2_lib.baseboard_fab2(sch_1):page77_i111:dq(60)" )
			)
			( pin "J1G1.273"
				( objectStatus "@baseboard_fab2_lib.baseboard_fab2(sch_1):page77_i111:dq(61)" )
			)
			( pin "J1G1.135"
				( objectStatus "@baseboard_fab2_lib.baseboard_fab2(sch_1):page77_i111:dq(62)" )
			)
			( pin "J1G1.280"
				( objectStatus "@baseboard_fab2_lib.baseboard_fab2(sch_1):page77_i111:dq(63)" )
			)
			( pin "J1G1.78"
				( objectStatus "@baseboard_fab2_lib.baseboard_fab2(sch_1):page77_i111:event_n" )
			)
			( pin "J1G1.87"
				( objectStatus "@baseboard_fab2_lib.baseboard_fab2(sch_1):page77_i111:odt(0)" )
			)
			( pin "J1G1.91"
				( objectStatus "@baseboard_fab2_lib.baseboard_fab2(sch_1):page77_i111:odt(1)" )
			)
			( pin "J1G1.222"
				( objectStatus "@baseboard_fab2_lib.baseboard_fab2(sch_1):page77_i111:par" )
			)
			( pin "J1G1.58"
				( objectStatus "@baseboard_fab2_lib.baseboard_fab2(sch_1):page77_i111:reset_n" )
			)
			( pin "J1G1.205"
				( objectStatus "@baseboard_fab2_lib.baseboard_fab2(sch_1):page77_i111:rfu(0)" )
			)
			( pin "J1G1.227"
				( objectStatus "@baseboard_fab2_lib.baseboard_fab2(sch_1):page77_i111:rfu(1)" )
			)
			( pin "J1G1.144"
				( objectStatus "@baseboard_fab2_lib.baseboard_fab2(sch_1):page77_i111:rfu(2)" )
			)
			( pin "J1G1.84"
				( objectStatus "@baseboard_fab2_lib.baseboard_fab2(sch_1):page77_i111:s0_n" )
			)
			( pin "J1G1.89"
				( objectStatus "@baseboard_fab2_lib.baseboard_fab2(sch_1):page77_i111:s1_n" )
			)
			( pin "J1G1.93"
				( objectStatus "@baseboard_fab2_lib.baseboard_fab2(sch_1):page77_i111:s2_n_c(0)" )
			)
			( pin "J1G1.237"
				( objectStatus "@baseboard_fab2_lib.baseboard_fab2(sch_1):page77_i111:s3_n_c(1)" )
			)
			( pin "J1G1.139"
				( objectStatus "@baseboard_fab2_lib.baseboard_fab2(sch_1):page77_i111:sa(0)" )
			)
			( pin "J1G1.140"
				( objectStatus "@baseboard_fab2_lib.baseboard_fab2(sch_1):page77_i111:sa(1)" )
			)
			( pin "J1G1.238"
				( objectStatus "@baseboard_fab2_lib.baseboard_fab2(sch_1):page77_i111:sa(2)" )
			)
			( pin "J1G1.230"
				( objectStatus "@baseboard_fab2_lib.baseboard_fab2(sch_1):page77_i111:save_n_nc" )
			)
			( pin "J1G1.141"
				( objectStatus "@baseboard_fab2_lib.baseboard_fab2(sch_1):page77_i111:scl" )
			)
			( pin "J1G1.285"
				( objectStatus "@baseboard_fab2_lib.baseboard_fab2(sch_1):page77_i111:sda" )
			)
			( pin "J1G1.284"
				( objectStatus "@baseboard_fab2_lib.baseboard_fab2(sch_1):page77_i111:vddspd" )
			)
			( pin "J1G1.146"
				( objectStatus "@baseboard_fab2_lib.baseboard_fab2(sch_1):page77_i111:vrefca" )
			)
			( pin "J1G1.145"
				( objectStatus "@baseboard_fab2_lib.baseboard_fab2(sch_1):page77_i171:\12v\(0)" )
			)
			( pin "J1G1.1"
				( objectStatus "@baseboard_fab2_lib.baseboard_fab2(sch_1):page77_i171:\12v\(1)" )
			)
			( pin "J1G1.236"
				( objectStatus "@baseboard_fab2_lib.baseboard_fab2(sch_1):page77_i171:vdd(0)" )
			)
			( pin "J1G1.233"
				( objectStatus "@baseboard_fab2_lib.baseboard_fab2(sch_1):page77_i171:vdd(1)" )
			)
			( pin "J1G1.231"
				( objectStatus "@baseboard_fab2_lib.baseboard_fab2(sch_1):page77_i171:vdd(2)" )
			)
			( pin "J1G1.229"
				( objectStatus "@baseboard_fab2_lib.baseboard_fab2(sch_1):page77_i171:vdd(3)" )
			)
			( pin "J1G1.226"
				( objectStatus "@baseboard_fab2_lib.baseboard_fab2(sch_1):page77_i171:vdd(4)" )
			)
			( pin "J1G1.223"
				( objectStatus "@baseboard_fab2_lib.baseboard_fab2(sch_1):page77_i171:vdd(5)" )
			)
			( pin "J1G1.220"
				( objectStatus "@baseboard_fab2_lib.baseboard_fab2(sch_1):page77_i171:vdd(6)" )
			)
			( pin "J1G1.217"
				( objectStatus "@baseboard_fab2_lib.baseboard_fab2(sch_1):page77_i171:vdd(7)" )
			)
			( pin "J1G1.215"
				( objectStatus "@baseboard_fab2_lib.baseboard_fab2(sch_1):page77_i171:vdd(8)" )
			)
			( pin "J1G1.212"
				( objectStatus "@baseboard_fab2_lib.baseboard_fab2(sch_1):page77_i171:vdd(9)" )
			)
			( pin "J1G1.209"
				( objectStatus "@baseboard_fab2_lib.baseboard_fab2(sch_1):page77_i171:vdd(10)" )
			)
			( pin "J1G1.206"
				( objectStatus "@baseboard_fab2_lib.baseboard_fab2(sch_1):page77_i171:vdd(11)" )
			)
			( pin "J1G1.204"
				( objectStatus "@baseboard_fab2_lib.baseboard_fab2(sch_1):page77_i171:vdd(12)" )
			)
			( pin "J1G1.92"
				( objectStatus "@baseboard_fab2_lib.baseboard_fab2(sch_1):page77_i171:vdd(13)" )
			)
			( pin "J1G1.90"
				( objectStatus "@baseboard_fab2_lib.baseboard_fab2(sch_1):page77_i171:vdd(14)" )
			)
			( pin "J1G1.88"
				( objectStatus "@baseboard_fab2_lib.baseboard_fab2(sch_1):page77_i171:vdd(15)" )
			)
			( pin "J1G1.85"
				( objectStatus "@baseboard_fab2_lib.baseboard_fab2(sch_1):page77_i171:vdd(16)" )
			)
			( pin "J1G1.83"
				( objectStatus "@baseboard_fab2_lib.baseboard_fab2(sch_1):page77_i171:vdd(17)" )
			)
			( pin "J1G1.80"
				( objectStatus "@baseboard_fab2_lib.baseboard_fab2(sch_1):page77_i171:vdd(18)" )
			)
			( pin "J1G1.76"
				( objectStatus "@baseboard_fab2_lib.baseboard_fab2(sch_1):page77_i171:vdd(19)" )
			)
			( pin "J1G1.73"
				( objectStatus "@baseboard_fab2_lib.baseboard_fab2(sch_1):page77_i171:vdd(20)" )
			)
			( pin "J1G1.70"
				( objectStatus "@baseboard_fab2_lib.baseboard_fab2(sch_1):page77_i171:vdd(21)" )
			)
			( pin "J1G1.67"
				( objectStatus "@baseboard_fab2_lib.baseboard_fab2(sch_1):page77_i171:vdd(22)" )
			)
			( pin "J1G1.64"
				( objectStatus "@baseboard_fab2_lib.baseboard_fab2(sch_1):page77_i171:vdd(23)" )
			)
			( pin "J1G1.61"
				( objectStatus "@baseboard_fab2_lib.baseboard_fab2(sch_1):page77_i171:vdd(24)" )
			)
			( pin "J1G1.59"
				( objectStatus "@baseboard_fab2_lib.baseboard_fab2(sch_1):page77_i171:vdd(25)" )
			)
			( pin "J1G1.287"
				( objectStatus "@baseboard_fab2_lib.baseboard_fab2(sch_1):page77_i171:vpp(0)" )
			)
			( pin "J1G1.286"
				( objectStatus "@baseboard_fab2_lib.baseboard_fab2(sch_1):page77_i171:vpp(1)" )
			)
			( pin "J1G1.288"
				( objectStatus "@baseboard_fab2_lib.baseboard_fab2(sch_1):page77_i171:vpp(2)" )
			)
			( pin "J1G1.143"
				( objectStatus "@baseboard_fab2_lib.baseboard_fab2(sch_1):page77_i171:vpp(3)" )
			)
			( pin "J1G1.142"
				( objectStatus "@baseboard_fab2_lib.baseboard_fab2(sch_1):page77_i171:vpp(4)" )
			)
			( pin "J1G1.221"
				( objectStatus "@baseboard_fab2_lib.baseboard_fab2(sch_1):page77_i171:vtt(0)" )
			)
			( pin "J1G1.77"
				( objectStatus "@baseboard_fab2_lib.baseboard_fab2(sch_1):page77_i171:vtt(1)" )
			)
			( pin "C1F22.1"
				( objectStatus "@baseboard_fab2_lib.baseboard_fab2(sch_1):page77_i181:a" )
			)
			( pin "C1F22.2"
				( objectStatus "@baseboard_fab2_lib.baseboard_fab2(sch_1):page77_i181:b" )
			)
			( pin "C9T7.1"
				( objectStatus "@baseboard_fab2_lib.baseboard_fab2(sch_1):page78_i2:a" )
			)
			( pin "C9T7.2"
				( objectStatus "@baseboard_fab2_lib.baseboard_fab2(sch_1):page78_i2:b" )
			)
			( pin "J9T1.79"
				( objectStatus "@baseboard_fab2_lib.baseboard_fab2(sch_1):page78_i13:a0" )
			)
			( pin "J9T1.72"
				( objectStatus "@baseboard_fab2_lib.baseboard_fab2(sch_1):page78_i13:a1" )
			)
			( pin "J9T1.216"
				( objectStatus "@baseboard_fab2_lib.baseboard_fab2(sch_1):page78_i13:a2" )
			)
			( pin "J9T1.71"
				( objectStatus "@baseboard_fab2_lib.baseboard_fab2(sch_1):page78_i13:a3" )
			)
			( pin "J9T1.214"
				( objectStatus "@baseboard_fab2_lib.baseboard_fab2(sch_1):page78_i13:a4" )
			)
			( pin "J9T1.213"
				( objectStatus "@baseboard_fab2_lib.baseboard_fab2(sch_1):page78_i13:a5" )
			)
			( pin "J9T1.69"
				( objectStatus "@baseboard_fab2_lib.baseboard_fab2(sch_1):page78_i13:a6" )
			)
			( pin "J9T1.211"
				( objectStatus "@baseboard_fab2_lib.baseboard_fab2(sch_1):page78_i13:a7" )
			)
			( pin "J9T1.68"
				( objectStatus "@baseboard_fab2_lib.baseboard_fab2(sch_1):page78_i13:a8" )
			)
			( pin "J9T1.66"
				( objectStatus "@baseboard_fab2_lib.baseboard_fab2(sch_1):page78_i13:a9" )
			)
			( pin "J9T1.225"
				( objectStatus "@baseboard_fab2_lib.baseboard_fab2(sch_1):page78_i13:a10" )
			)
			( pin "J9T1.210"
				( objectStatus "@baseboard_fab2_lib.baseboard_fab2(sch_1):page78_i13:a11" )
			)
			( pin "J9T1.65"
				( objectStatus "@baseboard_fab2_lib.baseboard_fab2(sch_1):page78_i13:a12" )
			)
			( pin "J9T1.232"
				( objectStatus "@baseboard_fab2_lib.baseboard_fab2(sch_1):page78_i13:a13" )
			)
			( pin "J9T1.228"
				( objectStatus "@baseboard_fab2_lib.baseboard_fab2(sch_1):page78_i13:a14_we_n" )
			)
			( pin "J9T1.86"
				( objectStatus "@baseboard_fab2_lib.baseboard_fab2(sch_1):page78_i13:a15_cas_n" )
			)
			( pin "J9T1.82"
				( objectStatus "@baseboard_fab2_lib.baseboard_fab2(sch_1):page78_i13:a16_ras_n" )
			)
			( pin "J9T1.234"
				( objectStatus "@baseboard_fab2_lib.baseboard_fab2(sch_1):page78_i13:a17" )
			)
			( pin "J9T1.62"
				( objectStatus "@baseboard_fab2_lib.baseboard_fab2(sch_1):page78_i13:act_n" )
			)
			( pin "J9T1.208"
				( objectStatus "@baseboard_fab2_lib.baseboard_fab2(sch_1):page78_i13:alert_n" )
			)
			( pin "J9T1.81"
				( objectStatus "@baseboard_fab2_lib.baseboard_fab2(sch_1):page78_i13:ba(0)" )
			)
			( pin "J9T1.224"
				( objectStatus "@baseboard_fab2_lib.baseboard_fab2(sch_1):page78_i13:ba(1)" )
			)
			( pin "J9T1.63"
				( objectStatus "@baseboard_fab2_lib.baseboard_fab2(sch_1):page78_i13:bg(0)" )
			)
			( pin "J9T1.207"
				( objectStatus "@baseboard_fab2_lib.baseboard_fab2(sch_1):page78_i13:bg(1)" )
			)
			( pin "J9T1.235"
				( objectStatus "@baseboard_fab2_lib.baseboard_fab2(sch_1):page78_i13:c(2)" )
			)
			( pin "J9T1.49"
				( objectStatus "@baseboard_fab2_lib.baseboard_fab2(sch_1):page78_i13:cb(0)" )
			)
			( pin "J9T1.194"
				( objectStatus "@baseboard_fab2_lib.baseboard_fab2(sch_1):page78_i13:cb(1)" )
			)
			( pin "J9T1.56"
				( objectStatus "@baseboard_fab2_lib.baseboard_fab2(sch_1):page78_i13:cb(2)" )
			)
			( pin "J9T1.201"
				( objectStatus "@baseboard_fab2_lib.baseboard_fab2(sch_1):page78_i13:cb(3)" )
			)
			( pin "J9T1.47"
				( objectStatus "@baseboard_fab2_lib.baseboard_fab2(sch_1):page78_i13:cb(4)" )
			)
			( pin "J9T1.192"
				( objectStatus "@baseboard_fab2_lib.baseboard_fab2(sch_1):page78_i13:cb(5)" )
			)
			( pin "J9T1.54"
				( objectStatus "@baseboard_fab2_lib.baseboard_fab2(sch_1):page78_i13:cb(6)" )
			)
			( pin "J9T1.199"
				( objectStatus "@baseboard_fab2_lib.baseboard_fab2(sch_1):page78_i13:cb(7)" )
			)
			( pin "J9T1.75"
				( objectStatus "@baseboard_fab2_lib.baseboard_fab2(sch_1):page78_i13:ck0n" )
			)
			( pin "J9T1.74"
				( objectStatus "@baseboard_fab2_lib.baseboard_fab2(sch_1):page78_i13:ck0p" )
			)
			( pin "J9T1.219"
				( objectStatus "@baseboard_fab2_lib.baseboard_fab2(sch_1):page78_i13:ck1n" )
			)
			( pin "J9T1.218"
				( objectStatus "@baseboard_fab2_lib.baseboard_fab2(sch_1):page78_i13:ck1p" )
			)
			( pin "J9T1.60"
				( objectStatus "@baseboard_fab2_lib.baseboard_fab2(sch_1):page78_i13:cke(0)" )
			)
			( pin "J9T1.203"
				( objectStatus "@baseboard_fab2_lib.baseboard_fab2(sch_1):page78_i13:cke(1)" )
			)
			( pin "J9T1.5"
				( objectStatus "@baseboard_fab2_lib.baseboard_fab2(sch_1):page78_i13:dq(0)" )
			)
			( pin "J9T1.150"
				( objectStatus "@baseboard_fab2_lib.baseboard_fab2(sch_1):page78_i13:dq(1)" )
			)
			( pin "J9T1.12"
				( objectStatus "@baseboard_fab2_lib.baseboard_fab2(sch_1):page78_i13:dq(2)" )
			)
			( pin "J9T1.157"
				( objectStatus "@baseboard_fab2_lib.baseboard_fab2(sch_1):page78_i13:dq(3)" )
			)
			( pin "J9T1.3"
				( objectStatus "@baseboard_fab2_lib.baseboard_fab2(sch_1):page78_i13:dq(4)" )
			)
			( pin "J9T1.148"
				( objectStatus "@baseboard_fab2_lib.baseboard_fab2(sch_1):page78_i13:dq(5)" )
			)
			( pin "J9T1.10"
				( objectStatus "@baseboard_fab2_lib.baseboard_fab2(sch_1):page78_i13:dq(6)" )
			)
			( pin "J9T1.155"
				( objectStatus "@baseboard_fab2_lib.baseboard_fab2(sch_1):page78_i13:dq(7)" )
			)
			( pin "J9T1.16"
				( objectStatus "@baseboard_fab2_lib.baseboard_fab2(sch_1):page78_i13:dq(8)" )
			)
			( pin "J9T1.161"
				( objectStatus "@baseboard_fab2_lib.baseboard_fab2(sch_1):page78_i13:dq(9)" )
			)
			( pin "J9T1.23"
				( objectStatus "@baseboard_fab2_lib.baseboard_fab2(sch_1):page78_i13:dq(10)" )
			)
			( pin "J9T1.168"
				( objectStatus "@baseboard_fab2_lib.baseboard_fab2(sch_1):page78_i13:dq(11)" )
			)
			( pin "J9T1.14"
				( objectStatus "@baseboard_fab2_lib.baseboard_fab2(sch_1):page78_i13:dq(12)" )
			)
			( pin "J9T1.159"
				( objectStatus "@baseboard_fab2_lib.baseboard_fab2(sch_1):page78_i13:dq(13)" )
			)
			( pin "J9T1.21"
				( objectStatus "@baseboard_fab2_lib.baseboard_fab2(sch_1):page78_i13:dq(14)" )
			)
			( pin "J9T1.166"
				( objectStatus "@baseboard_fab2_lib.baseboard_fab2(sch_1):page78_i13:dq(15)" )
			)
			( pin "J9T1.27"
				( objectStatus "@baseboard_fab2_lib.baseboard_fab2(sch_1):page78_i13:dq(16)" )
			)
			( pin "J9T1.172"
				( objectStatus "@baseboard_fab2_lib.baseboard_fab2(sch_1):page78_i13:dq(17)" )
			)
			( pin "J9T1.34"
				( objectStatus "@baseboard_fab2_lib.baseboard_fab2(sch_1):page78_i13:dq(18)" )
			)
			( pin "J9T1.179"
				( objectStatus "@baseboard_fab2_lib.baseboard_fab2(sch_1):page78_i13:dq(19)" )
			)
			( pin "J9T1.25"
				( objectStatus "@baseboard_fab2_lib.baseboard_fab2(sch_1):page78_i13:dq(20)" )
			)
			( pin "J9T1.170"
				( objectStatus "@baseboard_fab2_lib.baseboard_fab2(sch_1):page78_i13:dq(21)" )
			)
			( pin "J9T1.32"
				( objectStatus "@baseboard_fab2_lib.baseboard_fab2(sch_1):page78_i13:dq(22)" )
			)
			( pin "J9T1.177"
				( objectStatus "@baseboard_fab2_lib.baseboard_fab2(sch_1):page78_i13:dq(23)" )
			)
			( pin "J9T1.38"
				( objectStatus "@baseboard_fab2_lib.baseboard_fab2(sch_1):page78_i13:dq(24)" )
			)
			( pin "J9T1.183"
				( objectStatus "@baseboard_fab2_lib.baseboard_fab2(sch_1):page78_i13:dq(25)" )
			)
			( pin "J9T1.45"
				( objectStatus "@baseboard_fab2_lib.baseboard_fab2(sch_1):page78_i13:dq(26)" )
			)
			( pin "J9T1.190"
				( objectStatus "@baseboard_fab2_lib.baseboard_fab2(sch_1):page78_i13:dq(27)" )
			)
			( pin "J9T1.36"
				( objectStatus "@baseboard_fab2_lib.baseboard_fab2(sch_1):page78_i13:dq(28)" )
			)
			( pin "J9T1.181"
				( objectStatus "@baseboard_fab2_lib.baseboard_fab2(sch_1):page78_i13:dq(29)" )
			)
			( pin "J9T1.43"
				( objectStatus "@baseboard_fab2_lib.baseboard_fab2(sch_1):page78_i13:dq(30)" )
			)
			( pin "J9T1.188"
				( objectStatus "@baseboard_fab2_lib.baseboard_fab2(sch_1):page78_i13:dq(31)" )
			)
			( pin "J9T1.97"
				( objectStatus "@baseboard_fab2_lib.baseboard_fab2(sch_1):page78_i13:dq(32)" )
			)
			( pin "J9T1.242"
				( objectStatus "@baseboard_fab2_lib.baseboard_fab2(sch_1):page78_i13:dq(33)" )
			)
			( pin "J9T1.104"
				( objectStatus "@baseboard_fab2_lib.baseboard_fab2(sch_1):page78_i13:dq(34)" )
			)
			( pin "J9T1.249"
				( objectStatus "@baseboard_fab2_lib.baseboard_fab2(sch_1):page78_i13:dq(35)" )
			)
			( pin "J9T1.95"
				( objectStatus "@baseboard_fab2_lib.baseboard_fab2(sch_1):page78_i13:dq(36)" )
			)
			( pin "J9T1.240"
				( objectStatus "@baseboard_fab2_lib.baseboard_fab2(sch_1):page78_i13:dq(37)" )
			)
			( pin "J9T1.102"
				( objectStatus "@baseboard_fab2_lib.baseboard_fab2(sch_1):page78_i13:dq(38)" )
			)
			( pin "J9T1.247"
				( objectStatus "@baseboard_fab2_lib.baseboard_fab2(sch_1):page78_i13:dq(39)" )
			)
			( pin "J9T1.108"
				( objectStatus "@baseboard_fab2_lib.baseboard_fab2(sch_1):page78_i13:dq(40)" )
			)
			( pin "J9T1.253"
				( objectStatus "@baseboard_fab2_lib.baseboard_fab2(sch_1):page78_i13:dq(41)" )
			)
			( pin "J9T1.115"
				( objectStatus "@baseboard_fab2_lib.baseboard_fab2(sch_1):page78_i13:dq(42)" )
			)
			( pin "J9T1.260"
				( objectStatus "@baseboard_fab2_lib.baseboard_fab2(sch_1):page78_i13:dq(43)" )
			)
			( pin "J9T1.106"
				( objectStatus "@baseboard_fab2_lib.baseboard_fab2(sch_1):page78_i13:dq(44)" )
			)
			( pin "J9T1.251"
				( objectStatus "@baseboard_fab2_lib.baseboard_fab2(sch_1):page78_i13:dq(45)" )
			)
			( pin "J9T1.113"
				( objectStatus "@baseboard_fab2_lib.baseboard_fab2(sch_1):page78_i13:dq(46)" )
			)
			( pin "J9T1.258"
				( objectStatus "@baseboard_fab2_lib.baseboard_fab2(sch_1):page78_i13:dq(47)" )
			)
			( pin "J9T1.119"
				( objectStatus "@baseboard_fab2_lib.baseboard_fab2(sch_1):page78_i13:dq(48)" )
			)
			( pin "J9T1.264"
				( objectStatus "@baseboard_fab2_lib.baseboard_fab2(sch_1):page78_i13:dq(49)" )
			)
			( pin "J9T1.126"
				( objectStatus "@baseboard_fab2_lib.baseboard_fab2(sch_1):page78_i13:dq(50)" )
			)
			( pin "J9T1.271"
				( objectStatus "@baseboard_fab2_lib.baseboard_fab2(sch_1):page78_i13:dq(51)" )
			)
			( pin "J9T1.117"
				( objectStatus "@baseboard_fab2_lib.baseboard_fab2(sch_1):page78_i13:dq(52)" )
			)
			( pin "J9T1.262"
				( objectStatus "@baseboard_fab2_lib.baseboard_fab2(sch_1):page78_i13:dq(53)" )
			)
			( pin "J9T1.124"
				( objectStatus "@baseboard_fab2_lib.baseboard_fab2(sch_1):page78_i13:dq(54)" )
			)
			( pin "J9T1.269"
				( objectStatus "@baseboard_fab2_lib.baseboard_fab2(sch_1):page78_i13:dq(55)" )
			)
			( pin "J9T1.130"
				( objectStatus "@baseboard_fab2_lib.baseboard_fab2(sch_1):page78_i13:dq(56)" )
			)
			( pin "J9T1.275"
				( objectStatus "@baseboard_fab2_lib.baseboard_fab2(sch_1):page78_i13:dq(57)" )
			)
			( pin "J9T1.137"
				( objectStatus "@baseboard_fab2_lib.baseboard_fab2(sch_1):page78_i13:dq(58)" )
			)
			( pin "J9T1.282"
				( objectStatus "@baseboard_fab2_lib.baseboard_fab2(sch_1):page78_i13:dq(59)" )
			)
			( pin "J9T1.128"
				( objectStatus "@baseboard_fab2_lib.baseboard_fab2(sch_1):page78_i13:dq(60)" )
			)
			( pin "J9T1.273"
				( objectStatus "@baseboard_fab2_lib.baseboard_fab2(sch_1):page78_i13:dq(61)" )
			)
			( pin "J9T1.135"
				( objectStatus "@baseboard_fab2_lib.baseboard_fab2(sch_1):page78_i13:dq(62)" )
			)
			( pin "J9T1.280"
				( objectStatus "@baseboard_fab2_lib.baseboard_fab2(sch_1):page78_i13:dq(63)" )
			)
			( pin "J9T1.78"
				( objectStatus "@baseboard_fab2_lib.baseboard_fab2(sch_1):page78_i13:event_n" )
			)
			( pin "J9T1.87"
				( objectStatus "@baseboard_fab2_lib.baseboard_fab2(sch_1):page78_i13:odt(0)" )
			)
			( pin "J9T1.91"
				( objectStatus "@baseboard_fab2_lib.baseboard_fab2(sch_1):page78_i13:odt(1)" )
			)
			( pin "J9T1.222"
				( objectStatus "@baseboard_fab2_lib.baseboard_fab2(sch_1):page78_i13:par" )
			)
			( pin "J9T1.58"
				( objectStatus "@baseboard_fab2_lib.baseboard_fab2(sch_1):page78_i13:reset_n" )
			)
			( pin "J9T1.205"
				( objectStatus "@baseboard_fab2_lib.baseboard_fab2(sch_1):page78_i13:rfu(0)" )
			)
			( pin "J9T1.227"
				( objectStatus "@baseboard_fab2_lib.baseboard_fab2(sch_1):page78_i13:rfu(1)" )
			)
			( pin "J9T1.144"
				( objectStatus "@baseboard_fab2_lib.baseboard_fab2(sch_1):page78_i13:rfu(2)" )
			)
			( pin "J9T1.84"
				( objectStatus "@baseboard_fab2_lib.baseboard_fab2(sch_1):page78_i13:s0_n" )
			)
			( pin "J9T1.89"
				( objectStatus "@baseboard_fab2_lib.baseboard_fab2(sch_1):page78_i13:s1_n" )
			)
			( pin "J9T1.93"
				( objectStatus "@baseboard_fab2_lib.baseboard_fab2(sch_1):page78_i13:s2_n_c(0)" )
			)
			( pin "J9T1.237"
				( objectStatus "@baseboard_fab2_lib.baseboard_fab2(sch_1):page78_i13:s3_n_c(1)" )
			)
			( pin "J9T1.139"
				( objectStatus "@baseboard_fab2_lib.baseboard_fab2(sch_1):page78_i13:sa(0)" )
			)
			( pin "J9T1.140"
				( objectStatus "@baseboard_fab2_lib.baseboard_fab2(sch_1):page78_i13:sa(1)" )
			)
			( pin "J9T1.238"
				( objectStatus "@baseboard_fab2_lib.baseboard_fab2(sch_1):page78_i13:sa(2)" )
			)
			( pin "J9T1.230"
				( objectStatus "@baseboard_fab2_lib.baseboard_fab2(sch_1):page78_i13:save_n_nc" )
			)
			( pin "J9T1.141"
				( objectStatus "@baseboard_fab2_lib.baseboard_fab2(sch_1):page78_i13:scl" )
			)
			( pin "J9T1.285"
				( objectStatus "@baseboard_fab2_lib.baseboard_fab2(sch_1):page78_i13:sda" )
			)
			( pin "J9T1.284"
				( objectStatus "@baseboard_fab2_lib.baseboard_fab2(sch_1):page78_i13:vddspd" )
			)
			( pin "J9T1.146"
				( objectStatus "@baseboard_fab2_lib.baseboard_fab2(sch_1):page78_i13:vrefca" )
			)
			( pin "J9T1.145"
				( objectStatus "@baseboard_fab2_lib.baseboard_fab2(sch_1):page78_i75:\12v\(0)" )
			)
			( pin "J9T1.1"
				( objectStatus "@baseboard_fab2_lib.baseboard_fab2(sch_1):page78_i75:\12v\(1)" )
			)
			( pin "J9T1.236"
				( objectStatus "@baseboard_fab2_lib.baseboard_fab2(sch_1):page78_i75:vdd(0)" )
			)
			( pin "J9T1.233"
				( objectStatus "@baseboard_fab2_lib.baseboard_fab2(sch_1):page78_i75:vdd(1)" )
			)
			( pin "J9T1.231"
				( objectStatus "@baseboard_fab2_lib.baseboard_fab2(sch_1):page78_i75:vdd(2)" )
			)
			( pin "J9T1.229"
				( objectStatus "@baseboard_fab2_lib.baseboard_fab2(sch_1):page78_i75:vdd(3)" )
			)
			( pin "J9T1.226"
				( objectStatus "@baseboard_fab2_lib.baseboard_fab2(sch_1):page78_i75:vdd(4)" )
			)
			( pin "J9T1.223"
				( objectStatus "@baseboard_fab2_lib.baseboard_fab2(sch_1):page78_i75:vdd(5)" )
			)
			( pin "J9T1.220"
				( objectStatus "@baseboard_fab2_lib.baseboard_fab2(sch_1):page78_i75:vdd(6)" )
			)
			( pin "J9T1.217"
				( objectStatus "@baseboard_fab2_lib.baseboard_fab2(sch_1):page78_i75:vdd(7)" )
			)
			( pin "J9T1.215"
				( objectStatus "@baseboard_fab2_lib.baseboard_fab2(sch_1):page78_i75:vdd(8)" )
			)
			( pin "J9T1.212"
				( objectStatus "@baseboard_fab2_lib.baseboard_fab2(sch_1):page78_i75:vdd(9)" )
			)
			( pin "J9T1.209"
				( objectStatus "@baseboard_fab2_lib.baseboard_fab2(sch_1):page78_i75:vdd(10)" )
			)
			( pin "J9T1.206"
				( objectStatus "@baseboard_fab2_lib.baseboard_fab2(sch_1):page78_i75:vdd(11)" )
			)
			( pin "J9T1.204"
				( objectStatus "@baseboard_fab2_lib.baseboard_fab2(sch_1):page78_i75:vdd(12)" )
			)
			( pin "J9T1.92"
				( objectStatus "@baseboard_fab2_lib.baseboard_fab2(sch_1):page78_i75:vdd(13)" )
			)
			( pin "J9T1.90"
				( objectStatus "@baseboard_fab2_lib.baseboard_fab2(sch_1):page78_i75:vdd(14)" )
			)
			( pin "J9T1.88"
				( objectStatus "@baseboard_fab2_lib.baseboard_fab2(sch_1):page78_i75:vdd(15)" )
			)
			( pin "J9T1.85"
				( objectStatus "@baseboard_fab2_lib.baseboard_fab2(sch_1):page78_i75:vdd(16)" )
			)
			( pin "J9T1.83"
				( objectStatus "@baseboard_fab2_lib.baseboard_fab2(sch_1):page78_i75:vdd(17)" )
			)
			( pin "J9T1.80"
				( objectStatus "@baseboard_fab2_lib.baseboard_fab2(sch_1):page78_i75:vdd(18)" )
			)
			( pin "J9T1.76"
				( objectStatus "@baseboard_fab2_lib.baseboard_fab2(sch_1):page78_i75:vdd(19)" )
			)
			( pin "J9T1.73"
				( objectStatus "@baseboard_fab2_lib.baseboard_fab2(sch_1):page78_i75:vdd(20)" )
			)
			( pin "J9T1.70"
				( objectStatus "@baseboard_fab2_lib.baseboard_fab2(sch_1):page78_i75:vdd(21)" )
			)
			( pin "J9T1.67"
				( objectStatus "@baseboard_fab2_lib.baseboard_fab2(sch_1):page78_i75:vdd(22)" )
			)
			( pin "J9T1.64"
				( objectStatus "@baseboard_fab2_lib.baseboard_fab2(sch_1):page78_i75:vdd(23)" )
			)
			( pin "J9T1.61"
				( objectStatus "@baseboard_fab2_lib.baseboard_fab2(sch_1):page78_i75:vdd(24)" )
			)
			( pin "J9T1.59"
				( objectStatus "@baseboard_fab2_lib.baseboard_fab2(sch_1):page78_i75:vdd(25)" )
			)
			( pin "J9T1.287"
				( objectStatus "@baseboard_fab2_lib.baseboard_fab2(sch_1):page78_i75:vpp(0)" )
			)
			( pin "J9T1.286"
				( objectStatus "@baseboard_fab2_lib.baseboard_fab2(sch_1):page78_i75:vpp(1)" )
			)
			( pin "J9T1.288"
				( objectStatus "@baseboard_fab2_lib.baseboard_fab2(sch_1):page78_i75:vpp(2)" )
			)
			( pin "J9T1.143"
				( objectStatus "@baseboard_fab2_lib.baseboard_fab2(sch_1):page78_i75:vpp(3)" )
			)
			( pin "J9T1.142"
				( objectStatus "@baseboard_fab2_lib.baseboard_fab2(sch_1):page78_i75:vpp(4)" )
			)
			( pin "J9T1.221"
				( objectStatus "@baseboard_fab2_lib.baseboard_fab2(sch_1):page78_i75:vtt(0)" )
			)
			( pin "J9T1.77"
				( objectStatus "@baseboard_fab2_lib.baseboard_fab2(sch_1):page78_i75:vtt(1)" )
			)
			( pin "J9T1.152"
				( objectStatus "@baseboard_fab2_lib.baseboard_fab2(sch_1):page78_i120:dqs0n" )
			)
			( pin "J9T1.153"
				( objectStatus "@baseboard_fab2_lib.baseboard_fab2(sch_1):page78_i120:dqs0p" )
			)
			( pin "J9T1.163"
				( objectStatus "@baseboard_fab2_lib.baseboard_fab2(sch_1):page78_i120:dqs1n" )
			)
			( pin "J9T1.164"
				( objectStatus "@baseboard_fab2_lib.baseboard_fab2(sch_1):page78_i120:dqs1p" )
			)
			( pin "J9T1.174"
				( objectStatus "@baseboard_fab2_lib.baseboard_fab2(sch_1):page78_i120:dqs2n" )
			)
			( pin "J9T1.175"
				( objectStatus "@baseboard_fab2_lib.baseboard_fab2(sch_1):page78_i120:dqs2p" )
			)
			( pin "J9T1.185"
				( objectStatus "@baseboard_fab2_lib.baseboard_fab2(sch_1):page78_i120:dqs3n" )
			)
			( pin "J9T1.186"
				( objectStatus "@baseboard_fab2_lib.baseboard_fab2(sch_1):page78_i120:dqs3p" )
			)
			( pin "J9T1.244"
				( objectStatus "@baseboard_fab2_lib.baseboard_fab2(sch_1):page78_i120:dqs4n" )
			)
			( pin "J9T1.245"
				( objectStatus "@baseboard_fab2_lib.baseboard_fab2(sch_1):page78_i120:dqs4p" )
			)
			( pin "J9T1.255"
				( objectStatus "@baseboard_fab2_lib.baseboard_fab2(sch_1):page78_i120:dqs5n" )
			)
			( pin "J9T1.256"
				( objectStatus "@baseboard_fab2_lib.baseboard_fab2(sch_1):page78_i120:dqs5p" )
			)
			( pin "J9T1.266"
				( objectStatus "@baseboard_fab2_lib.baseboard_fab2(sch_1):page78_i120:dqs6n" )
			)
			( pin "J9T1.267"
				( objectStatus "@baseboard_fab2_lib.baseboard_fab2(sch_1):page78_i120:dqs6p" )
			)
			( pin "J9T1.277"
				( objectStatus "@baseboard_fab2_lib.baseboard_fab2(sch_1):page78_i120:dqs7n" )
			)
			( pin "J9T1.278"
				( objectStatus "@baseboard_fab2_lib.baseboard_fab2(sch_1):page78_i120:dqs7p" )
			)
			( pin "J9T1.196"
				( objectStatus "@baseboard_fab2_lib.baseboard_fab2(sch_1):page78_i120:dqs8n" )
			)
			( pin "J9T1.197"
				( objectStatus "@baseboard_fab2_lib.baseboard_fab2(sch_1):page78_i120:dqs8p" )
			)
			( pin "J9T1.8"
				( objectStatus "@baseboard_fab2_lib.baseboard_fab2(sch_1):page78_i120:dqs9n" )
			)
			( pin "J9T1.7"
				( objectStatus "@baseboard_fab2_lib.baseboard_fab2(sch_1):page78_i120:dqs9p" )
			)
			( pin "J9T1.19"
				( objectStatus "@baseboard_fab2_lib.baseboard_fab2(sch_1):page78_i120:dqs10n" )
			)
			( pin "J9T1.18"
				( objectStatus "@baseboard_fab2_lib.baseboard_fab2(sch_1):page78_i120:dqs10p" )
			)
			( pin "J9T1.30"
				( objectStatus "@baseboard_fab2_lib.baseboard_fab2(sch_1):page78_i120:dqs11n" )
			)
			( pin "J9T1.29"
				( objectStatus "@baseboard_fab2_lib.baseboard_fab2(sch_1):page78_i120:dqs11p" )
			)
			( pin "J9T1.41"
				( objectStatus "@baseboard_fab2_lib.baseboard_fab2(sch_1):page78_i120:dqs12n" )
			)
			( pin "J9T1.40"
				( objectStatus "@baseboard_fab2_lib.baseboard_fab2(sch_1):page78_i120:dqs12p" )
			)
			( pin "J9T1.100"
				( objectStatus "@baseboard_fab2_lib.baseboard_fab2(sch_1):page78_i120:dqs13n" )
			)
			( pin "J9T1.99"
				( objectStatus "@baseboard_fab2_lib.baseboard_fab2(sch_1):page78_i120:dqs13p" )
			)
			( pin "J9T1.111"
				( objectStatus "@baseboard_fab2_lib.baseboard_fab2(sch_1):page78_i120:dqs14n" )
			)
			( pin "J9T1.110"
				( objectStatus "@baseboard_fab2_lib.baseboard_fab2(sch_1):page78_i120:dqs14p" )
			)
			( pin "J9T1.122"
				( objectStatus "@baseboard_fab2_lib.baseboard_fab2(sch_1):page78_i120:dqs15n" )
			)
			( pin "J9T1.121"
				( objectStatus "@baseboard_fab2_lib.baseboard_fab2(sch_1):page78_i120:dqs15p" )
			)
			( pin "J9T1.133"
				( objectStatus "@baseboard_fab2_lib.baseboard_fab2(sch_1):page78_i120:dqs16n" )
			)
			( pin "J9T1.132"
				( objectStatus "@baseboard_fab2_lib.baseboard_fab2(sch_1):page78_i120:dqs16p" )
			)
			( pin "J9T1.52"
				( objectStatus "@baseboard_fab2_lib.baseboard_fab2(sch_1):page78_i120:dqs17n" )
			)
			( pin "J9T1.51"
				( objectStatus "@baseboard_fab2_lib.baseboard_fab2(sch_1):page78_i120:dqs17p" )
			)
			( pin "J9T1.283"
				( objectStatus "@baseboard_fab2_lib.baseboard_fab2(sch_1):page78_i144:vss(0)" )
			)
			( pin "J9T1.281"
				( objectStatus "@baseboard_fab2_lib.baseboard_fab2(sch_1):page78_i144:vss(1)" )
			)
			( pin "J9T1.279"
				( objectStatus "@baseboard_fab2_lib.baseboard_fab2(sch_1):page78_i144:vss(2)" )
			)
			( pin "J9T1.276"
				( objectStatus "@baseboard_fab2_lib.baseboard_fab2(sch_1):page78_i144:vss(3)" )
			)
			( pin "J9T1.274"
				( objectStatus "@baseboard_fab2_lib.baseboard_fab2(sch_1):page78_i144:vss(4)" )
			)
			( pin "J9T1.272"
				( objectStatus "@baseboard_fab2_lib.baseboard_fab2(sch_1):page78_i144:vss(5)" )
			)
			( pin "J9T1.270"
				( objectStatus "@baseboard_fab2_lib.baseboard_fab2(sch_1):page78_i144:vss(6)" )
			)
			( pin "J9T1.268"
				( objectStatus "@baseboard_fab2_lib.baseboard_fab2(sch_1):page78_i144:vss(7)" )
			)
			( pin "J9T1.265"
				( objectStatus "@baseboard_fab2_lib.baseboard_fab2(sch_1):page78_i144:vss(8)" )
			)
			( pin "J9T1.263"
				( objectStatus "@baseboard_fab2_lib.baseboard_fab2(sch_1):page78_i144:vss(9)" )
			)
			( pin "J9T1.261"
				( objectStatus "@baseboard_fab2_lib.baseboard_fab2(sch_1):page78_i144:vss(10)" )
			)
			( pin "J9T1.259"
				( objectStatus "@baseboard_fab2_lib.baseboard_fab2(sch_1):page78_i144:vss(11)" )
			)
			( pin "J9T1.257"
				( objectStatus "@baseboard_fab2_lib.baseboard_fab2(sch_1):page78_i144:vss(12)" )
			)
			( pin "J9T1.254"
				( objectStatus "@baseboard_fab2_lib.baseboard_fab2(sch_1):page78_i144:vss(13)" )
			)
			( pin "J9T1.252"
				( objectStatus "@baseboard_fab2_lib.baseboard_fab2(sch_1):page78_i144:vss(14)" )
			)
			( pin "J9T1.250"
				( objectStatus "@baseboard_fab2_lib.baseboard_fab2(sch_1):page78_i144:vss(15)" )
			)
			( pin "J9T1.248"
				( objectStatus "@baseboard_fab2_lib.baseboard_fab2(sch_1):page78_i144:vss(16)" )
			)
			( pin "J9T1.246"
				( objectStatus "@baseboard_fab2_lib.baseboard_fab2(sch_1):page78_i144:vss(17)" )
			)
			( pin "J9T1.243"
				( objectStatus "@baseboard_fab2_lib.baseboard_fab2(sch_1):page78_i144:vss(18)" )
			)
			( pin "J9T1.241"
				( objectStatus "@baseboard_fab2_lib.baseboard_fab2(sch_1):page78_i144:vss(19)" )
			)
			( pin "J9T1.239"
				( objectStatus "@baseboard_fab2_lib.baseboard_fab2(sch_1):page78_i144:vss(20)" )
			)
			( pin "J9T1.202"
				( objectStatus "@baseboard_fab2_lib.baseboard_fab2(sch_1):page78_i144:vss(21)" )
			)
			( pin "J9T1.200"
				( objectStatus "@baseboard_fab2_lib.baseboard_fab2(sch_1):page78_i144:vss(22)" )
			)
			( pin "J9T1.198"
				( objectStatus "@baseboard_fab2_lib.baseboard_fab2(sch_1):page78_i144:vss(23)" )
			)
			( pin "J9T1.195"
				( objectStatus "@baseboard_fab2_lib.baseboard_fab2(sch_1):page78_i144:vss(24)" )
			)
			( pin "J9T1.193"
				( objectStatus "@baseboard_fab2_lib.baseboard_fab2(sch_1):page78_i144:vss(25)" )
			)
			( pin "J9T1.191"
				( objectStatus "@baseboard_fab2_lib.baseboard_fab2(sch_1):page78_i144:vss(26)" )
			)
			( pin "J9T1.189"
				( objectStatus "@baseboard_fab2_lib.baseboard_fab2(sch_1):page78_i144:vss(27)" )
			)
			( pin "J9T1.187"
				( objectStatus "@baseboard_fab2_lib.baseboard_fab2(sch_1):page78_i144:vss(28)" )
			)
			( pin "J9T1.184"
				( objectStatus "@baseboard_fab2_lib.baseboard_fab2(sch_1):page78_i144:vss(29)" )
			)
			( pin "J9T1.182"
				( objectStatus "@baseboard_fab2_lib.baseboard_fab2(sch_1):page78_i144:vss(30)" )
			)
			( pin "J9T1.180"
				( objectStatus "@baseboard_fab2_lib.baseboard_fab2(sch_1):page78_i144:vss(31)" )
			)
			( pin "J9T1.178"
				( objectStatus "@baseboard_fab2_lib.baseboard_fab2(sch_1):page78_i144:vss(32)" )
			)
			( pin "J9T1.176"
				( objectStatus "@baseboard_fab2_lib.baseboard_fab2(sch_1):page78_i144:vss(33)" )
			)
			( pin "J9T1.173"
				( objectStatus "@baseboard_fab2_lib.baseboard_fab2(sch_1):page78_i144:vss(34)" )
			)
			( pin "J9T1.171"
				( objectStatus "@baseboard_fab2_lib.baseboard_fab2(sch_1):page78_i144:vss(35)" )
			)
			( pin "J9T1.169"
				( objectStatus "@baseboard_fab2_lib.baseboard_fab2(sch_1):page78_i144:vss(36)" )
			)
			( pin "J9T1.167"
				( objectStatus "@baseboard_fab2_lib.baseboard_fab2(sch_1):page78_i144:vss(37)" )
			)
			( pin "J9T1.165"
				( objectStatus "@baseboard_fab2_lib.baseboard_fab2(sch_1):page78_i144:vss(38)" )
			)
			( pin "J9T1.162"
				( objectStatus "@baseboard_fab2_lib.baseboard_fab2(sch_1):page78_i144:vss(39)" )
			)
			( pin "J9T1.160"
				( objectStatus "@baseboard_fab2_lib.baseboard_fab2(sch_1):page78_i144:vss(40)" )
			)
			( pin "J9T1.158"
				( objectStatus "@baseboard_fab2_lib.baseboard_fab2(sch_1):page78_i144:vss(41)" )
			)
			( pin "J9T1.156"
				( objectStatus "@baseboard_fab2_lib.baseboard_fab2(sch_1):page78_i144:vss(42)" )
			)
			( pin "J9T1.154"
				( objectStatus "@baseboard_fab2_lib.baseboard_fab2(sch_1):page78_i144:vss(43)" )
			)
			( pin "J9T1.151"
				( objectStatus "@baseboard_fab2_lib.baseboard_fab2(sch_1):page78_i144:vss(44)" )
			)
			( pin "J9T1.149"
				( objectStatus "@baseboard_fab2_lib.baseboard_fab2(sch_1):page78_i144:vss(45)" )
			)
			( pin "J9T1.147"
				( objectStatus "@baseboard_fab2_lib.baseboard_fab2(sch_1):page78_i144:vss(46)" )
			)
			( pin "J9T1.138"
				( objectStatus "@baseboard_fab2_lib.baseboard_fab2(sch_1):page78_i144:vss(47)" )
			)
			( pin "J9T1.136"
				( objectStatus "@baseboard_fab2_lib.baseboard_fab2(sch_1):page78_i144:vss(48)" )
			)
			( pin "J9T1.134"
				( objectStatus "@baseboard_fab2_lib.baseboard_fab2(sch_1):page78_i144:vss(49)" )
			)
			( pin "J9T1.131"
				( objectStatus "@baseboard_fab2_lib.baseboard_fab2(sch_1):page78_i144:vss(50)" )
			)
			( pin "J9T1.129"
				( objectStatus "@baseboard_fab2_lib.baseboard_fab2(sch_1):page78_i144:vss(51)" )
			)
			( pin "J9T1.127"
				( objectStatus "@baseboard_fab2_lib.baseboard_fab2(sch_1):page78_i144:vss(52)" )
			)
			( pin "J9T1.125"
				( objectStatus "@baseboard_fab2_lib.baseboard_fab2(sch_1):page78_i144:vss(53)" )
			)
			( pin "J9T1.123"
				( objectStatus "@baseboard_fab2_lib.baseboard_fab2(sch_1):page78_i144:vss(54)" )
			)
			( pin "J9T1.120"
				( objectStatus "@baseboard_fab2_lib.baseboard_fab2(sch_1):page78_i144:vss(55)" )
			)
			( pin "J9T1.118"
				( objectStatus "@baseboard_fab2_lib.baseboard_fab2(sch_1):page78_i144:vss(56)" )
			)
			( pin "J9T1.116"
				( objectStatus "@baseboard_fab2_lib.baseboard_fab2(sch_1):page78_i144:vss(57)" )
			)
			( pin "J9T1.114"
				( objectStatus "@baseboard_fab2_lib.baseboard_fab2(sch_1):page78_i144:vss(58)" )
			)
			( pin "J9T1.112"
				( objectStatus "@baseboard_fab2_lib.baseboard_fab2(sch_1):page78_i144:vss(59)" )
			)
			( pin "J9T1.109"
				( objectStatus "@baseboard_fab2_lib.baseboard_fab2(sch_1):page78_i144:vss(60)" )
			)
			( pin "J9T1.107"
				( objectStatus "@baseboard_fab2_lib.baseboard_fab2(sch_1):page78_i144:vss(61)" )
			)
			( pin "J9T1.105"
				( objectStatus "@baseboard_fab2_lib.baseboard_fab2(sch_1):page78_i144:vss(62)" )
			)
			( pin "J9T1.103"
				( objectStatus "@baseboard_fab2_lib.baseboard_fab2(sch_1):page78_i144:vss(63)" )
			)
			( pin "J9T1.101"
				( objectStatus "@baseboard_fab2_lib.baseboard_fab2(sch_1):page78_i144:vss(64)" )
			)
			( pin "J9T1.98"
				( objectStatus "@baseboard_fab2_lib.baseboard_fab2(sch_1):page78_i144:vss(65)" )
			)
			( pin "J9T1.96"
				( objectStatus "@baseboard_fab2_lib.baseboard_fab2(sch_1):page78_i144:vss(66)" )
			)
			( pin "J9T1.94"
				( objectStatus "@baseboard_fab2_lib.baseboard_fab2(sch_1):page78_i144:vss(67)" )
			)
			( pin "J9T1.57"
				( objectStatus "@baseboard_fab2_lib.baseboard_fab2(sch_1):page78_i144:vss(68)" )
			)
			( pin "J9T1.55"
				( objectStatus "@baseboard_fab2_lib.baseboard_fab2(sch_1):page78_i144:vss(69)" )
			)
			( pin "J9T1.53"
				( objectStatus "@baseboard_fab2_lib.baseboard_fab2(sch_1):page78_i144:vss(70)" )
			)
			( pin "J9T1.50"
				( objectStatus "@baseboard_fab2_lib.baseboard_fab2(sch_1):page78_i144:vss(71)" )
			)
			( pin "J9T1.48"
				( objectStatus "@baseboard_fab2_lib.baseboard_fab2(sch_1):page78_i144:vss(72)" )
			)
			( pin "J9T1.46"
				( objectStatus "@baseboard_fab2_lib.baseboard_fab2(sch_1):page78_i144:vss(73)" )
			)
			( pin "J9T1.44"
				( objectStatus "@baseboard_fab2_lib.baseboard_fab2(sch_1):page78_i144:vss(74)" )
			)
			( pin "J9T1.42"
				( objectStatus "@baseboard_fab2_lib.baseboard_fab2(sch_1):page78_i144:vss(75)" )
			)
			( pin "J9T1.39"
				( objectStatus "@baseboard_fab2_lib.baseboard_fab2(sch_1):page78_i144:vss(76)" )
			)
			( pin "J9T1.37"
				( objectStatus "@baseboard_fab2_lib.baseboard_fab2(sch_1):page78_i144:vss(77)" )
			)
			( pin "J9T1.35"
				( objectStatus "@baseboard_fab2_lib.baseboard_fab2(sch_1):page78_i144:vss(78)" )
			)
			( pin "J9T1.33"
				( objectStatus "@baseboard_fab2_lib.baseboard_fab2(sch_1):page78_i144:vss(79)" )
			)
			( pin "J9T1.31"
				( objectStatus "@baseboard_fab2_lib.baseboard_fab2(sch_1):page78_i144:vss(80)" )
			)
			( pin "J9T1.28"
				( objectStatus "@baseboard_fab2_lib.baseboard_fab2(sch_1):page78_i144:vss(81)" )
			)
			( pin "J9T1.26"
				( objectStatus "@baseboard_fab2_lib.baseboard_fab2(sch_1):page78_i144:vss(82)" )
			)
			( pin "J9T1.24"
				( objectStatus "@baseboard_fab2_lib.baseboard_fab2(sch_1):page78_i144:vss(83)" )
			)
			( pin "J9T1.22"
				( objectStatus "@baseboard_fab2_lib.baseboard_fab2(sch_1):page78_i144:vss(84)" )
			)
			( pin "J9T1.20"
				( objectStatus "@baseboard_fab2_lib.baseboard_fab2(sch_1):page78_i144:vss(85)" )
			)
			( pin "J9T1.17"
				( objectStatus "@baseboard_fab2_lib.baseboard_fab2(sch_1):page78_i144:vss(86)" )
			)
			( pin "J9T1.15"
				( objectStatus "@baseboard_fab2_lib.baseboard_fab2(sch_1):page78_i144:vss(87)" )
			)
			( pin "J9T1.13"
				( objectStatus "@baseboard_fab2_lib.baseboard_fab2(sch_1):page78_i144:vss(88)" )
			)
			( pin "J9T1.11"
				( objectStatus "@baseboard_fab2_lib.baseboard_fab2(sch_1):page78_i144:vss(89)" )
			)
			( pin "J9T1.9"
				( objectStatus "@baseboard_fab2_lib.baseboard_fab2(sch_1):page78_i144:vss(90)" )
			)
			( pin "J9T1.6"
				( objectStatus "@baseboard_fab2_lib.baseboard_fab2(sch_1):page78_i144:vss(91)" )
			)
			( pin "J9T1.4"
				( objectStatus "@baseboard_fab2_lib.baseboard_fab2(sch_1):page78_i144:vss(92)" )
			)
			( pin "J9T1.2"
				( objectStatus "@baseboard_fab2_lib.baseboard_fab2(sch_1):page78_i144:vss(93)" )
			)
			( pin "J1G2.283"
				( objectStatus "@baseboard_fab2_lib.baseboard_fab2(sch_1):page79_i43:vss(0)" )
			)
			( pin "J1G2.281"
				( objectStatus "@baseboard_fab2_lib.baseboard_fab2(sch_1):page79_i43:vss(1)" )
			)
			( pin "J1G2.279"
				( objectStatus "@baseboard_fab2_lib.baseboard_fab2(sch_1):page79_i43:vss(2)" )
			)
			( pin "J1G2.276"
				( objectStatus "@baseboard_fab2_lib.baseboard_fab2(sch_1):page79_i43:vss(3)" )
			)
			( pin "J1G2.274"
				( objectStatus "@baseboard_fab2_lib.baseboard_fab2(sch_1):page79_i43:vss(4)" )
			)
			( pin "J1G2.272"
				( objectStatus "@baseboard_fab2_lib.baseboard_fab2(sch_1):page79_i43:vss(5)" )
			)
			( pin "J1G2.270"
				( objectStatus "@baseboard_fab2_lib.baseboard_fab2(sch_1):page79_i43:vss(6)" )
			)
			( pin "J1G2.268"
				( objectStatus "@baseboard_fab2_lib.baseboard_fab2(sch_1):page79_i43:vss(7)" )
			)
			( pin "J1G2.265"
				( objectStatus "@baseboard_fab2_lib.baseboard_fab2(sch_1):page79_i43:vss(8)" )
			)
			( pin "J1G2.263"
				( objectStatus "@baseboard_fab2_lib.baseboard_fab2(sch_1):page79_i43:vss(9)" )
			)
			( pin "J1G2.261"
				( objectStatus "@baseboard_fab2_lib.baseboard_fab2(sch_1):page79_i43:vss(10)" )
			)
			( pin "J1G2.259"
				( objectStatus "@baseboard_fab2_lib.baseboard_fab2(sch_1):page79_i43:vss(11)" )
			)
			( pin "J1G2.257"
				( objectStatus "@baseboard_fab2_lib.baseboard_fab2(sch_1):page79_i43:vss(12)" )
			)
			( pin "J1G2.254"
				( objectStatus "@baseboard_fab2_lib.baseboard_fab2(sch_1):page79_i43:vss(13)" )
			)
			( pin "J1G2.252"
				( objectStatus "@baseboard_fab2_lib.baseboard_fab2(sch_1):page79_i43:vss(14)" )
			)
			( pin "J1G2.250"
				( objectStatus "@baseboard_fab2_lib.baseboard_fab2(sch_1):page79_i43:vss(15)" )
			)
			( pin "J1G2.248"
				( objectStatus "@baseboard_fab2_lib.baseboard_fab2(sch_1):page79_i43:vss(16)" )
			)
			( pin "J1G2.246"
				( objectStatus "@baseboard_fab2_lib.baseboard_fab2(sch_1):page79_i43:vss(17)" )
			)
			( pin "J1G2.243"
				( objectStatus "@baseboard_fab2_lib.baseboard_fab2(sch_1):page79_i43:vss(18)" )
			)
			( pin "J1G2.241"
				( objectStatus "@baseboard_fab2_lib.baseboard_fab2(sch_1):page79_i43:vss(19)" )
			)
			( pin "J1G2.239"
				( objectStatus "@baseboard_fab2_lib.baseboard_fab2(sch_1):page79_i43:vss(20)" )
			)
			( pin "J1G2.202"
				( objectStatus "@baseboard_fab2_lib.baseboard_fab2(sch_1):page79_i43:vss(21)" )
			)
			( pin "J1G2.200"
				( objectStatus "@baseboard_fab2_lib.baseboard_fab2(sch_1):page79_i43:vss(22)" )
			)
			( pin "J1G2.198"
				( objectStatus "@baseboard_fab2_lib.baseboard_fab2(sch_1):page79_i43:vss(23)" )
			)
			( pin "J1G2.195"
				( objectStatus "@baseboard_fab2_lib.baseboard_fab2(sch_1):page79_i43:vss(24)" )
			)
			( pin "J1G2.193"
				( objectStatus "@baseboard_fab2_lib.baseboard_fab2(sch_1):page79_i43:vss(25)" )
			)
			( pin "J1G2.191"
				( objectStatus "@baseboard_fab2_lib.baseboard_fab2(sch_1):page79_i43:vss(26)" )
			)
			( pin "J1G2.189"
				( objectStatus "@baseboard_fab2_lib.baseboard_fab2(sch_1):page79_i43:vss(27)" )
			)
			( pin "J1G2.187"
				( objectStatus "@baseboard_fab2_lib.baseboard_fab2(sch_1):page79_i43:vss(28)" )
			)
			( pin "J1G2.184"
				( objectStatus "@baseboard_fab2_lib.baseboard_fab2(sch_1):page79_i43:vss(29)" )
			)
			( pin "J1G2.182"
				( objectStatus "@baseboard_fab2_lib.baseboard_fab2(sch_1):page79_i43:vss(30)" )
			)
			( pin "J1G2.180"
				( objectStatus "@baseboard_fab2_lib.baseboard_fab2(sch_1):page79_i43:vss(31)" )
			)
			( pin "J1G2.178"
				( objectStatus "@baseboard_fab2_lib.baseboard_fab2(sch_1):page79_i43:vss(32)" )
			)
			( pin "J1G2.176"
				( objectStatus "@baseboard_fab2_lib.baseboard_fab2(sch_1):page79_i43:vss(33)" )
			)
			( pin "J1G2.173"
				( objectStatus "@baseboard_fab2_lib.baseboard_fab2(sch_1):page79_i43:vss(34)" )
			)
			( pin "J1G2.171"
				( objectStatus "@baseboard_fab2_lib.baseboard_fab2(sch_1):page79_i43:vss(35)" )
			)
			( pin "J1G2.169"
				( objectStatus "@baseboard_fab2_lib.baseboard_fab2(sch_1):page79_i43:vss(36)" )
			)
			( pin "J1G2.167"
				( objectStatus "@baseboard_fab2_lib.baseboard_fab2(sch_1):page79_i43:vss(37)" )
			)
			( pin "J1G2.165"
				( objectStatus "@baseboard_fab2_lib.baseboard_fab2(sch_1):page79_i43:vss(38)" )
			)
			( pin "J1G2.162"
				( objectStatus "@baseboard_fab2_lib.baseboard_fab2(sch_1):page79_i43:vss(39)" )
			)
			( pin "J1G2.160"
				( objectStatus "@baseboard_fab2_lib.baseboard_fab2(sch_1):page79_i43:vss(40)" )
			)
			( pin "J1G2.158"
				( objectStatus "@baseboard_fab2_lib.baseboard_fab2(sch_1):page79_i43:vss(41)" )
			)
			( pin "J1G2.156"
				( objectStatus "@baseboard_fab2_lib.baseboard_fab2(sch_1):page79_i43:vss(42)" )
			)
			( pin "J1G2.154"
				( objectStatus "@baseboard_fab2_lib.baseboard_fab2(sch_1):page79_i43:vss(43)" )
			)
			( pin "J1G2.151"
				( objectStatus "@baseboard_fab2_lib.baseboard_fab2(sch_1):page79_i43:vss(44)" )
			)
			( pin "J1G2.149"
				( objectStatus "@baseboard_fab2_lib.baseboard_fab2(sch_1):page79_i43:vss(45)" )
			)
			( pin "J1G2.147"
				( objectStatus "@baseboard_fab2_lib.baseboard_fab2(sch_1):page79_i43:vss(46)" )
			)
			( pin "J1G2.138"
				( objectStatus "@baseboard_fab2_lib.baseboard_fab2(sch_1):page79_i43:vss(47)" )
			)
			( pin "J1G2.136"
				( objectStatus "@baseboard_fab2_lib.baseboard_fab2(sch_1):page79_i43:vss(48)" )
			)
			( pin "J1G2.134"
				( objectStatus "@baseboard_fab2_lib.baseboard_fab2(sch_1):page79_i43:vss(49)" )
			)
			( pin "J1G2.131"
				( objectStatus "@baseboard_fab2_lib.baseboard_fab2(sch_1):page79_i43:vss(50)" )
			)
			( pin "J1G2.129"
				( objectStatus "@baseboard_fab2_lib.baseboard_fab2(sch_1):page79_i43:vss(51)" )
			)
			( pin "J1G2.127"
				( objectStatus "@baseboard_fab2_lib.baseboard_fab2(sch_1):page79_i43:vss(52)" )
			)
			( pin "J1G2.125"
				( objectStatus "@baseboard_fab2_lib.baseboard_fab2(sch_1):page79_i43:vss(53)" )
			)
			( pin "J1G2.123"
				( objectStatus "@baseboard_fab2_lib.baseboard_fab2(sch_1):page79_i43:vss(54)" )
			)
			( pin "J1G2.120"
				( objectStatus "@baseboard_fab2_lib.baseboard_fab2(sch_1):page79_i43:vss(55)" )
			)
			( pin "J1G2.118"
				( objectStatus "@baseboard_fab2_lib.baseboard_fab2(sch_1):page79_i43:vss(56)" )
			)
			( pin "J1G2.116"
				( objectStatus "@baseboard_fab2_lib.baseboard_fab2(sch_1):page79_i43:vss(57)" )
			)
			( pin "J1G2.114"
				( objectStatus "@baseboard_fab2_lib.baseboard_fab2(sch_1):page79_i43:vss(58)" )
			)
			( pin "J1G2.112"
				( objectStatus "@baseboard_fab2_lib.baseboard_fab2(sch_1):page79_i43:vss(59)" )
			)
			( pin "J1G2.109"
				( objectStatus "@baseboard_fab2_lib.baseboard_fab2(sch_1):page79_i43:vss(60)" )
			)
			( pin "J1G2.107"
				( objectStatus "@baseboard_fab2_lib.baseboard_fab2(sch_1):page79_i43:vss(61)" )
			)
			( pin "J1G2.105"
				( objectStatus "@baseboard_fab2_lib.baseboard_fab2(sch_1):page79_i43:vss(62)" )
			)
			( pin "J1G2.103"
				( objectStatus "@baseboard_fab2_lib.baseboard_fab2(sch_1):page79_i43:vss(63)" )
			)
			( pin "J1G2.101"
				( objectStatus "@baseboard_fab2_lib.baseboard_fab2(sch_1):page79_i43:vss(64)" )
			)
			( pin "J1G2.98"
				( objectStatus "@baseboard_fab2_lib.baseboard_fab2(sch_1):page79_i43:vss(65)" )
			)
			( pin "J1G2.96"
				( objectStatus "@baseboard_fab2_lib.baseboard_fab2(sch_1):page79_i43:vss(66)" )
			)
			( pin "J1G2.94"
				( objectStatus "@baseboard_fab2_lib.baseboard_fab2(sch_1):page79_i43:vss(67)" )
			)
			( pin "J1G2.57"
				( objectStatus "@baseboard_fab2_lib.baseboard_fab2(sch_1):page79_i43:vss(68)" )
			)
			( pin "J1G2.55"
				( objectStatus "@baseboard_fab2_lib.baseboard_fab2(sch_1):page79_i43:vss(69)" )
			)
			( pin "J1G2.53"
				( objectStatus "@baseboard_fab2_lib.baseboard_fab2(sch_1):page79_i43:vss(70)" )
			)
			( pin "J1G2.50"
				( objectStatus "@baseboard_fab2_lib.baseboard_fab2(sch_1):page79_i43:vss(71)" )
			)
			( pin "J1G2.48"
				( objectStatus "@baseboard_fab2_lib.baseboard_fab2(sch_1):page79_i43:vss(72)" )
			)
			( pin "J1G2.46"
				( objectStatus "@baseboard_fab2_lib.baseboard_fab2(sch_1):page79_i43:vss(73)" )
			)
			( pin "J1G2.44"
				( objectStatus "@baseboard_fab2_lib.baseboard_fab2(sch_1):page79_i43:vss(74)" )
			)
			( pin "J1G2.42"
				( objectStatus "@baseboard_fab2_lib.baseboard_fab2(sch_1):page79_i43:vss(75)" )
			)
			( pin "J1G2.39"
				( objectStatus "@baseboard_fab2_lib.baseboard_fab2(sch_1):page79_i43:vss(76)" )
			)
			( pin "J1G2.37"
				( objectStatus "@baseboard_fab2_lib.baseboard_fab2(sch_1):page79_i43:vss(77)" )
			)
			( pin "J1G2.35"
				( objectStatus "@baseboard_fab2_lib.baseboard_fab2(sch_1):page79_i43:vss(78)" )
			)
			( pin "J1G2.33"
				( objectStatus "@baseboard_fab2_lib.baseboard_fab2(sch_1):page79_i43:vss(79)" )
			)
			( pin "J1G2.31"
				( objectStatus "@baseboard_fab2_lib.baseboard_fab2(sch_1):page79_i43:vss(80)" )
			)
			( pin "J1G2.28"
				( objectStatus "@baseboard_fab2_lib.baseboard_fab2(sch_1):page79_i43:vss(81)" )
			)
			( pin "J1G2.26"
				( objectStatus "@baseboard_fab2_lib.baseboard_fab2(sch_1):page79_i43:vss(82)" )
			)
			( pin "J1G2.24"
				( objectStatus "@baseboard_fab2_lib.baseboard_fab2(sch_1):page79_i43:vss(83)" )
			)
			( pin "J1G2.22"
				( objectStatus "@baseboard_fab2_lib.baseboard_fab2(sch_1):page79_i43:vss(84)" )
			)
			( pin "J1G2.20"
				( objectStatus "@baseboard_fab2_lib.baseboard_fab2(sch_1):page79_i43:vss(85)" )
			)
			( pin "J1G2.17"
				( objectStatus "@baseboard_fab2_lib.baseboard_fab2(sch_1):page79_i43:vss(86)" )
			)
			( pin "J1G2.15"
				( objectStatus "@baseboard_fab2_lib.baseboard_fab2(sch_1):page79_i43:vss(87)" )
			)
			( pin "J1G2.13"
				( objectStatus "@baseboard_fab2_lib.baseboard_fab2(sch_1):page79_i43:vss(88)" )
			)
			( pin "J1G2.11"
				( objectStatus "@baseboard_fab2_lib.baseboard_fab2(sch_1):page79_i43:vss(89)" )
			)
			( pin "J1G2.9"
				( objectStatus "@baseboard_fab2_lib.baseboard_fab2(sch_1):page79_i43:vss(90)" )
			)
			( pin "J1G2.6"
				( objectStatus "@baseboard_fab2_lib.baseboard_fab2(sch_1):page79_i43:vss(91)" )
			)
			( pin "J1G2.4"
				( objectStatus "@baseboard_fab2_lib.baseboard_fab2(sch_1):page79_i43:vss(92)" )
			)
			( pin "J1G2.2"
				( objectStatus "@baseboard_fab2_lib.baseboard_fab2(sch_1):page79_i43:vss(93)" )
			)
			( pin "J1G2.152"
				( objectStatus "@baseboard_fab2_lib.baseboard_fab2(sch_1):page79_i64:dqs0n" )
			)
			( pin "J1G2.153"
				( objectStatus "@baseboard_fab2_lib.baseboard_fab2(sch_1):page79_i64:dqs0p" )
			)
			( pin "J1G2.163"
				( objectStatus "@baseboard_fab2_lib.baseboard_fab2(sch_1):page79_i64:dqs1n" )
			)
			( pin "J1G2.164"
				( objectStatus "@baseboard_fab2_lib.baseboard_fab2(sch_1):page79_i64:dqs1p" )
			)
			( pin "J1G2.174"
				( objectStatus "@baseboard_fab2_lib.baseboard_fab2(sch_1):page79_i64:dqs2n" )
			)
			( pin "J1G2.175"
				( objectStatus "@baseboard_fab2_lib.baseboard_fab2(sch_1):page79_i64:dqs2p" )
			)
			( pin "J1G2.185"
				( objectStatus "@baseboard_fab2_lib.baseboard_fab2(sch_1):page79_i64:dqs3n" )
			)
			( pin "J1G2.186"
				( objectStatus "@baseboard_fab2_lib.baseboard_fab2(sch_1):page79_i64:dqs3p" )
			)
			( pin "J1G2.244"
				( objectStatus "@baseboard_fab2_lib.baseboard_fab2(sch_1):page79_i64:dqs4n" )
			)
			( pin "J1G2.245"
				( objectStatus "@baseboard_fab2_lib.baseboard_fab2(sch_1):page79_i64:dqs4p" )
			)
			( pin "J1G2.255"
				( objectStatus "@baseboard_fab2_lib.baseboard_fab2(sch_1):page79_i64:dqs5n" )
			)
			( pin "J1G2.256"
				( objectStatus "@baseboard_fab2_lib.baseboard_fab2(sch_1):page79_i64:dqs5p" )
			)
			( pin "J1G2.266"
				( objectStatus "@baseboard_fab2_lib.baseboard_fab2(sch_1):page79_i64:dqs6n" )
			)
			( pin "J1G2.267"
				( objectStatus "@baseboard_fab2_lib.baseboard_fab2(sch_1):page79_i64:dqs6p" )
			)
			( pin "J1G2.277"
				( objectStatus "@baseboard_fab2_lib.baseboard_fab2(sch_1):page79_i64:dqs7n" )
			)
			( pin "J1G2.278"
				( objectStatus "@baseboard_fab2_lib.baseboard_fab2(sch_1):page79_i64:dqs7p" )
			)
			( pin "J1G2.196"
				( objectStatus "@baseboard_fab2_lib.baseboard_fab2(sch_1):page79_i64:dqs8n" )
			)
			( pin "J1G2.197"
				( objectStatus "@baseboard_fab2_lib.baseboard_fab2(sch_1):page79_i64:dqs8p" )
			)
			( pin "J1G2.8"
				( objectStatus "@baseboard_fab2_lib.baseboard_fab2(sch_1):page79_i64:dqs9n" )
			)
			( pin "J1G2.7"
				( objectStatus "@baseboard_fab2_lib.baseboard_fab2(sch_1):page79_i64:dqs9p" )
			)
			( pin "J1G2.19"
				( objectStatus "@baseboard_fab2_lib.baseboard_fab2(sch_1):page79_i64:dqs10n" )
			)
			( pin "J1G2.18"
				( objectStatus "@baseboard_fab2_lib.baseboard_fab2(sch_1):page79_i64:dqs10p" )
			)
			( pin "J1G2.30"
				( objectStatus "@baseboard_fab2_lib.baseboard_fab2(sch_1):page79_i64:dqs11n" )
			)
			( pin "J1G2.29"
				( objectStatus "@baseboard_fab2_lib.baseboard_fab2(sch_1):page79_i64:dqs11p" )
			)
			( pin "J1G2.41"
				( objectStatus "@baseboard_fab2_lib.baseboard_fab2(sch_1):page79_i64:dqs12n" )
			)
			( pin "J1G2.40"
				( objectStatus "@baseboard_fab2_lib.baseboard_fab2(sch_1):page79_i64:dqs12p" )
			)
			( pin "J1G2.100"
				( objectStatus "@baseboard_fab2_lib.baseboard_fab2(sch_1):page79_i64:dqs13n" )
			)
			( pin "J1G2.99"
				( objectStatus "@baseboard_fab2_lib.baseboard_fab2(sch_1):page79_i64:dqs13p" )
			)
			( pin "J1G2.111"
				( objectStatus "@baseboard_fab2_lib.baseboard_fab2(sch_1):page79_i64:dqs14n" )
			)
			( pin "J1G2.110"
				( objectStatus "@baseboard_fab2_lib.baseboard_fab2(sch_1):page79_i64:dqs14p" )
			)
			( pin "J1G2.122"
				( objectStatus "@baseboard_fab2_lib.baseboard_fab2(sch_1):page79_i64:dqs15n" )
			)
			( pin "J1G2.121"
				( objectStatus "@baseboard_fab2_lib.baseboard_fab2(sch_1):page79_i64:dqs15p" )
			)
			( pin "J1G2.133"
				( objectStatus "@baseboard_fab2_lib.baseboard_fab2(sch_1):page79_i64:dqs16n" )
			)
			( pin "J1G2.132"
				( objectStatus "@baseboard_fab2_lib.baseboard_fab2(sch_1):page79_i64:dqs16p" )
			)
			( pin "J1G2.52"
				( objectStatus "@baseboard_fab2_lib.baseboard_fab2(sch_1):page79_i64:dqs17n" )
			)
			( pin "J1G2.51"
				( objectStatus "@baseboard_fab2_lib.baseboard_fab2(sch_1):page79_i64:dqs17p" )
			)
			( pin "J1G2.79"
				( objectStatus "@baseboard_fab2_lib.baseboard_fab2(sch_1):page79_i111:a0" )
			)
			( pin "J1G2.72"
				( objectStatus "@baseboard_fab2_lib.baseboard_fab2(sch_1):page79_i111:a1" )
			)
			( pin "J1G2.216"
				( objectStatus "@baseboard_fab2_lib.baseboard_fab2(sch_1):page79_i111:a2" )
			)
			( pin "J1G2.71"
				( objectStatus "@baseboard_fab2_lib.baseboard_fab2(sch_1):page79_i111:a3" )
			)
			( pin "J1G2.214"
				( objectStatus "@baseboard_fab2_lib.baseboard_fab2(sch_1):page79_i111:a4" )
			)
			( pin "J1G2.213"
				( objectStatus "@baseboard_fab2_lib.baseboard_fab2(sch_1):page79_i111:a5" )
			)
			( pin "J1G2.69"
				( objectStatus "@baseboard_fab2_lib.baseboard_fab2(sch_1):page79_i111:a6" )
			)
			( pin "J1G2.211"
				( objectStatus "@baseboard_fab2_lib.baseboard_fab2(sch_1):page79_i111:a7" )
			)
			( pin "J1G2.68"
				( objectStatus "@baseboard_fab2_lib.baseboard_fab2(sch_1):page79_i111:a8" )
			)
			( pin "J1G2.66"
				( objectStatus "@baseboard_fab2_lib.baseboard_fab2(sch_1):page79_i111:a9" )
			)
			( pin "J1G2.225"
				( objectStatus "@baseboard_fab2_lib.baseboard_fab2(sch_1):page79_i111:a10" )
			)
			( pin "J1G2.210"
				( objectStatus "@baseboard_fab2_lib.baseboard_fab2(sch_1):page79_i111:a11" )
			)
			( pin "J1G2.65"
				( objectStatus "@baseboard_fab2_lib.baseboard_fab2(sch_1):page79_i111:a12" )
			)
			( pin "J1G2.232"
				( objectStatus "@baseboard_fab2_lib.baseboard_fab2(sch_1):page79_i111:a13" )
			)
			( pin "J1G2.228"
				( objectStatus "@baseboard_fab2_lib.baseboard_fab2(sch_1):page79_i111:a14_we_n" )
			)
			( pin "J1G2.86"
				( objectStatus "@baseboard_fab2_lib.baseboard_fab2(sch_1):page79_i111:a15_cas_n" )
			)
			( pin "J1G2.82"
				( objectStatus "@baseboard_fab2_lib.baseboard_fab2(sch_1):page79_i111:a16_ras_n" )
			)
			( pin "J1G2.234"
				( objectStatus "@baseboard_fab2_lib.baseboard_fab2(sch_1):page79_i111:a17" )
			)
			( pin "J1G2.62"
				( objectStatus "@baseboard_fab2_lib.baseboard_fab2(sch_1):page79_i111:act_n" )
			)
			( pin "J1G2.208"
				( objectStatus "@baseboard_fab2_lib.baseboard_fab2(sch_1):page79_i111:alert_n" )
			)
			( pin "J1G2.81"
				( objectStatus "@baseboard_fab2_lib.baseboard_fab2(sch_1):page79_i111:ba(0)" )
			)
			( pin "J1G2.224"
				( objectStatus "@baseboard_fab2_lib.baseboard_fab2(sch_1):page79_i111:ba(1)" )
			)
			( pin "J1G2.63"
				( objectStatus "@baseboard_fab2_lib.baseboard_fab2(sch_1):page79_i111:bg(0)" )
			)
			( pin "J1G2.207"
				( objectStatus "@baseboard_fab2_lib.baseboard_fab2(sch_1):page79_i111:bg(1)" )
			)
			( pin "J1G2.235"
				( objectStatus "@baseboard_fab2_lib.baseboard_fab2(sch_1):page79_i111:c(2)" )
			)
			( pin "J1G2.49"
				( objectStatus "@baseboard_fab2_lib.baseboard_fab2(sch_1):page79_i111:cb(0)" )
			)
			( pin "J1G2.194"
				( objectStatus "@baseboard_fab2_lib.baseboard_fab2(sch_1):page79_i111:cb(1)" )
			)
			( pin "J1G2.56"
				( objectStatus "@baseboard_fab2_lib.baseboard_fab2(sch_1):page79_i111:cb(2)" )
			)
			( pin "J1G2.201"
				( objectStatus "@baseboard_fab2_lib.baseboard_fab2(sch_1):page79_i111:cb(3)" )
			)
			( pin "J1G2.47"
				( objectStatus "@baseboard_fab2_lib.baseboard_fab2(sch_1):page79_i111:cb(4)" )
			)
			( pin "J1G2.192"
				( objectStatus "@baseboard_fab2_lib.baseboard_fab2(sch_1):page79_i111:cb(5)" )
			)
			( pin "J1G2.54"
				( objectStatus "@baseboard_fab2_lib.baseboard_fab2(sch_1):page79_i111:cb(6)" )
			)
			( pin "J1G2.199"
				( objectStatus "@baseboard_fab2_lib.baseboard_fab2(sch_1):page79_i111:cb(7)" )
			)
			( pin "J1G2.75"
				( objectStatus "@baseboard_fab2_lib.baseboard_fab2(sch_1):page79_i111:ck0n" )
			)
			( pin "J1G2.74"
				( objectStatus "@baseboard_fab2_lib.baseboard_fab2(sch_1):page79_i111:ck0p" )
			)
			( pin "J1G2.219"
				( objectStatus "@baseboard_fab2_lib.baseboard_fab2(sch_1):page79_i111:ck1n" )
			)
			( pin "J1G2.218"
				( objectStatus "@baseboard_fab2_lib.baseboard_fab2(sch_1):page79_i111:ck1p" )
			)
			( pin "J1G2.60"
				( objectStatus "@baseboard_fab2_lib.baseboard_fab2(sch_1):page79_i111:cke(0)" )
			)
			( pin "J1G2.203"
				( objectStatus "@baseboard_fab2_lib.baseboard_fab2(sch_1):page79_i111:cke(1)" )
			)
			( pin "J1G2.5"
				( objectStatus "@baseboard_fab2_lib.baseboard_fab2(sch_1):page79_i111:dq(0)" )
			)
			( pin "J1G2.150"
				( objectStatus "@baseboard_fab2_lib.baseboard_fab2(sch_1):page79_i111:dq(1)" )
			)
			( pin "J1G2.12"
				( objectStatus "@baseboard_fab2_lib.baseboard_fab2(sch_1):page79_i111:dq(2)" )
			)
			( pin "J1G2.157"
				( objectStatus "@baseboard_fab2_lib.baseboard_fab2(sch_1):page79_i111:dq(3)" )
			)
			( pin "J1G2.3"
				( objectStatus "@baseboard_fab2_lib.baseboard_fab2(sch_1):page79_i111:dq(4)" )
			)
			( pin "J1G2.148"
				( objectStatus "@baseboard_fab2_lib.baseboard_fab2(sch_1):page79_i111:dq(5)" )
			)
			( pin "J1G2.10"
				( objectStatus "@baseboard_fab2_lib.baseboard_fab2(sch_1):page79_i111:dq(6)" )
			)
			( pin "J1G2.155"
				( objectStatus "@baseboard_fab2_lib.baseboard_fab2(sch_1):page79_i111:dq(7)" )
			)
			( pin "J1G2.16"
				( objectStatus "@baseboard_fab2_lib.baseboard_fab2(sch_1):page79_i111:dq(8)" )
			)
			( pin "J1G2.161"
				( objectStatus "@baseboard_fab2_lib.baseboard_fab2(sch_1):page79_i111:dq(9)" )
			)
			( pin "J1G2.23"
				( objectStatus "@baseboard_fab2_lib.baseboard_fab2(sch_1):page79_i111:dq(10)" )
			)
			( pin "J1G2.168"
				( objectStatus "@baseboard_fab2_lib.baseboard_fab2(sch_1):page79_i111:dq(11)" )
			)
			( pin "J1G2.14"
				( objectStatus "@baseboard_fab2_lib.baseboard_fab2(sch_1):page79_i111:dq(12)" )
			)
			( pin "J1G2.159"
				( objectStatus "@baseboard_fab2_lib.baseboard_fab2(sch_1):page79_i111:dq(13)" )
			)
			( pin "J1G2.21"
				( objectStatus "@baseboard_fab2_lib.baseboard_fab2(sch_1):page79_i111:dq(14)" )
			)
			( pin "J1G2.166"
				( objectStatus "@baseboard_fab2_lib.baseboard_fab2(sch_1):page79_i111:dq(15)" )
			)
			( pin "J1G2.27"
				( objectStatus "@baseboard_fab2_lib.baseboard_fab2(sch_1):page79_i111:dq(16)" )
			)
			( pin "J1G2.172"
				( objectStatus "@baseboard_fab2_lib.baseboard_fab2(sch_1):page79_i111:dq(17)" )
			)
			( pin "J1G2.34"
				( objectStatus "@baseboard_fab2_lib.baseboard_fab2(sch_1):page79_i111:dq(18)" )
			)
			( pin "J1G2.179"
				( objectStatus "@baseboard_fab2_lib.baseboard_fab2(sch_1):page79_i111:dq(19)" )
			)
			( pin "J1G2.25"
				( objectStatus "@baseboard_fab2_lib.baseboard_fab2(sch_1):page79_i111:dq(20)" )
			)
			( pin "J1G2.170"
				( objectStatus "@baseboard_fab2_lib.baseboard_fab2(sch_1):page79_i111:dq(21)" )
			)
			( pin "J1G2.32"
				( objectStatus "@baseboard_fab2_lib.baseboard_fab2(sch_1):page79_i111:dq(22)" )
			)
			( pin "J1G2.177"
				( objectStatus "@baseboard_fab2_lib.baseboard_fab2(sch_1):page79_i111:dq(23)" )
			)
			( pin "J1G2.38"
				( objectStatus "@baseboard_fab2_lib.baseboard_fab2(sch_1):page79_i111:dq(24)" )
			)
			( pin "J1G2.183"
				( objectStatus "@baseboard_fab2_lib.baseboard_fab2(sch_1):page79_i111:dq(25)" )
			)
			( pin "J1G2.45"
				( objectStatus "@baseboard_fab2_lib.baseboard_fab2(sch_1):page79_i111:dq(26)" )
			)
			( pin "J1G2.190"
				( objectStatus "@baseboard_fab2_lib.baseboard_fab2(sch_1):page79_i111:dq(27)" )
			)
			( pin "J1G2.36"
				( objectStatus "@baseboard_fab2_lib.baseboard_fab2(sch_1):page79_i111:dq(28)" )
			)
			( pin "J1G2.181"
				( objectStatus "@baseboard_fab2_lib.baseboard_fab2(sch_1):page79_i111:dq(29)" )
			)
			( pin "J1G2.43"
				( objectStatus "@baseboard_fab2_lib.baseboard_fab2(sch_1):page79_i111:dq(30)" )
			)
			( pin "J1G2.188"
				( objectStatus "@baseboard_fab2_lib.baseboard_fab2(sch_1):page79_i111:dq(31)" )
			)
			( pin "J1G2.97"
				( objectStatus "@baseboard_fab2_lib.baseboard_fab2(sch_1):page79_i111:dq(32)" )
			)
			( pin "J1G2.242"
				( objectStatus "@baseboard_fab2_lib.baseboard_fab2(sch_1):page79_i111:dq(33)" )
			)
			( pin "J1G2.104"
				( objectStatus "@baseboard_fab2_lib.baseboard_fab2(sch_1):page79_i111:dq(34)" )
			)
			( pin "J1G2.249"
				( objectStatus "@baseboard_fab2_lib.baseboard_fab2(sch_1):page79_i111:dq(35)" )
			)
			( pin "J1G2.95"
				( objectStatus "@baseboard_fab2_lib.baseboard_fab2(sch_1):page79_i111:dq(36)" )
			)
			( pin "J1G2.240"
				( objectStatus "@baseboard_fab2_lib.baseboard_fab2(sch_1):page79_i111:dq(37)" )
			)
			( pin "J1G2.102"
				( objectStatus "@baseboard_fab2_lib.baseboard_fab2(sch_1):page79_i111:dq(38)" )
			)
			( pin "J1G2.247"
				( objectStatus "@baseboard_fab2_lib.baseboard_fab2(sch_1):page79_i111:dq(39)" )
			)
			( pin "J1G2.108"
				( objectStatus "@baseboard_fab2_lib.baseboard_fab2(sch_1):page79_i111:dq(40)" )
			)
			( pin "J1G2.253"
				( objectStatus "@baseboard_fab2_lib.baseboard_fab2(sch_1):page79_i111:dq(41)" )
			)
			( pin "J1G2.115"
				( objectStatus "@baseboard_fab2_lib.baseboard_fab2(sch_1):page79_i111:dq(42)" )
			)
			( pin "J1G2.260"
				( objectStatus "@baseboard_fab2_lib.baseboard_fab2(sch_1):page79_i111:dq(43)" )
			)
			( pin "J1G2.106"
				( objectStatus "@baseboard_fab2_lib.baseboard_fab2(sch_1):page79_i111:dq(44)" )
			)
			( pin "J1G2.251"
				( objectStatus "@baseboard_fab2_lib.baseboard_fab2(sch_1):page79_i111:dq(45)" )
			)
			( pin "J1G2.113"
				( objectStatus "@baseboard_fab2_lib.baseboard_fab2(sch_1):page79_i111:dq(46)" )
			)
			( pin "J1G2.258"
				( objectStatus "@baseboard_fab2_lib.baseboard_fab2(sch_1):page79_i111:dq(47)" )
			)
			( pin "J1G2.119"
				( objectStatus "@baseboard_fab2_lib.baseboard_fab2(sch_1):page79_i111:dq(48)" )
			)
			( pin "J1G2.264"
				( objectStatus "@baseboard_fab2_lib.baseboard_fab2(sch_1):page79_i111:dq(49)" )
			)
			( pin "J1G2.126"
				( objectStatus "@baseboard_fab2_lib.baseboard_fab2(sch_1):page79_i111:dq(50)" )
			)
			( pin "J1G2.271"
				( objectStatus "@baseboard_fab2_lib.baseboard_fab2(sch_1):page79_i111:dq(51)" )
			)
			( pin "J1G2.117"
				( objectStatus "@baseboard_fab2_lib.baseboard_fab2(sch_1):page79_i111:dq(52)" )
			)
			( pin "J1G2.262"
				( objectStatus "@baseboard_fab2_lib.baseboard_fab2(sch_1):page79_i111:dq(53)" )
			)
			( pin "J1G2.124"
				( objectStatus "@baseboard_fab2_lib.baseboard_fab2(sch_1):page79_i111:dq(54)" )
			)
			( pin "J1G2.269"
				( objectStatus "@baseboard_fab2_lib.baseboard_fab2(sch_1):page79_i111:dq(55)" )
			)
			( pin "J1G2.130"
				( objectStatus "@baseboard_fab2_lib.baseboard_fab2(sch_1):page79_i111:dq(56)" )
			)
			( pin "J1G2.275"
				( objectStatus "@baseboard_fab2_lib.baseboard_fab2(sch_1):page79_i111:dq(57)" )
			)
			( pin "J1G2.137"
				( objectStatus "@baseboard_fab2_lib.baseboard_fab2(sch_1):page79_i111:dq(58)" )
			)
			( pin "J1G2.282"
				( objectStatus "@baseboard_fab2_lib.baseboard_fab2(sch_1):page79_i111:dq(59)" )
			)
			( pin "J1G2.128"
				( objectStatus "@baseboard_fab2_lib.baseboard_fab2(sch_1):page79_i111:dq(60)" )
			)
			( pin "J1G2.273"
				( objectStatus "@baseboard_fab2_lib.baseboard_fab2(sch_1):page79_i111:dq(61)" )
			)
			( pin "J1G2.135"
				( objectStatus "@baseboard_fab2_lib.baseboard_fab2(sch_1):page79_i111:dq(62)" )
			)
			( pin "J1G2.280"
				( objectStatus "@baseboard_fab2_lib.baseboard_fab2(sch_1):page79_i111:dq(63)" )
			)
			( pin "J1G2.78"
				( objectStatus "@baseboard_fab2_lib.baseboard_fab2(sch_1):page79_i111:event_n" )
			)
			( pin "J1G2.87"
				( objectStatus "@baseboard_fab2_lib.baseboard_fab2(sch_1):page79_i111:odt(0)" )
			)
			( pin "J1G2.91"
				( objectStatus "@baseboard_fab2_lib.baseboard_fab2(sch_1):page79_i111:odt(1)" )
			)
			( pin "J1G2.222"
				( objectStatus "@baseboard_fab2_lib.baseboard_fab2(sch_1):page79_i111:par" )
			)
			( pin "J1G2.58"
				( objectStatus "@baseboard_fab2_lib.baseboard_fab2(sch_1):page79_i111:reset_n" )
			)
			( pin "J1G2.205"
				( objectStatus "@baseboard_fab2_lib.baseboard_fab2(sch_1):page79_i111:rfu(0)" )
			)
			( pin "J1G2.227"
				( objectStatus "@baseboard_fab2_lib.baseboard_fab2(sch_1):page79_i111:rfu(1)" )
			)
			( pin "J1G2.144"
				( objectStatus "@baseboard_fab2_lib.baseboard_fab2(sch_1):page79_i111:rfu(2)" )
			)
			( pin "J1G2.84"
				( objectStatus "@baseboard_fab2_lib.baseboard_fab2(sch_1):page79_i111:s0_n" )
			)
			( pin "J1G2.89"
				( objectStatus "@baseboard_fab2_lib.baseboard_fab2(sch_1):page79_i111:s1_n" )
			)
			( pin "J1G2.93"
				( objectStatus "@baseboard_fab2_lib.baseboard_fab2(sch_1):page79_i111:s2_n_c(0)" )
			)
			( pin "J1G2.237"
				( objectStatus "@baseboard_fab2_lib.baseboard_fab2(sch_1):page79_i111:s3_n_c(1)" )
			)
			( pin "J1G2.139"
				( objectStatus "@baseboard_fab2_lib.baseboard_fab2(sch_1):page79_i111:sa(0)" )
			)
			( pin "J1G2.140"
				( objectStatus "@baseboard_fab2_lib.baseboard_fab2(sch_1):page79_i111:sa(1)" )
			)
			( pin "J1G2.238"
				( objectStatus "@baseboard_fab2_lib.baseboard_fab2(sch_1):page79_i111:sa(2)" )
			)
			( pin "J1G2.230"
				( objectStatus "@baseboard_fab2_lib.baseboard_fab2(sch_1):page79_i111:save_n_nc" )
			)
			( pin "J1G2.141"
				( objectStatus "@baseboard_fab2_lib.baseboard_fab2(sch_1):page79_i111:scl" )
			)
			( pin "J1G2.285"
				( objectStatus "@baseboard_fab2_lib.baseboard_fab2(sch_1):page79_i111:sda" )
			)
			( pin "J1G2.284"
				( objectStatus "@baseboard_fab2_lib.baseboard_fab2(sch_1):page79_i111:vddspd" )
			)
			( pin "J1G2.146"
				( objectStatus "@baseboard_fab2_lib.baseboard_fab2(sch_1):page79_i111:vrefca" )
			)
			( pin "J1G2.145"
				( objectStatus "@baseboard_fab2_lib.baseboard_fab2(sch_1):page79_i169:\12v\(0)" )
			)
			( pin "J1G2.1"
				( objectStatus "@baseboard_fab2_lib.baseboard_fab2(sch_1):page79_i169:\12v\(1)" )
			)
			( pin "J1G2.236"
				( objectStatus "@baseboard_fab2_lib.baseboard_fab2(sch_1):page79_i169:vdd(0)" )
			)
			( pin "J1G2.233"
				( objectStatus "@baseboard_fab2_lib.baseboard_fab2(sch_1):page79_i169:vdd(1)" )
			)
			( pin "J1G2.231"
				( objectStatus "@baseboard_fab2_lib.baseboard_fab2(sch_1):page79_i169:vdd(2)" )
			)
			( pin "J1G2.229"
				( objectStatus "@baseboard_fab2_lib.baseboard_fab2(sch_1):page79_i169:vdd(3)" )
			)
			( pin "J1G2.226"
				( objectStatus "@baseboard_fab2_lib.baseboard_fab2(sch_1):page79_i169:vdd(4)" )
			)
			( pin "J1G2.223"
				( objectStatus "@baseboard_fab2_lib.baseboard_fab2(sch_1):page79_i169:vdd(5)" )
			)
			( pin "J1G2.220"
				( objectStatus "@baseboard_fab2_lib.baseboard_fab2(sch_1):page79_i169:vdd(6)" )
			)
			( pin "J1G2.217"
				( objectStatus "@baseboard_fab2_lib.baseboard_fab2(sch_1):page79_i169:vdd(7)" )
			)
			( pin "J1G2.215"
				( objectStatus "@baseboard_fab2_lib.baseboard_fab2(sch_1):page79_i169:vdd(8)" )
			)
			( pin "J1G2.212"
				( objectStatus "@baseboard_fab2_lib.baseboard_fab2(sch_1):page79_i169:vdd(9)" )
			)
			( pin "J1G2.209"
				( objectStatus "@baseboard_fab2_lib.baseboard_fab2(sch_1):page79_i169:vdd(10)" )
			)
			( pin "J1G2.206"
				( objectStatus "@baseboard_fab2_lib.baseboard_fab2(sch_1):page79_i169:vdd(11)" )
			)
			( pin "J1G2.204"
				( objectStatus "@baseboard_fab2_lib.baseboard_fab2(sch_1):page79_i169:vdd(12)" )
			)
			( pin "J1G2.92"
				( objectStatus "@baseboard_fab2_lib.baseboard_fab2(sch_1):page79_i169:vdd(13)" )
			)
			( pin "J1G2.90"
				( objectStatus "@baseboard_fab2_lib.baseboard_fab2(sch_1):page79_i169:vdd(14)" )
			)
			( pin "J1G2.88"
				( objectStatus "@baseboard_fab2_lib.baseboard_fab2(sch_1):page79_i169:vdd(15)" )
			)
			( pin "J1G2.85"
				( objectStatus "@baseboard_fab2_lib.baseboard_fab2(sch_1):page79_i169:vdd(16)" )
			)
			( pin "J1G2.83"
				( objectStatus "@baseboard_fab2_lib.baseboard_fab2(sch_1):page79_i169:vdd(17)" )
			)
			( pin "J1G2.80"
				( objectStatus "@baseboard_fab2_lib.baseboard_fab2(sch_1):page79_i169:vdd(18)" )
			)
			( pin "J1G2.76"
				( objectStatus "@baseboard_fab2_lib.baseboard_fab2(sch_1):page79_i169:vdd(19)" )
			)
			( pin "J1G2.73"
				( objectStatus "@baseboard_fab2_lib.baseboard_fab2(sch_1):page79_i169:vdd(20)" )
			)
			( pin "J1G2.70"
				( objectStatus "@baseboard_fab2_lib.baseboard_fab2(sch_1):page79_i169:vdd(21)" )
			)
			( pin "J1G2.67"
				( objectStatus "@baseboard_fab2_lib.baseboard_fab2(sch_1):page79_i169:vdd(22)" )
			)
			( pin "J1G2.64"
				( objectStatus "@baseboard_fab2_lib.baseboard_fab2(sch_1):page79_i169:vdd(23)" )
			)
			( pin "J1G2.61"
				( objectStatus "@baseboard_fab2_lib.baseboard_fab2(sch_1):page79_i169:vdd(24)" )
			)
			( pin "J1G2.59"
				( objectStatus "@baseboard_fab2_lib.baseboard_fab2(sch_1):page79_i169:vdd(25)" )
			)
			( pin "J1G2.287"
				( objectStatus "@baseboard_fab2_lib.baseboard_fab2(sch_1):page79_i169:vpp(0)" )
			)
			( pin "J1G2.286"
				( objectStatus "@baseboard_fab2_lib.baseboard_fab2(sch_1):page79_i169:vpp(1)" )
			)
			( pin "J1G2.288"
				( objectStatus "@baseboard_fab2_lib.baseboard_fab2(sch_1):page79_i169:vpp(2)" )
			)
			( pin "J1G2.143"
				( objectStatus "@baseboard_fab2_lib.baseboard_fab2(sch_1):page79_i169:vpp(3)" )
			)
			( pin "J1G2.142"
				( objectStatus "@baseboard_fab2_lib.baseboard_fab2(sch_1):page79_i169:vpp(4)" )
			)
			( pin "J1G2.221"
				( objectStatus "@baseboard_fab2_lib.baseboard_fab2(sch_1):page79_i169:vtt(0)" )
			)
			( pin "J1G2.77"
				( objectStatus "@baseboard_fab2_lib.baseboard_fab2(sch_1):page79_i169:vtt(1)" )
			)
			( pin "C9U7.1"
				( objectStatus "@baseboard_fab2_lib.baseboard_fab2(sch_1):page79_i178:a" )
			)
			( pin "C9U7.2"
				( objectStatus "@baseboard_fab2_lib.baseboard_fab2(sch_1):page79_i178:b" )
			)
			( pin "C1G10.1"
				( objectStatus "@baseboard_fab2_lib.baseboard_fab2(sch_1):page80_i3:a" )
			)
			( pin "C1G10.2"
				( objectStatus "@baseboard_fab2_lib.baseboard_fab2(sch_1):page80_i3:b" )
			)
			( pin "J9U1.79"
				( objectStatus "@baseboard_fab2_lib.baseboard_fab2(sch_1):page80_i24:a0" )
			)
			( pin "J9U1.72"
				( objectStatus "@baseboard_fab2_lib.baseboard_fab2(sch_1):page80_i24:a1" )
			)
			( pin "J9U1.216"
				( objectStatus "@baseboard_fab2_lib.baseboard_fab2(sch_1):page80_i24:a2" )
			)
			( pin "J9U1.71"
				( objectStatus "@baseboard_fab2_lib.baseboard_fab2(sch_1):page80_i24:a3" )
			)
			( pin "J9U1.214"
				( objectStatus "@baseboard_fab2_lib.baseboard_fab2(sch_1):page80_i24:a4" )
			)
			( pin "J9U1.213"
				( objectStatus "@baseboard_fab2_lib.baseboard_fab2(sch_1):page80_i24:a5" )
			)
			( pin "J9U1.69"
				( objectStatus "@baseboard_fab2_lib.baseboard_fab2(sch_1):page80_i24:a6" )
			)
			( pin "J9U1.211"
				( objectStatus "@baseboard_fab2_lib.baseboard_fab2(sch_1):page80_i24:a7" )
			)
			( pin "J9U1.68"
				( objectStatus "@baseboard_fab2_lib.baseboard_fab2(sch_1):page80_i24:a8" )
			)
			( pin "J9U1.66"
				( objectStatus "@baseboard_fab2_lib.baseboard_fab2(sch_1):page80_i24:a9" )
			)
			( pin "J9U1.225"
				( objectStatus "@baseboard_fab2_lib.baseboard_fab2(sch_1):page80_i24:a10" )
			)
			( pin "J9U1.210"
				( objectStatus "@baseboard_fab2_lib.baseboard_fab2(sch_1):page80_i24:a11" )
			)
			( pin "J9U1.65"
				( objectStatus "@baseboard_fab2_lib.baseboard_fab2(sch_1):page80_i24:a12" )
			)
			( pin "J9U1.232"
				( objectStatus "@baseboard_fab2_lib.baseboard_fab2(sch_1):page80_i24:a13" )
			)
			( pin "J9U1.228"
				( objectStatus "@baseboard_fab2_lib.baseboard_fab2(sch_1):page80_i24:a14_we_n" )
			)
			( pin "J9U1.86"
				( objectStatus "@baseboard_fab2_lib.baseboard_fab2(sch_1):page80_i24:a15_cas_n" )
			)
			( pin "J9U1.82"
				( objectStatus "@baseboard_fab2_lib.baseboard_fab2(sch_1):page80_i24:a16_ras_n" )
			)
			( pin "J9U1.234"
				( objectStatus "@baseboard_fab2_lib.baseboard_fab2(sch_1):page80_i24:a17" )
			)
			( pin "J9U1.62"
				( objectStatus "@baseboard_fab2_lib.baseboard_fab2(sch_1):page80_i24:act_n" )
			)
			( pin "J9U1.208"
				( objectStatus "@baseboard_fab2_lib.baseboard_fab2(sch_1):page80_i24:alert_n" )
			)
			( pin "J9U1.81"
				( objectStatus "@baseboard_fab2_lib.baseboard_fab2(sch_1):page80_i24:ba(0)" )
			)
			( pin "J9U1.224"
				( objectStatus "@baseboard_fab2_lib.baseboard_fab2(sch_1):page80_i24:ba(1)" )
			)
			( pin "J9U1.63"
				( objectStatus "@baseboard_fab2_lib.baseboard_fab2(sch_1):page80_i24:bg(0)" )
			)
			( pin "J9U1.207"
				( objectStatus "@baseboard_fab2_lib.baseboard_fab2(sch_1):page80_i24:bg(1)" )
			)
			( pin "J9U1.235"
				( objectStatus "@baseboard_fab2_lib.baseboard_fab2(sch_1):page80_i24:c(2)" )
			)
			( pin "J9U1.49"
				( objectStatus "@baseboard_fab2_lib.baseboard_fab2(sch_1):page80_i24:cb(0)" )
			)
			( pin "J9U1.194"
				( objectStatus "@baseboard_fab2_lib.baseboard_fab2(sch_1):page80_i24:cb(1)" )
			)
			( pin "J9U1.56"
				( objectStatus "@baseboard_fab2_lib.baseboard_fab2(sch_1):page80_i24:cb(2)" )
			)
			( pin "J9U1.201"
				( objectStatus "@baseboard_fab2_lib.baseboard_fab2(sch_1):page80_i24:cb(3)" )
			)
			( pin "J9U1.47"
				( objectStatus "@baseboard_fab2_lib.baseboard_fab2(sch_1):page80_i24:cb(4)" )
			)
			( pin "J9U1.192"
				( objectStatus "@baseboard_fab2_lib.baseboard_fab2(sch_1):page80_i24:cb(5)" )
			)
			( pin "J9U1.54"
				( objectStatus "@baseboard_fab2_lib.baseboard_fab2(sch_1):page80_i24:cb(6)" )
			)
			( pin "J9U1.199"
				( objectStatus "@baseboard_fab2_lib.baseboard_fab2(sch_1):page80_i24:cb(7)" )
			)
			( pin "J9U1.75"
				( objectStatus "@baseboard_fab2_lib.baseboard_fab2(sch_1):page80_i24:ck0n" )
			)
			( pin "J9U1.74"
				( objectStatus "@baseboard_fab2_lib.baseboard_fab2(sch_1):page80_i24:ck0p" )
			)
			( pin "J9U1.219"
				( objectStatus "@baseboard_fab2_lib.baseboard_fab2(sch_1):page80_i24:ck1n" )
			)
			( pin "J9U1.218"
				( objectStatus "@baseboard_fab2_lib.baseboard_fab2(sch_1):page80_i24:ck1p" )
			)
			( pin "J9U1.60"
				( objectStatus "@baseboard_fab2_lib.baseboard_fab2(sch_1):page80_i24:cke(0)" )
			)
			( pin "J9U1.203"
				( objectStatus "@baseboard_fab2_lib.baseboard_fab2(sch_1):page80_i24:cke(1)" )
			)
			( pin "J9U1.5"
				( objectStatus "@baseboard_fab2_lib.baseboard_fab2(sch_1):page80_i24:dq(0)" )
			)
			( pin "J9U1.150"
				( objectStatus "@baseboard_fab2_lib.baseboard_fab2(sch_1):page80_i24:dq(1)" )
			)
			( pin "J9U1.12"
				( objectStatus "@baseboard_fab2_lib.baseboard_fab2(sch_1):page80_i24:dq(2)" )
			)
			( pin "J9U1.157"
				( objectStatus "@baseboard_fab2_lib.baseboard_fab2(sch_1):page80_i24:dq(3)" )
			)
			( pin "J9U1.3"
				( objectStatus "@baseboard_fab2_lib.baseboard_fab2(sch_1):page80_i24:dq(4)" )
			)
			( pin "J9U1.148"
				( objectStatus "@baseboard_fab2_lib.baseboard_fab2(sch_1):page80_i24:dq(5)" )
			)
			( pin "J9U1.10"
				( objectStatus "@baseboard_fab2_lib.baseboard_fab2(sch_1):page80_i24:dq(6)" )
			)
			( pin "J9U1.155"
				( objectStatus "@baseboard_fab2_lib.baseboard_fab2(sch_1):page80_i24:dq(7)" )
			)
			( pin "J9U1.16"
				( objectStatus "@baseboard_fab2_lib.baseboard_fab2(sch_1):page80_i24:dq(8)" )
			)
			( pin "J9U1.161"
				( objectStatus "@baseboard_fab2_lib.baseboard_fab2(sch_1):page80_i24:dq(9)" )
			)
			( pin "J9U1.23"
				( objectStatus "@baseboard_fab2_lib.baseboard_fab2(sch_1):page80_i24:dq(10)" )
			)
			( pin "J9U1.168"
				( objectStatus "@baseboard_fab2_lib.baseboard_fab2(sch_1):page80_i24:dq(11)" )
			)
			( pin "J9U1.14"
				( objectStatus "@baseboard_fab2_lib.baseboard_fab2(sch_1):page80_i24:dq(12)" )
			)
			( pin "J9U1.159"
				( objectStatus "@baseboard_fab2_lib.baseboard_fab2(sch_1):page80_i24:dq(13)" )
			)
			( pin "J9U1.21"
				( objectStatus "@baseboard_fab2_lib.baseboard_fab2(sch_1):page80_i24:dq(14)" )
			)
			( pin "J9U1.166"
				( objectStatus "@baseboard_fab2_lib.baseboard_fab2(sch_1):page80_i24:dq(15)" )
			)
			( pin "J9U1.27"
				( objectStatus "@baseboard_fab2_lib.baseboard_fab2(sch_1):page80_i24:dq(16)" )
			)
			( pin "J9U1.172"
				( objectStatus "@baseboard_fab2_lib.baseboard_fab2(sch_1):page80_i24:dq(17)" )
			)
			( pin "J9U1.34"
				( objectStatus "@baseboard_fab2_lib.baseboard_fab2(sch_1):page80_i24:dq(18)" )
			)
			( pin "J9U1.179"
				( objectStatus "@baseboard_fab2_lib.baseboard_fab2(sch_1):page80_i24:dq(19)" )
			)
			( pin "J9U1.25"
				( objectStatus "@baseboard_fab2_lib.baseboard_fab2(sch_1):page80_i24:dq(20)" )
			)
			( pin "J9U1.170"
				( objectStatus "@baseboard_fab2_lib.baseboard_fab2(sch_1):page80_i24:dq(21)" )
			)
			( pin "J9U1.32"
				( objectStatus "@baseboard_fab2_lib.baseboard_fab2(sch_1):page80_i24:dq(22)" )
			)
			( pin "J9U1.177"
				( objectStatus "@baseboard_fab2_lib.baseboard_fab2(sch_1):page80_i24:dq(23)" )
			)
			( pin "J9U1.38"
				( objectStatus "@baseboard_fab2_lib.baseboard_fab2(sch_1):page80_i24:dq(24)" )
			)
			( pin "J9U1.183"
				( objectStatus "@baseboard_fab2_lib.baseboard_fab2(sch_1):page80_i24:dq(25)" )
			)
			( pin "J9U1.45"
				( objectStatus "@baseboard_fab2_lib.baseboard_fab2(sch_1):page80_i24:dq(26)" )
			)
			( pin "J9U1.190"
				( objectStatus "@baseboard_fab2_lib.baseboard_fab2(sch_1):page80_i24:dq(27)" )
			)
			( pin "J9U1.36"
				( objectStatus "@baseboard_fab2_lib.baseboard_fab2(sch_1):page80_i24:dq(28)" )
			)
			( pin "J9U1.181"
				( objectStatus "@baseboard_fab2_lib.baseboard_fab2(sch_1):page80_i24:dq(29)" )
			)
			( pin "J9U1.43"
				( objectStatus "@baseboard_fab2_lib.baseboard_fab2(sch_1):page80_i24:dq(30)" )
			)
			( pin "J9U1.188"
				( objectStatus "@baseboard_fab2_lib.baseboard_fab2(sch_1):page80_i24:dq(31)" )
			)
			( pin "J9U1.97"
				( objectStatus "@baseboard_fab2_lib.baseboard_fab2(sch_1):page80_i24:dq(32)" )
			)
			( pin "J9U1.242"
				( objectStatus "@baseboard_fab2_lib.baseboard_fab2(sch_1):page80_i24:dq(33)" )
			)
			( pin "J9U1.104"
				( objectStatus "@baseboard_fab2_lib.baseboard_fab2(sch_1):page80_i24:dq(34)" )
			)
			( pin "J9U1.249"
				( objectStatus "@baseboard_fab2_lib.baseboard_fab2(sch_1):page80_i24:dq(35)" )
			)
			( pin "J9U1.95"
				( objectStatus "@baseboard_fab2_lib.baseboard_fab2(sch_1):page80_i24:dq(36)" )
			)
			( pin "J9U1.240"
				( objectStatus "@baseboard_fab2_lib.baseboard_fab2(sch_1):page80_i24:dq(37)" )
			)
			( pin "J9U1.102"
				( objectStatus "@baseboard_fab2_lib.baseboard_fab2(sch_1):page80_i24:dq(38)" )
			)
			( pin "J9U1.247"
				( objectStatus "@baseboard_fab2_lib.baseboard_fab2(sch_1):page80_i24:dq(39)" )
			)
			( pin "J9U1.108"
				( objectStatus "@baseboard_fab2_lib.baseboard_fab2(sch_1):page80_i24:dq(40)" )
			)
			( pin "J9U1.253"
				( objectStatus "@baseboard_fab2_lib.baseboard_fab2(sch_1):page80_i24:dq(41)" )
			)
			( pin "J9U1.115"
				( objectStatus "@baseboard_fab2_lib.baseboard_fab2(sch_1):page80_i24:dq(42)" )
			)
			( pin "J9U1.260"
				( objectStatus "@baseboard_fab2_lib.baseboard_fab2(sch_1):page80_i24:dq(43)" )
			)
			( pin "J9U1.106"
				( objectStatus "@baseboard_fab2_lib.baseboard_fab2(sch_1):page80_i24:dq(44)" )
			)
			( pin "J9U1.251"
				( objectStatus "@baseboard_fab2_lib.baseboard_fab2(sch_1):page80_i24:dq(45)" )
			)
			( pin "J9U1.113"
				( objectStatus "@baseboard_fab2_lib.baseboard_fab2(sch_1):page80_i24:dq(46)" )
			)
			( pin "J9U1.258"
				( objectStatus "@baseboard_fab2_lib.baseboard_fab2(sch_1):page80_i24:dq(47)" )
			)
			( pin "J9U1.119"
				( objectStatus "@baseboard_fab2_lib.baseboard_fab2(sch_1):page80_i24:dq(48)" )
			)
			( pin "J9U1.264"
				( objectStatus "@baseboard_fab2_lib.baseboard_fab2(sch_1):page80_i24:dq(49)" )
			)
			( pin "J9U1.126"
				( objectStatus "@baseboard_fab2_lib.baseboard_fab2(sch_1):page80_i24:dq(50)" )
			)
			( pin "J9U1.271"
				( objectStatus "@baseboard_fab2_lib.baseboard_fab2(sch_1):page80_i24:dq(51)" )
			)
			( pin "J9U1.117"
				( objectStatus "@baseboard_fab2_lib.baseboard_fab2(sch_1):page80_i24:dq(52)" )
			)
			( pin "J9U1.262"
				( objectStatus "@baseboard_fab2_lib.baseboard_fab2(sch_1):page80_i24:dq(53)" )
			)
			( pin "J9U1.124"
				( objectStatus "@baseboard_fab2_lib.baseboard_fab2(sch_1):page80_i24:dq(54)" )
			)
			( pin "J9U1.269"
				( objectStatus "@baseboard_fab2_lib.baseboard_fab2(sch_1):page80_i24:dq(55)" )
			)
			( pin "J9U1.130"
				( objectStatus "@baseboard_fab2_lib.baseboard_fab2(sch_1):page80_i24:dq(56)" )
			)
			( pin "J9U1.275"
				( objectStatus "@baseboard_fab2_lib.baseboard_fab2(sch_1):page80_i24:dq(57)" )
			)
			( pin "J9U1.137"
				( objectStatus "@baseboard_fab2_lib.baseboard_fab2(sch_1):page80_i24:dq(58)" )
			)
			( pin "J9U1.282"
				( objectStatus "@baseboard_fab2_lib.baseboard_fab2(sch_1):page80_i24:dq(59)" )
			)
			( pin "J9U1.128"
				( objectStatus "@baseboard_fab2_lib.baseboard_fab2(sch_1):page80_i24:dq(60)" )
			)
			( pin "J9U1.273"
				( objectStatus "@baseboard_fab2_lib.baseboard_fab2(sch_1):page80_i24:dq(61)" )
			)
			( pin "J9U1.135"
				( objectStatus "@baseboard_fab2_lib.baseboard_fab2(sch_1):page80_i24:dq(62)" )
			)
			( pin "J9U1.280"
				( objectStatus "@baseboard_fab2_lib.baseboard_fab2(sch_1):page80_i24:dq(63)" )
			)
			( pin "J9U1.78"
				( objectStatus "@baseboard_fab2_lib.baseboard_fab2(sch_1):page80_i24:event_n" )
			)
			( pin "J9U1.87"
				( objectStatus "@baseboard_fab2_lib.baseboard_fab2(sch_1):page80_i24:odt(0)" )
			)
			( pin "J9U1.91"
				( objectStatus "@baseboard_fab2_lib.baseboard_fab2(sch_1):page80_i24:odt(1)" )
			)
			( pin "J9U1.222"
				( objectStatus "@baseboard_fab2_lib.baseboard_fab2(sch_1):page80_i24:par" )
			)
			( pin "J9U1.58"
				( objectStatus "@baseboard_fab2_lib.baseboard_fab2(sch_1):page80_i24:reset_n" )
			)
			( pin "J9U1.205"
				( objectStatus "@baseboard_fab2_lib.baseboard_fab2(sch_1):page80_i24:rfu(0)" )
			)
			( pin "J9U1.227"
				( objectStatus "@baseboard_fab2_lib.baseboard_fab2(sch_1):page80_i24:rfu(1)" )
			)
			( pin "J9U1.144"
				( objectStatus "@baseboard_fab2_lib.baseboard_fab2(sch_1):page80_i24:rfu(2)" )
			)
			( pin "J9U1.84"
				( objectStatus "@baseboard_fab2_lib.baseboard_fab2(sch_1):page80_i24:s0_n" )
			)
			( pin "J9U1.89"
				( objectStatus "@baseboard_fab2_lib.baseboard_fab2(sch_1):page80_i24:s1_n" )
			)
			( pin "J9U1.93"
				( objectStatus "@baseboard_fab2_lib.baseboard_fab2(sch_1):page80_i24:s2_n_c(0)" )
			)
			( pin "J9U1.237"
				( objectStatus "@baseboard_fab2_lib.baseboard_fab2(sch_1):page80_i24:s3_n_c(1)" )
			)
			( pin "J9U1.139"
				( objectStatus "@baseboard_fab2_lib.baseboard_fab2(sch_1):page80_i24:sa(0)" )
			)
			( pin "J9U1.140"
				( objectStatus "@baseboard_fab2_lib.baseboard_fab2(sch_1):page80_i24:sa(1)" )
			)
			( pin "J9U1.238"
				( objectStatus "@baseboard_fab2_lib.baseboard_fab2(sch_1):page80_i24:sa(2)" )
			)
			( pin "J9U1.230"
				( objectStatus "@baseboard_fab2_lib.baseboard_fab2(sch_1):page80_i24:save_n_nc" )
			)
			( pin "J9U1.141"
				( objectStatus "@baseboard_fab2_lib.baseboard_fab2(sch_1):page80_i24:scl" )
			)
			( pin "J9U1.285"
				( objectStatus "@baseboard_fab2_lib.baseboard_fab2(sch_1):page80_i24:sda" )
			)
			( pin "J9U1.284"
				( objectStatus "@baseboard_fab2_lib.baseboard_fab2(sch_1):page80_i24:vddspd" )
			)
			( pin "J9U1.146"
				( objectStatus "@baseboard_fab2_lib.baseboard_fab2(sch_1):page80_i24:vrefca" )
			)
			( pin "J9U1.145"
				( objectStatus "@baseboard_fab2_lib.baseboard_fab2(sch_1):page80_i56:\12v\(0)" )
			)
			( pin "J9U1.1"
				( objectStatus "@baseboard_fab2_lib.baseboard_fab2(sch_1):page80_i56:\12v\(1)" )
			)
			( pin "J9U1.236"
				( objectStatus "@baseboard_fab2_lib.baseboard_fab2(sch_1):page80_i56:vdd(0)" )
			)
			( pin "J9U1.233"
				( objectStatus "@baseboard_fab2_lib.baseboard_fab2(sch_1):page80_i56:vdd(1)" )
			)
			( pin "J9U1.231"
				( objectStatus "@baseboard_fab2_lib.baseboard_fab2(sch_1):page80_i56:vdd(2)" )
			)
			( pin "J9U1.229"
				( objectStatus "@baseboard_fab2_lib.baseboard_fab2(sch_1):page80_i56:vdd(3)" )
			)
			( pin "J9U1.226"
				( objectStatus "@baseboard_fab2_lib.baseboard_fab2(sch_1):page80_i56:vdd(4)" )
			)
			( pin "J9U1.223"
				( objectStatus "@baseboard_fab2_lib.baseboard_fab2(sch_1):page80_i56:vdd(5)" )
			)
			( pin "J9U1.220"
				( objectStatus "@baseboard_fab2_lib.baseboard_fab2(sch_1):page80_i56:vdd(6)" )
			)
			( pin "J9U1.217"
				( objectStatus "@baseboard_fab2_lib.baseboard_fab2(sch_1):page80_i56:vdd(7)" )
			)
			( pin "J9U1.215"
				( objectStatus "@baseboard_fab2_lib.baseboard_fab2(sch_1):page80_i56:vdd(8)" )
			)
			( pin "J9U1.212"
				( objectStatus "@baseboard_fab2_lib.baseboard_fab2(sch_1):page80_i56:vdd(9)" )
			)
			( pin "J9U1.209"
				( objectStatus "@baseboard_fab2_lib.baseboard_fab2(sch_1):page80_i56:vdd(10)" )
			)
			( pin "J9U1.206"
				( objectStatus "@baseboard_fab2_lib.baseboard_fab2(sch_1):page80_i56:vdd(11)" )
			)
			( pin "J9U1.204"
				( objectStatus "@baseboard_fab2_lib.baseboard_fab2(sch_1):page80_i56:vdd(12)" )
			)
			( pin "J9U1.92"
				( objectStatus "@baseboard_fab2_lib.baseboard_fab2(sch_1):page80_i56:vdd(13)" )
			)
			( pin "J9U1.90"
				( objectStatus "@baseboard_fab2_lib.baseboard_fab2(sch_1):page80_i56:vdd(14)" )
			)
			( pin "J9U1.88"
				( objectStatus "@baseboard_fab2_lib.baseboard_fab2(sch_1):page80_i56:vdd(15)" )
			)
			( pin "J9U1.85"
				( objectStatus "@baseboard_fab2_lib.baseboard_fab2(sch_1):page80_i56:vdd(16)" )
			)
			( pin "J9U1.83"
				( objectStatus "@baseboard_fab2_lib.baseboard_fab2(sch_1):page80_i56:vdd(17)" )
			)
			( pin "J9U1.80"
				( objectStatus "@baseboard_fab2_lib.baseboard_fab2(sch_1):page80_i56:vdd(18)" )
			)
			( pin "J9U1.76"
				( objectStatus "@baseboard_fab2_lib.baseboard_fab2(sch_1):page80_i56:vdd(19)" )
			)
			( pin "J9U1.73"
				( objectStatus "@baseboard_fab2_lib.baseboard_fab2(sch_1):page80_i56:vdd(20)" )
			)
			( pin "J9U1.70"
				( objectStatus "@baseboard_fab2_lib.baseboard_fab2(sch_1):page80_i56:vdd(21)" )
			)
			( pin "J9U1.67"
				( objectStatus "@baseboard_fab2_lib.baseboard_fab2(sch_1):page80_i56:vdd(22)" )
			)
			( pin "J9U1.64"
				( objectStatus "@baseboard_fab2_lib.baseboard_fab2(sch_1):page80_i56:vdd(23)" )
			)
			( pin "J9U1.61"
				( objectStatus "@baseboard_fab2_lib.baseboard_fab2(sch_1):page80_i56:vdd(24)" )
			)
			( pin "J9U1.59"
				( objectStatus "@baseboard_fab2_lib.baseboard_fab2(sch_1):page80_i56:vdd(25)" )
			)
			( pin "J9U1.287"
				( objectStatus "@baseboard_fab2_lib.baseboard_fab2(sch_1):page80_i56:vpp(0)" )
			)
			( pin "J9U1.286"
				( objectStatus "@baseboard_fab2_lib.baseboard_fab2(sch_1):page80_i56:vpp(1)" )
			)
			( pin "J9U1.288"
				( objectStatus "@baseboard_fab2_lib.baseboard_fab2(sch_1):page80_i56:vpp(2)" )
			)
			( pin "J9U1.143"
				( objectStatus "@baseboard_fab2_lib.baseboard_fab2(sch_1):page80_i56:vpp(3)" )
			)
			( pin "J9U1.142"
				( objectStatus "@baseboard_fab2_lib.baseboard_fab2(sch_1):page80_i56:vpp(4)" )
			)
			( pin "J9U1.221"
				( objectStatus "@baseboard_fab2_lib.baseboard_fab2(sch_1):page80_i56:vtt(0)" )
			)
			( pin "J9U1.77"
				( objectStatus "@baseboard_fab2_lib.baseboard_fab2(sch_1):page80_i56:vtt(1)" )
			)
			( pin "J9U1.152"
				( objectStatus "@baseboard_fab2_lib.baseboard_fab2(sch_1):page80_i101:dqs0n" )
			)
			( pin "J9U1.153"
				( objectStatus "@baseboard_fab2_lib.baseboard_fab2(sch_1):page80_i101:dqs0p" )
			)
			( pin "J9U1.163"
				( objectStatus "@baseboard_fab2_lib.baseboard_fab2(sch_1):page80_i101:dqs1n" )
			)
			( pin "J9U1.164"
				( objectStatus "@baseboard_fab2_lib.baseboard_fab2(sch_1):page80_i101:dqs1p" )
			)
			( pin "J9U1.174"
				( objectStatus "@baseboard_fab2_lib.baseboard_fab2(sch_1):page80_i101:dqs2n" )
			)
			( pin "J9U1.175"
				( objectStatus "@baseboard_fab2_lib.baseboard_fab2(sch_1):page80_i101:dqs2p" )
			)
			( pin "J9U1.185"
				( objectStatus "@baseboard_fab2_lib.baseboard_fab2(sch_1):page80_i101:dqs3n" )
			)
			( pin "J9U1.186"
				( objectStatus "@baseboard_fab2_lib.baseboard_fab2(sch_1):page80_i101:dqs3p" )
			)
			( pin "J9U1.244"
				( objectStatus "@baseboard_fab2_lib.baseboard_fab2(sch_1):page80_i101:dqs4n" )
			)
			( pin "J9U1.245"
				( objectStatus "@baseboard_fab2_lib.baseboard_fab2(sch_1):page80_i101:dqs4p" )
			)
			( pin "J9U1.255"
				( objectStatus "@baseboard_fab2_lib.baseboard_fab2(sch_1):page80_i101:dqs5n" )
			)
			( pin "J9U1.256"
				( objectStatus "@baseboard_fab2_lib.baseboard_fab2(sch_1):page80_i101:dqs5p" )
			)
			( pin "J9U1.266"
				( objectStatus "@baseboard_fab2_lib.baseboard_fab2(sch_1):page80_i101:dqs6n" )
			)
			( pin "J9U1.267"
				( objectStatus "@baseboard_fab2_lib.baseboard_fab2(sch_1):page80_i101:dqs6p" )
			)
			( pin "J9U1.277"
				( objectStatus "@baseboard_fab2_lib.baseboard_fab2(sch_1):page80_i101:dqs7n" )
			)
			( pin "J9U1.278"
				( objectStatus "@baseboard_fab2_lib.baseboard_fab2(sch_1):page80_i101:dqs7p" )
			)
			( pin "J9U1.196"
				( objectStatus "@baseboard_fab2_lib.baseboard_fab2(sch_1):page80_i101:dqs8n" )
			)
			( pin "J9U1.197"
				( objectStatus "@baseboard_fab2_lib.baseboard_fab2(sch_1):page80_i101:dqs8p" )
			)
			( pin "J9U1.8"
				( objectStatus "@baseboard_fab2_lib.baseboard_fab2(sch_1):page80_i101:dqs9n" )
			)
			( pin "J9U1.7"
				( objectStatus "@baseboard_fab2_lib.baseboard_fab2(sch_1):page80_i101:dqs9p" )
			)
			( pin "J9U1.19"
				( objectStatus "@baseboard_fab2_lib.baseboard_fab2(sch_1):page80_i101:dqs10n" )
			)
			( pin "J9U1.18"
				( objectStatus "@baseboard_fab2_lib.baseboard_fab2(sch_1):page80_i101:dqs10p" )
			)
			( pin "J9U1.30"
				( objectStatus "@baseboard_fab2_lib.baseboard_fab2(sch_1):page80_i101:dqs11n" )
			)
			( pin "J9U1.29"
				( objectStatus "@baseboard_fab2_lib.baseboard_fab2(sch_1):page80_i101:dqs11p" )
			)
			( pin "J9U1.41"
				( objectStatus "@baseboard_fab2_lib.baseboard_fab2(sch_1):page80_i101:dqs12n" )
			)
			( pin "J9U1.40"
				( objectStatus "@baseboard_fab2_lib.baseboard_fab2(sch_1):page80_i101:dqs12p" )
			)
			( pin "J9U1.100"
				( objectStatus "@baseboard_fab2_lib.baseboard_fab2(sch_1):page80_i101:dqs13n" )
			)
			( pin "J9U1.99"
				( objectStatus "@baseboard_fab2_lib.baseboard_fab2(sch_1):page80_i101:dqs13p" )
			)
			( pin "J9U1.111"
				( objectStatus "@baseboard_fab2_lib.baseboard_fab2(sch_1):page80_i101:dqs14n" )
			)
			( pin "J9U1.110"
				( objectStatus "@baseboard_fab2_lib.baseboard_fab2(sch_1):page80_i101:dqs14p" )
			)
			( pin "J9U1.122"
				( objectStatus "@baseboard_fab2_lib.baseboard_fab2(sch_1):page80_i101:dqs15n" )
			)
			( pin "J9U1.121"
				( objectStatus "@baseboard_fab2_lib.baseboard_fab2(sch_1):page80_i101:dqs15p" )
			)
			( pin "J9U1.133"
				( objectStatus "@baseboard_fab2_lib.baseboard_fab2(sch_1):page80_i101:dqs16n" )
			)
			( pin "J9U1.132"
				( objectStatus "@baseboard_fab2_lib.baseboard_fab2(sch_1):page80_i101:dqs16p" )
			)
			( pin "J9U1.52"
				( objectStatus "@baseboard_fab2_lib.baseboard_fab2(sch_1):page80_i101:dqs17n" )
			)
			( pin "J9U1.51"
				( objectStatus "@baseboard_fab2_lib.baseboard_fab2(sch_1):page80_i101:dqs17p" )
			)
			( pin "J9U1.283"
				( objectStatus "@baseboard_fab2_lib.baseboard_fab2(sch_1):page80_i138:vss(0)" )
			)
			( pin "J9U1.281"
				( objectStatus "@baseboard_fab2_lib.baseboard_fab2(sch_1):page80_i138:vss(1)" )
			)
			( pin "J9U1.279"
				( objectStatus "@baseboard_fab2_lib.baseboard_fab2(sch_1):page80_i138:vss(2)" )
			)
			( pin "J9U1.276"
				( objectStatus "@baseboard_fab2_lib.baseboard_fab2(sch_1):page80_i138:vss(3)" )
			)
			( pin "J9U1.274"
				( objectStatus "@baseboard_fab2_lib.baseboard_fab2(sch_1):page80_i138:vss(4)" )
			)
			( pin "J9U1.272"
				( objectStatus "@baseboard_fab2_lib.baseboard_fab2(sch_1):page80_i138:vss(5)" )
			)
			( pin "J9U1.270"
				( objectStatus "@baseboard_fab2_lib.baseboard_fab2(sch_1):page80_i138:vss(6)" )
			)
			( pin "J9U1.268"
				( objectStatus "@baseboard_fab2_lib.baseboard_fab2(sch_1):page80_i138:vss(7)" )
			)
			( pin "J9U1.265"
				( objectStatus "@baseboard_fab2_lib.baseboard_fab2(sch_1):page80_i138:vss(8)" )
			)
			( pin "J9U1.263"
				( objectStatus "@baseboard_fab2_lib.baseboard_fab2(sch_1):page80_i138:vss(9)" )
			)
			( pin "J9U1.261"
				( objectStatus "@baseboard_fab2_lib.baseboard_fab2(sch_1):page80_i138:vss(10)" )
			)
			( pin "J9U1.259"
				( objectStatus "@baseboard_fab2_lib.baseboard_fab2(sch_1):page80_i138:vss(11)" )
			)
			( pin "J9U1.257"
				( objectStatus "@baseboard_fab2_lib.baseboard_fab2(sch_1):page80_i138:vss(12)" )
			)
			( pin "J9U1.254"
				( objectStatus "@baseboard_fab2_lib.baseboard_fab2(sch_1):page80_i138:vss(13)" )
			)
			( pin "J9U1.252"
				( objectStatus "@baseboard_fab2_lib.baseboard_fab2(sch_1):page80_i138:vss(14)" )
			)
			( pin "J9U1.250"
				( objectStatus "@baseboard_fab2_lib.baseboard_fab2(sch_1):page80_i138:vss(15)" )
			)
			( pin "J9U1.248"
				( objectStatus "@baseboard_fab2_lib.baseboard_fab2(sch_1):page80_i138:vss(16)" )
			)
			( pin "J9U1.246"
				( objectStatus "@baseboard_fab2_lib.baseboard_fab2(sch_1):page80_i138:vss(17)" )
			)
			( pin "J9U1.243"
				( objectStatus "@baseboard_fab2_lib.baseboard_fab2(sch_1):page80_i138:vss(18)" )
			)
			( pin "J9U1.241"
				( objectStatus "@baseboard_fab2_lib.baseboard_fab2(sch_1):page80_i138:vss(19)" )
			)
			( pin "J9U1.239"
				( objectStatus "@baseboard_fab2_lib.baseboard_fab2(sch_1):page80_i138:vss(20)" )
			)
			( pin "J9U1.202"
				( objectStatus "@baseboard_fab2_lib.baseboard_fab2(sch_1):page80_i138:vss(21)" )
			)
			( pin "J9U1.200"
				( objectStatus "@baseboard_fab2_lib.baseboard_fab2(sch_1):page80_i138:vss(22)" )
			)
			( pin "J9U1.198"
				( objectStatus "@baseboard_fab2_lib.baseboard_fab2(sch_1):page80_i138:vss(23)" )
			)
			( pin "J9U1.195"
				( objectStatus "@baseboard_fab2_lib.baseboard_fab2(sch_1):page80_i138:vss(24)" )
			)
			( pin "J9U1.193"
				( objectStatus "@baseboard_fab2_lib.baseboard_fab2(sch_1):page80_i138:vss(25)" )
			)
			( pin "J9U1.191"
				( objectStatus "@baseboard_fab2_lib.baseboard_fab2(sch_1):page80_i138:vss(26)" )
			)
			( pin "J9U1.189"
				( objectStatus "@baseboard_fab2_lib.baseboard_fab2(sch_1):page80_i138:vss(27)" )
			)
			( pin "J9U1.187"
				( objectStatus "@baseboard_fab2_lib.baseboard_fab2(sch_1):page80_i138:vss(28)" )
			)
			( pin "J9U1.184"
				( objectStatus "@baseboard_fab2_lib.baseboard_fab2(sch_1):page80_i138:vss(29)" )
			)
			( pin "J9U1.182"
				( objectStatus "@baseboard_fab2_lib.baseboard_fab2(sch_1):page80_i138:vss(30)" )
			)
			( pin "J9U1.180"
				( objectStatus "@baseboard_fab2_lib.baseboard_fab2(sch_1):page80_i138:vss(31)" )
			)
			( pin "J9U1.178"
				( objectStatus "@baseboard_fab2_lib.baseboard_fab2(sch_1):page80_i138:vss(32)" )
			)
			( pin "J9U1.176"
				( objectStatus "@baseboard_fab2_lib.baseboard_fab2(sch_1):page80_i138:vss(33)" )
			)
			( pin "J9U1.173"
				( objectStatus "@baseboard_fab2_lib.baseboard_fab2(sch_1):page80_i138:vss(34)" )
			)
			( pin "J9U1.171"
				( objectStatus "@baseboard_fab2_lib.baseboard_fab2(sch_1):page80_i138:vss(35)" )
			)
			( pin "J9U1.169"
				( objectStatus "@baseboard_fab2_lib.baseboard_fab2(sch_1):page80_i138:vss(36)" )
			)
			( pin "J9U1.167"
				( objectStatus "@baseboard_fab2_lib.baseboard_fab2(sch_1):page80_i138:vss(37)" )
			)
			( pin "J9U1.165"
				( objectStatus "@baseboard_fab2_lib.baseboard_fab2(sch_1):page80_i138:vss(38)" )
			)
			( pin "J9U1.162"
				( objectStatus "@baseboard_fab2_lib.baseboard_fab2(sch_1):page80_i138:vss(39)" )
			)
			( pin "J9U1.160"
				( objectStatus "@baseboard_fab2_lib.baseboard_fab2(sch_1):page80_i138:vss(40)" )
			)
			( pin "J9U1.158"
				( objectStatus "@baseboard_fab2_lib.baseboard_fab2(sch_1):page80_i138:vss(41)" )
			)
			( pin "J9U1.156"
				( objectStatus "@baseboard_fab2_lib.baseboard_fab2(sch_1):page80_i138:vss(42)" )
			)
			( pin "J9U1.154"
				( objectStatus "@baseboard_fab2_lib.baseboard_fab2(sch_1):page80_i138:vss(43)" )
			)
			( pin "J9U1.151"
				( objectStatus "@baseboard_fab2_lib.baseboard_fab2(sch_1):page80_i138:vss(44)" )
			)
			( pin "J9U1.149"
				( objectStatus "@baseboard_fab2_lib.baseboard_fab2(sch_1):page80_i138:vss(45)" )
			)
			( pin "J9U1.147"
				( objectStatus "@baseboard_fab2_lib.baseboard_fab2(sch_1):page80_i138:vss(46)" )
			)
			( pin "J9U1.138"
				( objectStatus "@baseboard_fab2_lib.baseboard_fab2(sch_1):page80_i138:vss(47)" )
			)
			( pin "J9U1.136"
				( objectStatus "@baseboard_fab2_lib.baseboard_fab2(sch_1):page80_i138:vss(48)" )
			)
			( pin "J9U1.134"
				( objectStatus "@baseboard_fab2_lib.baseboard_fab2(sch_1):page80_i138:vss(49)" )
			)
			( pin "J9U1.131"
				( objectStatus "@baseboard_fab2_lib.baseboard_fab2(sch_1):page80_i138:vss(50)" )
			)
			( pin "J9U1.129"
				( objectStatus "@baseboard_fab2_lib.baseboard_fab2(sch_1):page80_i138:vss(51)" )
			)
			( pin "J9U1.127"
				( objectStatus "@baseboard_fab2_lib.baseboard_fab2(sch_1):page80_i138:vss(52)" )
			)
			( pin "J9U1.125"
				( objectStatus "@baseboard_fab2_lib.baseboard_fab2(sch_1):page80_i138:vss(53)" )
			)
			( pin "J9U1.123"
				( objectStatus "@baseboard_fab2_lib.baseboard_fab2(sch_1):page80_i138:vss(54)" )
			)
			( pin "J9U1.120"
				( objectStatus "@baseboard_fab2_lib.baseboard_fab2(sch_1):page80_i138:vss(55)" )
			)
			( pin "J9U1.118"
				( objectStatus "@baseboard_fab2_lib.baseboard_fab2(sch_1):page80_i138:vss(56)" )
			)
			( pin "J9U1.116"
				( objectStatus "@baseboard_fab2_lib.baseboard_fab2(sch_1):page80_i138:vss(57)" )
			)
			( pin "J9U1.114"
				( objectStatus "@baseboard_fab2_lib.baseboard_fab2(sch_1):page80_i138:vss(58)" )
			)
			( pin "J9U1.112"
				( objectStatus "@baseboard_fab2_lib.baseboard_fab2(sch_1):page80_i138:vss(59)" )
			)
			( pin "J9U1.109"
				( objectStatus "@baseboard_fab2_lib.baseboard_fab2(sch_1):page80_i138:vss(60)" )
			)
			( pin "J9U1.107"
				( objectStatus "@baseboard_fab2_lib.baseboard_fab2(sch_1):page80_i138:vss(61)" )
			)
			( pin "J9U1.105"
				( objectStatus "@baseboard_fab2_lib.baseboard_fab2(sch_1):page80_i138:vss(62)" )
			)
			( pin "J9U1.103"
				( objectStatus "@baseboard_fab2_lib.baseboard_fab2(sch_1):page80_i138:vss(63)" )
			)
			( pin "J9U1.101"
				( objectStatus "@baseboard_fab2_lib.baseboard_fab2(sch_1):page80_i138:vss(64)" )
			)
			( pin "J9U1.98"
				( objectStatus "@baseboard_fab2_lib.baseboard_fab2(sch_1):page80_i138:vss(65)" )
			)
			( pin "J9U1.96"
				( objectStatus "@baseboard_fab2_lib.baseboard_fab2(sch_1):page80_i138:vss(66)" )
			)
			( pin "J9U1.94"
				( objectStatus "@baseboard_fab2_lib.baseboard_fab2(sch_1):page80_i138:vss(67)" )
			)
			( pin "J9U1.57"
				( objectStatus "@baseboard_fab2_lib.baseboard_fab2(sch_1):page80_i138:vss(68)" )
			)
			( pin "J9U1.55"
				( objectStatus "@baseboard_fab2_lib.baseboard_fab2(sch_1):page80_i138:vss(69)" )
			)
			( pin "J9U1.53"
				( objectStatus "@baseboard_fab2_lib.baseboard_fab2(sch_1):page80_i138:vss(70)" )
			)
			( pin "J9U1.50"
				( objectStatus "@baseboard_fab2_lib.baseboard_fab2(sch_1):page80_i138:vss(71)" )
			)
			( pin "J9U1.48"
				( objectStatus "@baseboard_fab2_lib.baseboard_fab2(sch_1):page80_i138:vss(72)" )
			)
			( pin "J9U1.46"
				( objectStatus "@baseboard_fab2_lib.baseboard_fab2(sch_1):page80_i138:vss(73)" )
			)
			( pin "J9U1.44"
				( objectStatus "@baseboard_fab2_lib.baseboard_fab2(sch_1):page80_i138:vss(74)" )
			)
			( pin "J9U1.42"
				( objectStatus "@baseboard_fab2_lib.baseboard_fab2(sch_1):page80_i138:vss(75)" )
			)
			( pin "J9U1.39"
				( objectStatus "@baseboard_fab2_lib.baseboard_fab2(sch_1):page80_i138:vss(76)" )
			)
			( pin "J9U1.37"
				( objectStatus "@baseboard_fab2_lib.baseboard_fab2(sch_1):page80_i138:vss(77)" )
			)
			( pin "J9U1.35"
				( objectStatus "@baseboard_fab2_lib.baseboard_fab2(sch_1):page80_i138:vss(78)" )
			)
			( pin "J9U1.33"
				( objectStatus "@baseboard_fab2_lib.baseboard_fab2(sch_1):page80_i138:vss(79)" )
			)
			( pin "J9U1.31"
				( objectStatus "@baseboard_fab2_lib.baseboard_fab2(sch_1):page80_i138:vss(80)" )
			)
			( pin "J9U1.28"
				( objectStatus "@baseboard_fab2_lib.baseboard_fab2(sch_1):page80_i138:vss(81)" )
			)
			( pin "J9U1.26"
				( objectStatus "@baseboard_fab2_lib.baseboard_fab2(sch_1):page80_i138:vss(82)" )
			)
			( pin "J9U1.24"
				( objectStatus "@baseboard_fab2_lib.baseboard_fab2(sch_1):page80_i138:vss(83)" )
			)
			( pin "J9U1.22"
				( objectStatus "@baseboard_fab2_lib.baseboard_fab2(sch_1):page80_i138:vss(84)" )
			)
			( pin "J9U1.20"
				( objectStatus "@baseboard_fab2_lib.baseboard_fab2(sch_1):page80_i138:vss(85)" )
			)
			( pin "J9U1.17"
				( objectStatus "@baseboard_fab2_lib.baseboard_fab2(sch_1):page80_i138:vss(86)" )
			)
			( pin "J9U1.15"
				( objectStatus "@baseboard_fab2_lib.baseboard_fab2(sch_1):page80_i138:vss(87)" )
			)
			( pin "J9U1.13"
				( objectStatus "@baseboard_fab2_lib.baseboard_fab2(sch_1):page80_i138:vss(88)" )
			)
			( pin "J9U1.11"
				( objectStatus "@baseboard_fab2_lib.baseboard_fab2(sch_1):page80_i138:vss(89)" )
			)
			( pin "J9U1.9"
				( objectStatus "@baseboard_fab2_lib.baseboard_fab2(sch_1):page80_i138:vss(90)" )
			)
			( pin "J9U1.6"
				( objectStatus "@baseboard_fab2_lib.baseboard_fab2(sch_1):page80_i138:vss(91)" )
			)
			( pin "J9U1.4"
				( objectStatus "@baseboard_fab2_lib.baseboard_fab2(sch_1):page80_i138:vss(92)" )
			)
			( pin "J9U1.2"
				( objectStatus "@baseboard_fab2_lib.baseboard_fab2(sch_1):page80_i138:vss(93)" )
			)
			( pin "J1G3.152"
				( objectStatus "@baseboard_fab2_lib.baseboard_fab2(sch_1):page81_i67:dqs0n" )
			)
			( pin "J1G3.153"
				( objectStatus "@baseboard_fab2_lib.baseboard_fab2(sch_1):page81_i67:dqs0p" )
			)
			( pin "J1G3.163"
				( objectStatus "@baseboard_fab2_lib.baseboard_fab2(sch_1):page81_i67:dqs1n" )
			)
			( pin "J1G3.164"
				( objectStatus "@baseboard_fab2_lib.baseboard_fab2(sch_1):page81_i67:dqs1p" )
			)
			( pin "J1G3.174"
				( objectStatus "@baseboard_fab2_lib.baseboard_fab2(sch_1):page81_i67:dqs2n" )
			)
			( pin "J1G3.175"
				( objectStatus "@baseboard_fab2_lib.baseboard_fab2(sch_1):page81_i67:dqs2p" )
			)
			( pin "J1G3.185"
				( objectStatus "@baseboard_fab2_lib.baseboard_fab2(sch_1):page81_i67:dqs3n" )
			)
			( pin "J1G3.186"
				( objectStatus "@baseboard_fab2_lib.baseboard_fab2(sch_1):page81_i67:dqs3p" )
			)
			( pin "J1G3.244"
				( objectStatus "@baseboard_fab2_lib.baseboard_fab2(sch_1):page81_i67:dqs4n" )
			)
			( pin "J1G3.245"
				( objectStatus "@baseboard_fab2_lib.baseboard_fab2(sch_1):page81_i67:dqs4p" )
			)
			( pin "J1G3.255"
				( objectStatus "@baseboard_fab2_lib.baseboard_fab2(sch_1):page81_i67:dqs5n" )
			)
			( pin "J1G3.256"
				( objectStatus "@baseboard_fab2_lib.baseboard_fab2(sch_1):page81_i67:dqs5p" )
			)
			( pin "J1G3.266"
				( objectStatus "@baseboard_fab2_lib.baseboard_fab2(sch_1):page81_i67:dqs6n" )
			)
			( pin "J1G3.267"
				( objectStatus "@baseboard_fab2_lib.baseboard_fab2(sch_1):page81_i67:dqs6p" )
			)
			( pin "J1G3.277"
				( objectStatus "@baseboard_fab2_lib.baseboard_fab2(sch_1):page81_i67:dqs7n" )
			)
			( pin "J1G3.278"
				( objectStatus "@baseboard_fab2_lib.baseboard_fab2(sch_1):page81_i67:dqs7p" )
			)
			( pin "J1G3.196"
				( objectStatus "@baseboard_fab2_lib.baseboard_fab2(sch_1):page81_i67:dqs8n" )
			)
			( pin "J1G3.197"
				( objectStatus "@baseboard_fab2_lib.baseboard_fab2(sch_1):page81_i67:dqs8p" )
			)
			( pin "J1G3.8"
				( objectStatus "@baseboard_fab2_lib.baseboard_fab2(sch_1):page81_i67:dqs9n" )
			)
			( pin "J1G3.7"
				( objectStatus "@baseboard_fab2_lib.baseboard_fab2(sch_1):page81_i67:dqs9p" )
			)
			( pin "J1G3.19"
				( objectStatus "@baseboard_fab2_lib.baseboard_fab2(sch_1):page81_i67:dqs10n" )
			)
			( pin "J1G3.18"
				( objectStatus "@baseboard_fab2_lib.baseboard_fab2(sch_1):page81_i67:dqs10p" )
			)
			( pin "J1G3.30"
				( objectStatus "@baseboard_fab2_lib.baseboard_fab2(sch_1):page81_i67:dqs11n" )
			)
			( pin "J1G3.29"
				( objectStatus "@baseboard_fab2_lib.baseboard_fab2(sch_1):page81_i67:dqs11p" )
			)
			( pin "J1G3.41"
				( objectStatus "@baseboard_fab2_lib.baseboard_fab2(sch_1):page81_i67:dqs12n" )
			)
			( pin "J1G3.40"
				( objectStatus "@baseboard_fab2_lib.baseboard_fab2(sch_1):page81_i67:dqs12p" )
			)
			( pin "J1G3.100"
				( objectStatus "@baseboard_fab2_lib.baseboard_fab2(sch_1):page81_i67:dqs13n" )
			)
			( pin "J1G3.99"
				( objectStatus "@baseboard_fab2_lib.baseboard_fab2(sch_1):page81_i67:dqs13p" )
			)
			( pin "J1G3.111"
				( objectStatus "@baseboard_fab2_lib.baseboard_fab2(sch_1):page81_i67:dqs14n" )
			)
			( pin "J1G3.110"
				( objectStatus "@baseboard_fab2_lib.baseboard_fab2(sch_1):page81_i67:dqs14p" )
			)
			( pin "J1G3.122"
				( objectStatus "@baseboard_fab2_lib.baseboard_fab2(sch_1):page81_i67:dqs15n" )
			)
			( pin "J1G3.121"
				( objectStatus "@baseboard_fab2_lib.baseboard_fab2(sch_1):page81_i67:dqs15p" )
			)
			( pin "J1G3.133"
				( objectStatus "@baseboard_fab2_lib.baseboard_fab2(sch_1):page81_i67:dqs16n" )
			)
			( pin "J1G3.132"
				( objectStatus "@baseboard_fab2_lib.baseboard_fab2(sch_1):page81_i67:dqs16p" )
			)
			( pin "J1G3.52"
				( objectStatus "@baseboard_fab2_lib.baseboard_fab2(sch_1):page81_i67:dqs17n" )
			)
			( pin "J1G3.51"
				( objectStatus "@baseboard_fab2_lib.baseboard_fab2(sch_1):page81_i67:dqs17p" )
			)
			( pin "J1G3.145"
				( objectStatus "@baseboard_fab2_lib.baseboard_fab2(sch_1):page81_i169:\12v\(0)" )
			)
			( pin "J1G3.1"
				( objectStatus "@baseboard_fab2_lib.baseboard_fab2(sch_1):page81_i169:\12v\(1)" )
			)
			( pin "J1G3.236"
				( objectStatus "@baseboard_fab2_lib.baseboard_fab2(sch_1):page81_i169:vdd(0)" )
			)
			( pin "J1G3.233"
				( objectStatus "@baseboard_fab2_lib.baseboard_fab2(sch_1):page81_i169:vdd(1)" )
			)
			( pin "J1G3.231"
				( objectStatus "@baseboard_fab2_lib.baseboard_fab2(sch_1):page81_i169:vdd(2)" )
			)
			( pin "J1G3.229"
				( objectStatus "@baseboard_fab2_lib.baseboard_fab2(sch_1):page81_i169:vdd(3)" )
			)
			( pin "J1G3.226"
				( objectStatus "@baseboard_fab2_lib.baseboard_fab2(sch_1):page81_i169:vdd(4)" )
			)
			( pin "J1G3.223"
				( objectStatus "@baseboard_fab2_lib.baseboard_fab2(sch_1):page81_i169:vdd(5)" )
			)
			( pin "J1G3.220"
				( objectStatus "@baseboard_fab2_lib.baseboard_fab2(sch_1):page81_i169:vdd(6)" )
			)
			( pin "J1G3.217"
				( objectStatus "@baseboard_fab2_lib.baseboard_fab2(sch_1):page81_i169:vdd(7)" )
			)
			( pin "J1G3.215"
				( objectStatus "@baseboard_fab2_lib.baseboard_fab2(sch_1):page81_i169:vdd(8)" )
			)
			( pin "J1G3.212"
				( objectStatus "@baseboard_fab2_lib.baseboard_fab2(sch_1):page81_i169:vdd(9)" )
			)
			( pin "J1G3.209"
				( objectStatus "@baseboard_fab2_lib.baseboard_fab2(sch_1):page81_i169:vdd(10)" )
			)
			( pin "J1G3.206"
				( objectStatus "@baseboard_fab2_lib.baseboard_fab2(sch_1):page81_i169:vdd(11)" )
			)
			( pin "J1G3.204"
				( objectStatus "@baseboard_fab2_lib.baseboard_fab2(sch_1):page81_i169:vdd(12)" )
			)
			( pin "J1G3.92"
				( objectStatus "@baseboard_fab2_lib.baseboard_fab2(sch_1):page81_i169:vdd(13)" )
			)
			( pin "J1G3.90"
				( objectStatus "@baseboard_fab2_lib.baseboard_fab2(sch_1):page81_i169:vdd(14)" )
			)
			( pin "J1G3.88"
				( objectStatus "@baseboard_fab2_lib.baseboard_fab2(sch_1):page81_i169:vdd(15)" )
			)
			( pin "J1G3.85"
				( objectStatus "@baseboard_fab2_lib.baseboard_fab2(sch_1):page81_i169:vdd(16)" )
			)
			( pin "J1G3.83"
				( objectStatus "@baseboard_fab2_lib.baseboard_fab2(sch_1):page81_i169:vdd(17)" )
			)
			( pin "J1G3.80"
				( objectStatus "@baseboard_fab2_lib.baseboard_fab2(sch_1):page81_i169:vdd(18)" )
			)
			( pin "J1G3.76"
				( objectStatus "@baseboard_fab2_lib.baseboard_fab2(sch_1):page81_i169:vdd(19)" )
			)
			( pin "J1G3.73"
				( objectStatus "@baseboard_fab2_lib.baseboard_fab2(sch_1):page81_i169:vdd(20)" )
			)
			( pin "J1G3.70"
				( objectStatus "@baseboard_fab2_lib.baseboard_fab2(sch_1):page81_i169:vdd(21)" )
			)
			( pin "J1G3.67"
				( objectStatus "@baseboard_fab2_lib.baseboard_fab2(sch_1):page81_i169:vdd(22)" )
			)
			( pin "J1G3.64"
				( objectStatus "@baseboard_fab2_lib.baseboard_fab2(sch_1):page81_i169:vdd(23)" )
			)
			( pin "J1G3.61"
				( objectStatus "@baseboard_fab2_lib.baseboard_fab2(sch_1):page81_i169:vdd(24)" )
			)
			( pin "J1G3.59"
				( objectStatus "@baseboard_fab2_lib.baseboard_fab2(sch_1):page81_i169:vdd(25)" )
			)
			( pin "J1G3.287"
				( objectStatus "@baseboard_fab2_lib.baseboard_fab2(sch_1):page81_i169:vpp(0)" )
			)
			( pin "J1G3.286"
				( objectStatus "@baseboard_fab2_lib.baseboard_fab2(sch_1):page81_i169:vpp(1)" )
			)
			( pin "J1G3.288"
				( objectStatus "@baseboard_fab2_lib.baseboard_fab2(sch_1):page81_i169:vpp(2)" )
			)
			( pin "J1G3.143"
				( objectStatus "@baseboard_fab2_lib.baseboard_fab2(sch_1):page81_i169:vpp(3)" )
			)
			( pin "J1G3.142"
				( objectStatus "@baseboard_fab2_lib.baseboard_fab2(sch_1):page81_i169:vpp(4)" )
			)
			( pin "J1G3.221"
				( objectStatus "@baseboard_fab2_lib.baseboard_fab2(sch_1):page81_i169:vtt(0)" )
			)
			( pin "J1G3.77"
				( objectStatus "@baseboard_fab2_lib.baseboard_fab2(sch_1):page81_i169:vtt(1)" )
			)
			( pin "C9U10.1"
				( objectStatus "@baseboard_fab2_lib.baseboard_fab2(sch_1):page81_i178:a" )
			)
			( pin "C9U10.2"
				( objectStatus "@baseboard_fab2_lib.baseboard_fab2(sch_1):page81_i178:b" )
			)
			( pin "J1G3.283"
				( objectStatus "@baseboard_fab2_lib.baseboard_fab2(sch_1):page81_i185:vss(0)" )
			)
			( pin "J1G3.281"
				( objectStatus "@baseboard_fab2_lib.baseboard_fab2(sch_1):page81_i185:vss(1)" )
			)
			( pin "J1G3.279"
				( objectStatus "@baseboard_fab2_lib.baseboard_fab2(sch_1):page81_i185:vss(2)" )
			)
			( pin "J1G3.276"
				( objectStatus "@baseboard_fab2_lib.baseboard_fab2(sch_1):page81_i185:vss(3)" )
			)
			( pin "J1G3.274"
				( objectStatus "@baseboard_fab2_lib.baseboard_fab2(sch_1):page81_i185:vss(4)" )
			)
			( pin "J1G3.272"
				( objectStatus "@baseboard_fab2_lib.baseboard_fab2(sch_1):page81_i185:vss(5)" )
			)
			( pin "J1G3.270"
				( objectStatus "@baseboard_fab2_lib.baseboard_fab2(sch_1):page81_i185:vss(6)" )
			)
			( pin "J1G3.268"
				( objectStatus "@baseboard_fab2_lib.baseboard_fab2(sch_1):page81_i185:vss(7)" )
			)
			( pin "J1G3.265"
				( objectStatus "@baseboard_fab2_lib.baseboard_fab2(sch_1):page81_i185:vss(8)" )
			)
			( pin "J1G3.263"
				( objectStatus "@baseboard_fab2_lib.baseboard_fab2(sch_1):page81_i185:vss(9)" )
			)
			( pin "J1G3.261"
				( objectStatus "@baseboard_fab2_lib.baseboard_fab2(sch_1):page81_i185:vss(10)" )
			)
			( pin "J1G3.259"
				( objectStatus "@baseboard_fab2_lib.baseboard_fab2(sch_1):page81_i185:vss(11)" )
			)
			( pin "J1G3.257"
				( objectStatus "@baseboard_fab2_lib.baseboard_fab2(sch_1):page81_i185:vss(12)" )
			)
			( pin "J1G3.254"
				( objectStatus "@baseboard_fab2_lib.baseboard_fab2(sch_1):page81_i185:vss(13)" )
			)
			( pin "J1G3.252"
				( objectStatus "@baseboard_fab2_lib.baseboard_fab2(sch_1):page81_i185:vss(14)" )
			)
			( pin "J1G3.250"
				( objectStatus "@baseboard_fab2_lib.baseboard_fab2(sch_1):page81_i185:vss(15)" )
			)
			( pin "J1G3.248"
				( objectStatus "@baseboard_fab2_lib.baseboard_fab2(sch_1):page81_i185:vss(16)" )
			)
			( pin "J1G3.246"
				( objectStatus "@baseboard_fab2_lib.baseboard_fab2(sch_1):page81_i185:vss(17)" )
			)
			( pin "J1G3.243"
				( objectStatus "@baseboard_fab2_lib.baseboard_fab2(sch_1):page81_i185:vss(18)" )
			)
			( pin "J1G3.241"
				( objectStatus "@baseboard_fab2_lib.baseboard_fab2(sch_1):page81_i185:vss(19)" )
			)
			( pin "J1G3.239"
				( objectStatus "@baseboard_fab2_lib.baseboard_fab2(sch_1):page81_i185:vss(20)" )
			)
			( pin "J1G3.202"
				( objectStatus "@baseboard_fab2_lib.baseboard_fab2(sch_1):page81_i185:vss(21)" )
			)
			( pin "J1G3.200"
				( objectStatus "@baseboard_fab2_lib.baseboard_fab2(sch_1):page81_i185:vss(22)" )
			)
			( pin "J1G3.198"
				( objectStatus "@baseboard_fab2_lib.baseboard_fab2(sch_1):page81_i185:vss(23)" )
			)
			( pin "J1G3.195"
				( objectStatus "@baseboard_fab2_lib.baseboard_fab2(sch_1):page81_i185:vss(24)" )
			)
			( pin "J1G3.193"
				( objectStatus "@baseboard_fab2_lib.baseboard_fab2(sch_1):page81_i185:vss(25)" )
			)
			( pin "J1G3.191"
				( objectStatus "@baseboard_fab2_lib.baseboard_fab2(sch_1):page81_i185:vss(26)" )
			)
			( pin "J1G3.189"
				( objectStatus "@baseboard_fab2_lib.baseboard_fab2(sch_1):page81_i185:vss(27)" )
			)
			( pin "J1G3.187"
				( objectStatus "@baseboard_fab2_lib.baseboard_fab2(sch_1):page81_i185:vss(28)" )
			)
			( pin "J1G3.184"
				( objectStatus "@baseboard_fab2_lib.baseboard_fab2(sch_1):page81_i185:vss(29)" )
			)
			( pin "J1G3.182"
				( objectStatus "@baseboard_fab2_lib.baseboard_fab2(sch_1):page81_i185:vss(30)" )
			)
			( pin "J1G3.180"
				( objectStatus "@baseboard_fab2_lib.baseboard_fab2(sch_1):page81_i185:vss(31)" )
			)
			( pin "J1G3.178"
				( objectStatus "@baseboard_fab2_lib.baseboard_fab2(sch_1):page81_i185:vss(32)" )
			)
			( pin "J1G3.176"
				( objectStatus "@baseboard_fab2_lib.baseboard_fab2(sch_1):page81_i185:vss(33)" )
			)
			( pin "J1G3.173"
				( objectStatus "@baseboard_fab2_lib.baseboard_fab2(sch_1):page81_i185:vss(34)" )
			)
			( pin "J1G3.171"
				( objectStatus "@baseboard_fab2_lib.baseboard_fab2(sch_1):page81_i185:vss(35)" )
			)
			( pin "J1G3.169"
				( objectStatus "@baseboard_fab2_lib.baseboard_fab2(sch_1):page81_i185:vss(36)" )
			)
			( pin "J1G3.167"
				( objectStatus "@baseboard_fab2_lib.baseboard_fab2(sch_1):page81_i185:vss(37)" )
			)
			( pin "J1G3.165"
				( objectStatus "@baseboard_fab2_lib.baseboard_fab2(sch_1):page81_i185:vss(38)" )
			)
			( pin "J1G3.162"
				( objectStatus "@baseboard_fab2_lib.baseboard_fab2(sch_1):page81_i185:vss(39)" )
			)
			( pin "J1G3.160"
				( objectStatus "@baseboard_fab2_lib.baseboard_fab2(sch_1):page81_i185:vss(40)" )
			)
			( pin "J1G3.158"
				( objectStatus "@baseboard_fab2_lib.baseboard_fab2(sch_1):page81_i185:vss(41)" )
			)
			( pin "J1G3.156"
				( objectStatus "@baseboard_fab2_lib.baseboard_fab2(sch_1):page81_i185:vss(42)" )
			)
			( pin "J1G3.154"
				( objectStatus "@baseboard_fab2_lib.baseboard_fab2(sch_1):page81_i185:vss(43)" )
			)
			( pin "J1G3.151"
				( objectStatus "@baseboard_fab2_lib.baseboard_fab2(sch_1):page81_i185:vss(44)" )
			)
			( pin "J1G3.149"
				( objectStatus "@baseboard_fab2_lib.baseboard_fab2(sch_1):page81_i185:vss(45)" )
			)
			( pin "J1G3.147"
				( objectStatus "@baseboard_fab2_lib.baseboard_fab2(sch_1):page81_i185:vss(46)" )
			)
			( pin "J1G3.138"
				( objectStatus "@baseboard_fab2_lib.baseboard_fab2(sch_1):page81_i185:vss(47)" )
			)
			( pin "J1G3.136"
				( objectStatus "@baseboard_fab2_lib.baseboard_fab2(sch_1):page81_i185:vss(48)" )
			)
			( pin "J1G3.134"
				( objectStatus "@baseboard_fab2_lib.baseboard_fab2(sch_1):page81_i185:vss(49)" )
			)
			( pin "J1G3.131"
				( objectStatus "@baseboard_fab2_lib.baseboard_fab2(sch_1):page81_i185:vss(50)" )
			)
			( pin "J1G3.129"
				( objectStatus "@baseboard_fab2_lib.baseboard_fab2(sch_1):page81_i185:vss(51)" )
			)
			( pin "J1G3.127"
				( objectStatus "@baseboard_fab2_lib.baseboard_fab2(sch_1):page81_i185:vss(52)" )
			)
			( pin "J1G3.125"
				( objectStatus "@baseboard_fab2_lib.baseboard_fab2(sch_1):page81_i185:vss(53)" )
			)
			( pin "J1G3.123"
				( objectStatus "@baseboard_fab2_lib.baseboard_fab2(sch_1):page81_i185:vss(54)" )
			)
			( pin "J1G3.120"
				( objectStatus "@baseboard_fab2_lib.baseboard_fab2(sch_1):page81_i185:vss(55)" )
			)
			( pin "J1G3.118"
				( objectStatus "@baseboard_fab2_lib.baseboard_fab2(sch_1):page81_i185:vss(56)" )
			)
			( pin "J1G3.116"
				( objectStatus "@baseboard_fab2_lib.baseboard_fab2(sch_1):page81_i185:vss(57)" )
			)
			( pin "J1G3.114"
				( objectStatus "@baseboard_fab2_lib.baseboard_fab2(sch_1):page81_i185:vss(58)" )
			)
			( pin "J1G3.112"
				( objectStatus "@baseboard_fab2_lib.baseboard_fab2(sch_1):page81_i185:vss(59)" )
			)
			( pin "J1G3.109"
				( objectStatus "@baseboard_fab2_lib.baseboard_fab2(sch_1):page81_i185:vss(60)" )
			)
			( pin "J1G3.107"
				( objectStatus "@baseboard_fab2_lib.baseboard_fab2(sch_1):page81_i185:vss(61)" )
			)
			( pin "J1G3.105"
				( objectStatus "@baseboard_fab2_lib.baseboard_fab2(sch_1):page81_i185:vss(62)" )
			)
			( pin "J1G3.103"
				( objectStatus "@baseboard_fab2_lib.baseboard_fab2(sch_1):page81_i185:vss(63)" )
			)
			( pin "J1G3.101"
				( objectStatus "@baseboard_fab2_lib.baseboard_fab2(sch_1):page81_i185:vss(64)" )
			)
			( pin "J1G3.98"
				( objectStatus "@baseboard_fab2_lib.baseboard_fab2(sch_1):page81_i185:vss(65)" )
			)
			( pin "J1G3.96"
				( objectStatus "@baseboard_fab2_lib.baseboard_fab2(sch_1):page81_i185:vss(66)" )
			)
			( pin "J1G3.94"
				( objectStatus "@baseboard_fab2_lib.baseboard_fab2(sch_1):page81_i185:vss(67)" )
			)
			( pin "J1G3.57"
				( objectStatus "@baseboard_fab2_lib.baseboard_fab2(sch_1):page81_i185:vss(68)" )
			)
			( pin "J1G3.55"
				( objectStatus "@baseboard_fab2_lib.baseboard_fab2(sch_1):page81_i185:vss(69)" )
			)
			( pin "J1G3.53"
				( objectStatus "@baseboard_fab2_lib.baseboard_fab2(sch_1):page81_i185:vss(70)" )
			)
			( pin "J1G3.50"
				( objectStatus "@baseboard_fab2_lib.baseboard_fab2(sch_1):page81_i185:vss(71)" )
			)
			( pin "J1G3.48"
				( objectStatus "@baseboard_fab2_lib.baseboard_fab2(sch_1):page81_i185:vss(72)" )
			)
			( pin "J1G3.46"
				( objectStatus "@baseboard_fab2_lib.baseboard_fab2(sch_1):page81_i185:vss(73)" )
			)
			( pin "J1G3.44"
				( objectStatus "@baseboard_fab2_lib.baseboard_fab2(sch_1):page81_i185:vss(74)" )
			)
			( pin "J1G3.42"
				( objectStatus "@baseboard_fab2_lib.baseboard_fab2(sch_1):page81_i185:vss(75)" )
			)
			( pin "J1G3.39"
				( objectStatus "@baseboard_fab2_lib.baseboard_fab2(sch_1):page81_i185:vss(76)" )
			)
			( pin "J1G3.37"
				( objectStatus "@baseboard_fab2_lib.baseboard_fab2(sch_1):page81_i185:vss(77)" )
			)
			( pin "J1G3.35"
				( objectStatus "@baseboard_fab2_lib.baseboard_fab2(sch_1):page81_i185:vss(78)" )
			)
			( pin "J1G3.33"
				( objectStatus "@baseboard_fab2_lib.baseboard_fab2(sch_1):page81_i185:vss(79)" )
			)
			( pin "J1G3.31"
				( objectStatus "@baseboard_fab2_lib.baseboard_fab2(sch_1):page81_i185:vss(80)" )
			)
			( pin "J1G3.28"
				( objectStatus "@baseboard_fab2_lib.baseboard_fab2(sch_1):page81_i185:vss(81)" )
			)
			( pin "J1G3.26"
				( objectStatus "@baseboard_fab2_lib.baseboard_fab2(sch_1):page81_i185:vss(82)" )
			)
			( pin "J1G3.24"
				( objectStatus "@baseboard_fab2_lib.baseboard_fab2(sch_1):page81_i185:vss(83)" )
			)
			( pin "J1G3.22"
				( objectStatus "@baseboard_fab2_lib.baseboard_fab2(sch_1):page81_i185:vss(84)" )
			)
			( pin "J1G3.20"
				( objectStatus "@baseboard_fab2_lib.baseboard_fab2(sch_1):page81_i185:vss(85)" )
			)
			( pin "J1G3.17"
				( objectStatus "@baseboard_fab2_lib.baseboard_fab2(sch_1):page81_i185:vss(86)" )
			)
			( pin "J1G3.15"
				( objectStatus "@baseboard_fab2_lib.baseboard_fab2(sch_1):page81_i185:vss(87)" )
			)
			( pin "J1G3.13"
				( objectStatus "@baseboard_fab2_lib.baseboard_fab2(sch_1):page81_i185:vss(88)" )
			)
			( pin "J1G3.11"
				( objectStatus "@baseboard_fab2_lib.baseboard_fab2(sch_1):page81_i185:vss(89)" )
			)
			( pin "J1G3.9"
				( objectStatus "@baseboard_fab2_lib.baseboard_fab2(sch_1):page81_i185:vss(90)" )
			)
			( pin "J1G3.6"
				( objectStatus "@baseboard_fab2_lib.baseboard_fab2(sch_1):page81_i185:vss(91)" )
			)
			( pin "J1G3.4"
				( objectStatus "@baseboard_fab2_lib.baseboard_fab2(sch_1):page81_i185:vss(92)" )
			)
			( pin "J1G3.2"
				( objectStatus "@baseboard_fab2_lib.baseboard_fab2(sch_1):page81_i185:vss(93)" )
			)
			( pin "J1G3.79"
				( objectStatus "@baseboard_fab2_lib.baseboard_fab2(sch_1):page81_i186:a0" )
			)
			( pin "J1G3.72"
				( objectStatus "@baseboard_fab2_lib.baseboard_fab2(sch_1):page81_i186:a1" )
			)
			( pin "J1G3.216"
				( objectStatus "@baseboard_fab2_lib.baseboard_fab2(sch_1):page81_i186:a2" )
			)
			( pin "J1G3.71"
				( objectStatus "@baseboard_fab2_lib.baseboard_fab2(sch_1):page81_i186:a3" )
			)
			( pin "J1G3.214"
				( objectStatus "@baseboard_fab2_lib.baseboard_fab2(sch_1):page81_i186:a4" )
			)
			( pin "J1G3.213"
				( objectStatus "@baseboard_fab2_lib.baseboard_fab2(sch_1):page81_i186:a5" )
			)
			( pin "J1G3.69"
				( objectStatus "@baseboard_fab2_lib.baseboard_fab2(sch_1):page81_i186:a6" )
			)
			( pin "J1G3.211"
				( objectStatus "@baseboard_fab2_lib.baseboard_fab2(sch_1):page81_i186:a7" )
			)
			( pin "J1G3.68"
				( objectStatus "@baseboard_fab2_lib.baseboard_fab2(sch_1):page81_i186:a8" )
			)
			( pin "J1G3.66"
				( objectStatus "@baseboard_fab2_lib.baseboard_fab2(sch_1):page81_i186:a9" )
			)
			( pin "J1G3.225"
				( objectStatus "@baseboard_fab2_lib.baseboard_fab2(sch_1):page81_i186:a10" )
			)
			( pin "J1G3.210"
				( objectStatus "@baseboard_fab2_lib.baseboard_fab2(sch_1):page81_i186:a11" )
			)
			( pin "J1G3.65"
				( objectStatus "@baseboard_fab2_lib.baseboard_fab2(sch_1):page81_i186:a12" )
			)
			( pin "J1G3.232"
				( objectStatus "@baseboard_fab2_lib.baseboard_fab2(sch_1):page81_i186:a13" )
			)
			( pin "J1G3.228"
				( objectStatus "@baseboard_fab2_lib.baseboard_fab2(sch_1):page81_i186:a14_we_n" )
			)
			( pin "J1G3.86"
				( objectStatus "@baseboard_fab2_lib.baseboard_fab2(sch_1):page81_i186:a15_cas_n" )
			)
			( pin "J1G3.82"
				( objectStatus "@baseboard_fab2_lib.baseboard_fab2(sch_1):page81_i186:a16_ras_n" )
			)
			( pin "J1G3.234"
				( objectStatus "@baseboard_fab2_lib.baseboard_fab2(sch_1):page81_i186:a17" )
			)
			( pin "J1G3.62"
				( objectStatus "@baseboard_fab2_lib.baseboard_fab2(sch_1):page81_i186:act_n" )
			)
			( pin "J1G3.208"
				( objectStatus "@baseboard_fab2_lib.baseboard_fab2(sch_1):page81_i186:alert_n" )
			)
			( pin "J1G3.81"
				( objectStatus "@baseboard_fab2_lib.baseboard_fab2(sch_1):page81_i186:ba(0)" )
			)
			( pin "J1G3.224"
				( objectStatus "@baseboard_fab2_lib.baseboard_fab2(sch_1):page81_i186:ba(1)" )
			)
			( pin "J1G3.63"
				( objectStatus "@baseboard_fab2_lib.baseboard_fab2(sch_1):page81_i186:bg(0)" )
			)
			( pin "J1G3.207"
				( objectStatus "@baseboard_fab2_lib.baseboard_fab2(sch_1):page81_i186:bg(1)" )
			)
			( pin "J1G3.235"
				( objectStatus "@baseboard_fab2_lib.baseboard_fab2(sch_1):page81_i186:c(2)" )
			)
			( pin "J1G3.49"
				( objectStatus "@baseboard_fab2_lib.baseboard_fab2(sch_1):page81_i186:cb(0)" )
			)
			( pin "J1G3.194"
				( objectStatus "@baseboard_fab2_lib.baseboard_fab2(sch_1):page81_i186:cb(1)" )
			)
			( pin "J1G3.56"
				( objectStatus "@baseboard_fab2_lib.baseboard_fab2(sch_1):page81_i186:cb(2)" )
			)
			( pin "J1G3.201"
				( objectStatus "@baseboard_fab2_lib.baseboard_fab2(sch_1):page81_i186:cb(3)" )
			)
			( pin "J1G3.47"
				( objectStatus "@baseboard_fab2_lib.baseboard_fab2(sch_1):page81_i186:cb(4)" )
			)
			( pin "J1G3.192"
				( objectStatus "@baseboard_fab2_lib.baseboard_fab2(sch_1):page81_i186:cb(5)" )
			)
			( pin "J1G3.54"
				( objectStatus "@baseboard_fab2_lib.baseboard_fab2(sch_1):page81_i186:cb(6)" )
			)
			( pin "J1G3.199"
				( objectStatus "@baseboard_fab2_lib.baseboard_fab2(sch_1):page81_i186:cb(7)" )
			)
			( pin "J1G3.75"
				( objectStatus "@baseboard_fab2_lib.baseboard_fab2(sch_1):page81_i186:ck0n" )
			)
			( pin "J1G3.74"
				( objectStatus "@baseboard_fab2_lib.baseboard_fab2(sch_1):page81_i186:ck0p" )
			)
			( pin "J1G3.219"
				( objectStatus "@baseboard_fab2_lib.baseboard_fab2(sch_1):page81_i186:ck1n" )
			)
			( pin "J1G3.218"
				( objectStatus "@baseboard_fab2_lib.baseboard_fab2(sch_1):page81_i186:ck1p" )
			)
			( pin "J1G3.60"
				( objectStatus "@baseboard_fab2_lib.baseboard_fab2(sch_1):page81_i186:cke(0)" )
			)
			( pin "J1G3.203"
				( objectStatus "@baseboard_fab2_lib.baseboard_fab2(sch_1):page81_i186:cke(1)" )
			)
			( pin "J1G3.5"
				( objectStatus "@baseboard_fab2_lib.baseboard_fab2(sch_1):page81_i186:dq(0)" )
			)
			( pin "J1G3.150"
				( objectStatus "@baseboard_fab2_lib.baseboard_fab2(sch_1):page81_i186:dq(1)" )
			)
			( pin "J1G3.12"
				( objectStatus "@baseboard_fab2_lib.baseboard_fab2(sch_1):page81_i186:dq(2)" )
			)
			( pin "J1G3.157"
				( objectStatus "@baseboard_fab2_lib.baseboard_fab2(sch_1):page81_i186:dq(3)" )
			)
			( pin "J1G3.3"
				( objectStatus "@baseboard_fab2_lib.baseboard_fab2(sch_1):page81_i186:dq(4)" )
			)
			( pin "J1G3.148"
				( objectStatus "@baseboard_fab2_lib.baseboard_fab2(sch_1):page81_i186:dq(5)" )
			)
			( pin "J1G3.10"
				( objectStatus "@baseboard_fab2_lib.baseboard_fab2(sch_1):page81_i186:dq(6)" )
			)
			( pin "J1G3.155"
				( objectStatus "@baseboard_fab2_lib.baseboard_fab2(sch_1):page81_i186:dq(7)" )
			)
			( pin "J1G3.16"
				( objectStatus "@baseboard_fab2_lib.baseboard_fab2(sch_1):page81_i186:dq(8)" )
			)
			( pin "J1G3.161"
				( objectStatus "@baseboard_fab2_lib.baseboard_fab2(sch_1):page81_i186:dq(9)" )
			)
			( pin "J1G3.23"
				( objectStatus "@baseboard_fab2_lib.baseboard_fab2(sch_1):page81_i186:dq(10)" )
			)
			( pin "J1G3.168"
				( objectStatus "@baseboard_fab2_lib.baseboard_fab2(sch_1):page81_i186:dq(11)" )
			)
			( pin "J1G3.14"
				( objectStatus "@baseboard_fab2_lib.baseboard_fab2(sch_1):page81_i186:dq(12)" )
			)
			( pin "J1G3.159"
				( objectStatus "@baseboard_fab2_lib.baseboard_fab2(sch_1):page81_i186:dq(13)" )
			)
			( pin "J1G3.21"
				( objectStatus "@baseboard_fab2_lib.baseboard_fab2(sch_1):page81_i186:dq(14)" )
			)
			( pin "J1G3.166"
				( objectStatus "@baseboard_fab2_lib.baseboard_fab2(sch_1):page81_i186:dq(15)" )
			)
			( pin "J1G3.27"
				( objectStatus "@baseboard_fab2_lib.baseboard_fab2(sch_1):page81_i186:dq(16)" )
			)
			( pin "J1G3.172"
				( objectStatus "@baseboard_fab2_lib.baseboard_fab2(sch_1):page81_i186:dq(17)" )
			)
			( pin "J1G3.34"
				( objectStatus "@baseboard_fab2_lib.baseboard_fab2(sch_1):page81_i186:dq(18)" )
			)
			( pin "J1G3.179"
				( objectStatus "@baseboard_fab2_lib.baseboard_fab2(sch_1):page81_i186:dq(19)" )
			)
			( pin "J1G3.25"
				( objectStatus "@baseboard_fab2_lib.baseboard_fab2(sch_1):page81_i186:dq(20)" )
			)
			( pin "J1G3.170"
				( objectStatus "@baseboard_fab2_lib.baseboard_fab2(sch_1):page81_i186:dq(21)" )
			)
			( pin "J1G3.32"
				( objectStatus "@baseboard_fab2_lib.baseboard_fab2(sch_1):page81_i186:dq(22)" )
			)
			( pin "J1G3.177"
				( objectStatus "@baseboard_fab2_lib.baseboard_fab2(sch_1):page81_i186:dq(23)" )
			)
			( pin "J1G3.38"
				( objectStatus "@baseboard_fab2_lib.baseboard_fab2(sch_1):page81_i186:dq(24)" )
			)
			( pin "J1G3.183"
				( objectStatus "@baseboard_fab2_lib.baseboard_fab2(sch_1):page81_i186:dq(25)" )
			)
			( pin "J1G3.45"
				( objectStatus "@baseboard_fab2_lib.baseboard_fab2(sch_1):page81_i186:dq(26)" )
			)
			( pin "J1G3.190"
				( objectStatus "@baseboard_fab2_lib.baseboard_fab2(sch_1):page81_i186:dq(27)" )
			)
			( pin "J1G3.36"
				( objectStatus "@baseboard_fab2_lib.baseboard_fab2(sch_1):page81_i186:dq(28)" )
			)
			( pin "J1G3.181"
				( objectStatus "@baseboard_fab2_lib.baseboard_fab2(sch_1):page81_i186:dq(29)" )
			)
			( pin "J1G3.43"
				( objectStatus "@baseboard_fab2_lib.baseboard_fab2(sch_1):page81_i186:dq(30)" )
			)
			( pin "J1G3.188"
				( objectStatus "@baseboard_fab2_lib.baseboard_fab2(sch_1):page81_i186:dq(31)" )
			)
			( pin "J1G3.97"
				( objectStatus "@baseboard_fab2_lib.baseboard_fab2(sch_1):page81_i186:dq(32)" )
			)
			( pin "J1G3.242"
				( objectStatus "@baseboard_fab2_lib.baseboard_fab2(sch_1):page81_i186:dq(33)" )
			)
			( pin "J1G3.104"
				( objectStatus "@baseboard_fab2_lib.baseboard_fab2(sch_1):page81_i186:dq(34)" )
			)
			( pin "J1G3.249"
				( objectStatus "@baseboard_fab2_lib.baseboard_fab2(sch_1):page81_i186:dq(35)" )
			)
			( pin "J1G3.95"
				( objectStatus "@baseboard_fab2_lib.baseboard_fab2(sch_1):page81_i186:dq(36)" )
			)
			( pin "J1G3.240"
				( objectStatus "@baseboard_fab2_lib.baseboard_fab2(sch_1):page81_i186:dq(37)" )
			)
			( pin "J1G3.102"
				( objectStatus "@baseboard_fab2_lib.baseboard_fab2(sch_1):page81_i186:dq(38)" )
			)
			( pin "J1G3.247"
				( objectStatus "@baseboard_fab2_lib.baseboard_fab2(sch_1):page81_i186:dq(39)" )
			)
			( pin "J1G3.108"
				( objectStatus "@baseboard_fab2_lib.baseboard_fab2(sch_1):page81_i186:dq(40)" )
			)
			( pin "J1G3.253"
				( objectStatus "@baseboard_fab2_lib.baseboard_fab2(sch_1):page81_i186:dq(41)" )
			)
			( pin "J1G3.115"
				( objectStatus "@baseboard_fab2_lib.baseboard_fab2(sch_1):page81_i186:dq(42)" )
			)
			( pin "J1G3.260"
				( objectStatus "@baseboard_fab2_lib.baseboard_fab2(sch_1):page81_i186:dq(43)" )
			)
			( pin "J1G3.106"
				( objectStatus "@baseboard_fab2_lib.baseboard_fab2(sch_1):page81_i186:dq(44)" )
			)
			( pin "J1G3.251"
				( objectStatus "@baseboard_fab2_lib.baseboard_fab2(sch_1):page81_i186:dq(45)" )
			)
			( pin "J1G3.113"
				( objectStatus "@baseboard_fab2_lib.baseboard_fab2(sch_1):page81_i186:dq(46)" )
			)
			( pin "J1G3.258"
				( objectStatus "@baseboard_fab2_lib.baseboard_fab2(sch_1):page81_i186:dq(47)" )
			)
			( pin "J1G3.119"
				( objectStatus "@baseboard_fab2_lib.baseboard_fab2(sch_1):page81_i186:dq(48)" )
			)
			( pin "J1G3.264"
				( objectStatus "@baseboard_fab2_lib.baseboard_fab2(sch_1):page81_i186:dq(49)" )
			)
			( pin "J1G3.126"
				( objectStatus "@baseboard_fab2_lib.baseboard_fab2(sch_1):page81_i186:dq(50)" )
			)
			( pin "J1G3.271"
				( objectStatus "@baseboard_fab2_lib.baseboard_fab2(sch_1):page81_i186:dq(51)" )
			)
			( pin "J1G3.117"
				( objectStatus "@baseboard_fab2_lib.baseboard_fab2(sch_1):page81_i186:dq(52)" )
			)
			( pin "J1G3.262"
				( objectStatus "@baseboard_fab2_lib.baseboard_fab2(sch_1):page81_i186:dq(53)" )
			)
			( pin "J1G3.124"
				( objectStatus "@baseboard_fab2_lib.baseboard_fab2(sch_1):page81_i186:dq(54)" )
			)
			( pin "J1G3.269"
				( objectStatus "@baseboard_fab2_lib.baseboard_fab2(sch_1):page81_i186:dq(55)" )
			)
			( pin "J1G3.130"
				( objectStatus "@baseboard_fab2_lib.baseboard_fab2(sch_1):page81_i186:dq(56)" )
			)
			( pin "J1G3.275"
				( objectStatus "@baseboard_fab2_lib.baseboard_fab2(sch_1):page81_i186:dq(57)" )
			)
			( pin "J1G3.137"
				( objectStatus "@baseboard_fab2_lib.baseboard_fab2(sch_1):page81_i186:dq(58)" )
			)
			( pin "J1G3.282"
				( objectStatus "@baseboard_fab2_lib.baseboard_fab2(sch_1):page81_i186:dq(59)" )
			)
			( pin "J1G3.128"
				( objectStatus "@baseboard_fab2_lib.baseboard_fab2(sch_1):page81_i186:dq(60)" )
			)
			( pin "J1G3.273"
				( objectStatus "@baseboard_fab2_lib.baseboard_fab2(sch_1):page81_i186:dq(61)" )
			)
			( pin "J1G3.135"
				( objectStatus "@baseboard_fab2_lib.baseboard_fab2(sch_1):page81_i186:dq(62)" )
			)
			( pin "J1G3.280"
				( objectStatus "@baseboard_fab2_lib.baseboard_fab2(sch_1):page81_i186:dq(63)" )
			)
			( pin "J1G3.78"
				( objectStatus "@baseboard_fab2_lib.baseboard_fab2(sch_1):page81_i186:event_n" )
			)
			( pin "J1G3.87"
				( objectStatus "@baseboard_fab2_lib.baseboard_fab2(sch_1):page81_i186:odt(0)" )
			)
			( pin "J1G3.91"
				( objectStatus "@baseboard_fab2_lib.baseboard_fab2(sch_1):page81_i186:odt(1)" )
			)
			( pin "J1G3.222"
				( objectStatus "@baseboard_fab2_lib.baseboard_fab2(sch_1):page81_i186:par" )
			)
			( pin "J1G3.58"
				( objectStatus "@baseboard_fab2_lib.baseboard_fab2(sch_1):page81_i186:reset_n" )
			)
			( pin "J1G3.205"
				( objectStatus "@baseboard_fab2_lib.baseboard_fab2(sch_1):page81_i186:rfu(0)" )
			)
			( pin "J1G3.227"
				( objectStatus "@baseboard_fab2_lib.baseboard_fab2(sch_1):page81_i186:rfu(1)" )
			)
			( pin "J1G3.144"
				( objectStatus "@baseboard_fab2_lib.baseboard_fab2(sch_1):page81_i186:rfu(2)" )
			)
			( pin "J1G3.84"
				( objectStatus "@baseboard_fab2_lib.baseboard_fab2(sch_1):page81_i186:s0_n" )
			)
			( pin "J1G3.89"
				( objectStatus "@baseboard_fab2_lib.baseboard_fab2(sch_1):page81_i186:s1_n" )
			)
			( pin "J1G3.93"
				( objectStatus "@baseboard_fab2_lib.baseboard_fab2(sch_1):page81_i186:s2_n_c(0)" )
			)
			( pin "J1G3.237"
				( objectStatus "@baseboard_fab2_lib.baseboard_fab2(sch_1):page81_i186:s3_n_c(1)" )
			)
			( pin "J1G3.139"
				( objectStatus "@baseboard_fab2_lib.baseboard_fab2(sch_1):page81_i186:sa(0)" )
			)
			( pin "J1G3.140"
				( objectStatus "@baseboard_fab2_lib.baseboard_fab2(sch_1):page81_i186:sa(1)" )
			)
			( pin "J1G3.238"
				( objectStatus "@baseboard_fab2_lib.baseboard_fab2(sch_1):page81_i186:sa(2)" )
			)
			( pin "J1G3.230"
				( objectStatus "@baseboard_fab2_lib.baseboard_fab2(sch_1):page81_i186:save_n_nc" )
			)
			( pin "J1G3.141"
				( objectStatus "@baseboard_fab2_lib.baseboard_fab2(sch_1):page81_i186:scl" )
			)
			( pin "J1G3.285"
				( objectStatus "@baseboard_fab2_lib.baseboard_fab2(sch_1):page81_i186:sda" )
			)
			( pin "J1G3.284"
				( objectStatus "@baseboard_fab2_lib.baseboard_fab2(sch_1):page81_i186:vddspd" )
			)
			( pin "J1G3.146"
				( objectStatus "@baseboard_fab2_lib.baseboard_fab2(sch_1):page81_i186:vrefca" )
			)
			( pin "J9U2.152"
				( objectStatus "@baseboard_fab2_lib.baseboard_fab2(sch_1):page82_i64:dqs0n" )
			)
			( pin "J9U2.153"
				( objectStatus "@baseboard_fab2_lib.baseboard_fab2(sch_1):page82_i64:dqs0p" )
			)
			( pin "J9U2.163"
				( objectStatus "@baseboard_fab2_lib.baseboard_fab2(sch_1):page82_i64:dqs1n" )
			)
			( pin "J9U2.164"
				( objectStatus "@baseboard_fab2_lib.baseboard_fab2(sch_1):page82_i64:dqs1p" )
			)
			( pin "J9U2.174"
				( objectStatus "@baseboard_fab2_lib.baseboard_fab2(sch_1):page82_i64:dqs2n" )
			)
			( pin "J9U2.175"
				( objectStatus "@baseboard_fab2_lib.baseboard_fab2(sch_1):page82_i64:dqs2p" )
			)
			( pin "J9U2.185"
				( objectStatus "@baseboard_fab2_lib.baseboard_fab2(sch_1):page82_i64:dqs3n" )
			)
			( pin "J9U2.186"
				( objectStatus "@baseboard_fab2_lib.baseboard_fab2(sch_1):page82_i64:dqs3p" )
			)
			( pin "J9U2.244"
				( objectStatus "@baseboard_fab2_lib.baseboard_fab2(sch_1):page82_i64:dqs4n" )
			)
			( pin "J9U2.245"
				( objectStatus "@baseboard_fab2_lib.baseboard_fab2(sch_1):page82_i64:dqs4p" )
			)
			( pin "J9U2.255"
				( objectStatus "@baseboard_fab2_lib.baseboard_fab2(sch_1):page82_i64:dqs5n" )
			)
			( pin "J9U2.256"
				( objectStatus "@baseboard_fab2_lib.baseboard_fab2(sch_1):page82_i64:dqs5p" )
			)
			( pin "J9U2.266"
				( objectStatus "@baseboard_fab2_lib.baseboard_fab2(sch_1):page82_i64:dqs6n" )
			)
			( pin "J9U2.267"
				( objectStatus "@baseboard_fab2_lib.baseboard_fab2(sch_1):page82_i64:dqs6p" )
			)
			( pin "J9U2.277"
				( objectStatus "@baseboard_fab2_lib.baseboard_fab2(sch_1):page82_i64:dqs7n" )
			)
			( pin "J9U2.278"
				( objectStatus "@baseboard_fab2_lib.baseboard_fab2(sch_1):page82_i64:dqs7p" )
			)
			( pin "J9U2.196"
				( objectStatus "@baseboard_fab2_lib.baseboard_fab2(sch_1):page82_i64:dqs8n" )
			)
			( pin "J9U2.197"
				( objectStatus "@baseboard_fab2_lib.baseboard_fab2(sch_1):page82_i64:dqs8p" )
			)
			( pin "J9U2.8"
				( objectStatus "@baseboard_fab2_lib.baseboard_fab2(sch_1):page82_i64:dqs9n" )
			)
			( pin "J9U2.7"
				( objectStatus "@baseboard_fab2_lib.baseboard_fab2(sch_1):page82_i64:dqs9p" )
			)
			( pin "J9U2.19"
				( objectStatus "@baseboard_fab2_lib.baseboard_fab2(sch_1):page82_i64:dqs10n" )
			)
			( pin "J9U2.18"
				( objectStatus "@baseboard_fab2_lib.baseboard_fab2(sch_1):page82_i64:dqs10p" )
			)
			( pin "J9U2.30"
				( objectStatus "@baseboard_fab2_lib.baseboard_fab2(sch_1):page82_i64:dqs11n" )
			)
			( pin "J9U2.29"
				( objectStatus "@baseboard_fab2_lib.baseboard_fab2(sch_1):page82_i64:dqs11p" )
			)
			( pin "J9U2.41"
				( objectStatus "@baseboard_fab2_lib.baseboard_fab2(sch_1):page82_i64:dqs12n" )
			)
			( pin "J9U2.40"
				( objectStatus "@baseboard_fab2_lib.baseboard_fab2(sch_1):page82_i64:dqs12p" )
			)
			( pin "J9U2.100"
				( objectStatus "@baseboard_fab2_lib.baseboard_fab2(sch_1):page82_i64:dqs13n" )
			)
			( pin "J9U2.99"
				( objectStatus "@baseboard_fab2_lib.baseboard_fab2(sch_1):page82_i64:dqs13p" )
			)
			( pin "J9U2.111"
				( objectStatus "@baseboard_fab2_lib.baseboard_fab2(sch_1):page82_i64:dqs14n" )
			)
			( pin "J9U2.110"
				( objectStatus "@baseboard_fab2_lib.baseboard_fab2(sch_1):page82_i64:dqs14p" )
			)
			( pin "J9U2.122"
				( objectStatus "@baseboard_fab2_lib.baseboard_fab2(sch_1):page82_i64:dqs15n" )
			)
			( pin "J9U2.121"
				( objectStatus "@baseboard_fab2_lib.baseboard_fab2(sch_1):page82_i64:dqs15p" )
			)
			( pin "J9U2.133"
				( objectStatus "@baseboard_fab2_lib.baseboard_fab2(sch_1):page82_i64:dqs16n" )
			)
			( pin "J9U2.132"
				( objectStatus "@baseboard_fab2_lib.baseboard_fab2(sch_1):page82_i64:dqs16p" )
			)
			( pin "J9U2.52"
				( objectStatus "@baseboard_fab2_lib.baseboard_fab2(sch_1):page82_i64:dqs17n" )
			)
			( pin "J9U2.51"
				( objectStatus "@baseboard_fab2_lib.baseboard_fab2(sch_1):page82_i64:dqs17p" )
			)
			( pin "J9U2.145"
				( objectStatus "@baseboard_fab2_lib.baseboard_fab2(sch_1):page82_i171:\12v\(0)" )
			)
			( pin "J9U2.1"
				( objectStatus "@baseboard_fab2_lib.baseboard_fab2(sch_1):page82_i171:\12v\(1)" )
			)
			( pin "J9U2.236"
				( objectStatus "@baseboard_fab2_lib.baseboard_fab2(sch_1):page82_i171:vdd(0)" )
			)
			( pin "J9U2.233"
				( objectStatus "@baseboard_fab2_lib.baseboard_fab2(sch_1):page82_i171:vdd(1)" )
			)
			( pin "J9U2.231"
				( objectStatus "@baseboard_fab2_lib.baseboard_fab2(sch_1):page82_i171:vdd(2)" )
			)
			( pin "J9U2.229"
				( objectStatus "@baseboard_fab2_lib.baseboard_fab2(sch_1):page82_i171:vdd(3)" )
			)
			( pin "J9U2.226"
				( objectStatus "@baseboard_fab2_lib.baseboard_fab2(sch_1):page82_i171:vdd(4)" )
			)
			( pin "J9U2.223"
				( objectStatus "@baseboard_fab2_lib.baseboard_fab2(sch_1):page82_i171:vdd(5)" )
			)
			( pin "J9U2.220"
				( objectStatus "@baseboard_fab2_lib.baseboard_fab2(sch_1):page82_i171:vdd(6)" )
			)
			( pin "J9U2.217"
				( objectStatus "@baseboard_fab2_lib.baseboard_fab2(sch_1):page82_i171:vdd(7)" )
			)
			( pin "J9U2.215"
				( objectStatus "@baseboard_fab2_lib.baseboard_fab2(sch_1):page82_i171:vdd(8)" )
			)
			( pin "J9U2.212"
				( objectStatus "@baseboard_fab2_lib.baseboard_fab2(sch_1):page82_i171:vdd(9)" )
			)
			( pin "J9U2.209"
				( objectStatus "@baseboard_fab2_lib.baseboard_fab2(sch_1):page82_i171:vdd(10)" )
			)
			( pin "J9U2.206"
				( objectStatus "@baseboard_fab2_lib.baseboard_fab2(sch_1):page82_i171:vdd(11)" )
			)
			( pin "J9U2.204"
				( objectStatus "@baseboard_fab2_lib.baseboard_fab2(sch_1):page82_i171:vdd(12)" )
			)
			( pin "J9U2.92"
				( objectStatus "@baseboard_fab2_lib.baseboard_fab2(sch_1):page82_i171:vdd(13)" )
			)
			( pin "J9U2.90"
				( objectStatus "@baseboard_fab2_lib.baseboard_fab2(sch_1):page82_i171:vdd(14)" )
			)
			( pin "J9U2.88"
				( objectStatus "@baseboard_fab2_lib.baseboard_fab2(sch_1):page82_i171:vdd(15)" )
			)
			( pin "J9U2.85"
				( objectStatus "@baseboard_fab2_lib.baseboard_fab2(sch_1):page82_i171:vdd(16)" )
			)
			( pin "J9U2.83"
				( objectStatus "@baseboard_fab2_lib.baseboard_fab2(sch_1):page82_i171:vdd(17)" )
			)
			( pin "J9U2.80"
				( objectStatus "@baseboard_fab2_lib.baseboard_fab2(sch_1):page82_i171:vdd(18)" )
			)
			( pin "J9U2.76"
				( objectStatus "@baseboard_fab2_lib.baseboard_fab2(sch_1):page82_i171:vdd(19)" )
			)
			( pin "J9U2.73"
				( objectStatus "@baseboard_fab2_lib.baseboard_fab2(sch_1):page82_i171:vdd(20)" )
			)
			( pin "J9U2.70"
				( objectStatus "@baseboard_fab2_lib.baseboard_fab2(sch_1):page82_i171:vdd(21)" )
			)
			( pin "J9U2.67"
				( objectStatus "@baseboard_fab2_lib.baseboard_fab2(sch_1):page82_i171:vdd(22)" )
			)
			( pin "J9U2.64"
				( objectStatus "@baseboard_fab2_lib.baseboard_fab2(sch_1):page82_i171:vdd(23)" )
			)
			( pin "J9U2.61"
				( objectStatus "@baseboard_fab2_lib.baseboard_fab2(sch_1):page82_i171:vdd(24)" )
			)
			( pin "J9U2.59"
				( objectStatus "@baseboard_fab2_lib.baseboard_fab2(sch_1):page82_i171:vdd(25)" )
			)
			( pin "J9U2.287"
				( objectStatus "@baseboard_fab2_lib.baseboard_fab2(sch_1):page82_i171:vpp(0)" )
			)
			( pin "J9U2.286"
				( objectStatus "@baseboard_fab2_lib.baseboard_fab2(sch_1):page82_i171:vpp(1)" )
			)
			( pin "J9U2.288"
				( objectStatus "@baseboard_fab2_lib.baseboard_fab2(sch_1):page82_i171:vpp(2)" )
			)
			( pin "J9U2.143"
				( objectStatus "@baseboard_fab2_lib.baseboard_fab2(sch_1):page82_i171:vpp(3)" )
			)
			( pin "J9U2.142"
				( objectStatus "@baseboard_fab2_lib.baseboard_fab2(sch_1):page82_i171:vpp(4)" )
			)
			( pin "J9U2.221"
				( objectStatus "@baseboard_fab2_lib.baseboard_fab2(sch_1):page82_i171:vtt(0)" )
			)
			( pin "J9U2.77"
				( objectStatus "@baseboard_fab2_lib.baseboard_fab2(sch_1):page82_i171:vtt(1)" )
			)
			( pin "C1G19.1"
				( objectStatus "@baseboard_fab2_lib.baseboard_fab2(sch_1):page82_i180:a" )
			)
			( pin "C1G19.2"
				( objectStatus "@baseboard_fab2_lib.baseboard_fab2(sch_1):page82_i180:b" )
			)
			( pin "J9U2.79"
				( objectStatus "@baseboard_fab2_lib.baseboard_fab2(sch_1):page82_i187:a0" )
			)
			( pin "J9U2.72"
				( objectStatus "@baseboard_fab2_lib.baseboard_fab2(sch_1):page82_i187:a1" )
			)
			( pin "J9U2.216"
				( objectStatus "@baseboard_fab2_lib.baseboard_fab2(sch_1):page82_i187:a2" )
			)
			( pin "J9U2.71"
				( objectStatus "@baseboard_fab2_lib.baseboard_fab2(sch_1):page82_i187:a3" )
			)
			( pin "J9U2.214"
				( objectStatus "@baseboard_fab2_lib.baseboard_fab2(sch_1):page82_i187:a4" )
			)
			( pin "J9U2.213"
				( objectStatus "@baseboard_fab2_lib.baseboard_fab2(sch_1):page82_i187:a5" )
			)
			( pin "J9U2.69"
				( objectStatus "@baseboard_fab2_lib.baseboard_fab2(sch_1):page82_i187:a6" )
			)
			( pin "J9U2.211"
				( objectStatus "@baseboard_fab2_lib.baseboard_fab2(sch_1):page82_i187:a7" )
			)
			( pin "J9U2.68"
				( objectStatus "@baseboard_fab2_lib.baseboard_fab2(sch_1):page82_i187:a8" )
			)
			( pin "J9U2.66"
				( objectStatus "@baseboard_fab2_lib.baseboard_fab2(sch_1):page82_i187:a9" )
			)
			( pin "J9U2.225"
				( objectStatus "@baseboard_fab2_lib.baseboard_fab2(sch_1):page82_i187:a10" )
			)
			( pin "J9U2.210"
				( objectStatus "@baseboard_fab2_lib.baseboard_fab2(sch_1):page82_i187:a11" )
			)
			( pin "J9U2.65"
				( objectStatus "@baseboard_fab2_lib.baseboard_fab2(sch_1):page82_i187:a12" )
			)
			( pin "J9U2.232"
				( objectStatus "@baseboard_fab2_lib.baseboard_fab2(sch_1):page82_i187:a13" )
			)
			( pin "J9U2.228"
				( objectStatus "@baseboard_fab2_lib.baseboard_fab2(sch_1):page82_i187:a14_we_n" )
			)
			( pin "J9U2.86"
				( objectStatus "@baseboard_fab2_lib.baseboard_fab2(sch_1):page82_i187:a15_cas_n" )
			)
			( pin "J9U2.82"
				( objectStatus "@baseboard_fab2_lib.baseboard_fab2(sch_1):page82_i187:a16_ras_n" )
			)
			( pin "J9U2.234"
				( objectStatus "@baseboard_fab2_lib.baseboard_fab2(sch_1):page82_i187:a17" )
			)
			( pin "J9U2.62"
				( objectStatus "@baseboard_fab2_lib.baseboard_fab2(sch_1):page82_i187:act_n" )
			)
			( pin "J9U2.208"
				( objectStatus "@baseboard_fab2_lib.baseboard_fab2(sch_1):page82_i187:alert_n" )
			)
			( pin "J9U2.81"
				( objectStatus "@baseboard_fab2_lib.baseboard_fab2(sch_1):page82_i187:ba(0)" )
			)
			( pin "J9U2.224"
				( objectStatus "@baseboard_fab2_lib.baseboard_fab2(sch_1):page82_i187:ba(1)" )
			)
			( pin "J9U2.63"
				( objectStatus "@baseboard_fab2_lib.baseboard_fab2(sch_1):page82_i187:bg(0)" )
			)
			( pin "J9U2.207"
				( objectStatus "@baseboard_fab2_lib.baseboard_fab2(sch_1):page82_i187:bg(1)" )
			)
			( pin "J9U2.235"
				( objectStatus "@baseboard_fab2_lib.baseboard_fab2(sch_1):page82_i187:c(2)" )
			)
			( pin "J9U2.49"
				( objectStatus "@baseboard_fab2_lib.baseboard_fab2(sch_1):page82_i187:cb(0)" )
			)
			( pin "J9U2.194"
				( objectStatus "@baseboard_fab2_lib.baseboard_fab2(sch_1):page82_i187:cb(1)" )
			)
			( pin "J9U2.56"
				( objectStatus "@baseboard_fab2_lib.baseboard_fab2(sch_1):page82_i187:cb(2)" )
			)
			( pin "J9U2.201"
				( objectStatus "@baseboard_fab2_lib.baseboard_fab2(sch_1):page82_i187:cb(3)" )
			)
			( pin "J9U2.47"
				( objectStatus "@baseboard_fab2_lib.baseboard_fab2(sch_1):page82_i187:cb(4)" )
			)
			( pin "J9U2.192"
				( objectStatus "@baseboard_fab2_lib.baseboard_fab2(sch_1):page82_i187:cb(5)" )
			)
			( pin "J9U2.54"
				( objectStatus "@baseboard_fab2_lib.baseboard_fab2(sch_1):page82_i187:cb(6)" )
			)
			( pin "J9U2.199"
				( objectStatus "@baseboard_fab2_lib.baseboard_fab2(sch_1):page82_i187:cb(7)" )
			)
			( pin "J9U2.75"
				( objectStatus "@baseboard_fab2_lib.baseboard_fab2(sch_1):page82_i187:ck0n" )
			)
			( pin "J9U2.74"
				( objectStatus "@baseboard_fab2_lib.baseboard_fab2(sch_1):page82_i187:ck0p" )
			)
			( pin "J9U2.219"
				( objectStatus "@baseboard_fab2_lib.baseboard_fab2(sch_1):page82_i187:ck1n" )
			)
			( pin "J9U2.218"
				( objectStatus "@baseboard_fab2_lib.baseboard_fab2(sch_1):page82_i187:ck1p" )
			)
			( pin "J9U2.60"
				( objectStatus "@baseboard_fab2_lib.baseboard_fab2(sch_1):page82_i187:cke(0)" )
			)
			( pin "J9U2.203"
				( objectStatus "@baseboard_fab2_lib.baseboard_fab2(sch_1):page82_i187:cke(1)" )
			)
			( pin "J9U2.5"
				( objectStatus "@baseboard_fab2_lib.baseboard_fab2(sch_1):page82_i187:dq(0)" )
			)
			( pin "J9U2.150"
				( objectStatus "@baseboard_fab2_lib.baseboard_fab2(sch_1):page82_i187:dq(1)" )
			)
			( pin "J9U2.12"
				( objectStatus "@baseboard_fab2_lib.baseboard_fab2(sch_1):page82_i187:dq(2)" )
			)
			( pin "J9U2.157"
				( objectStatus "@baseboard_fab2_lib.baseboard_fab2(sch_1):page82_i187:dq(3)" )
			)
			( pin "J9U2.3"
				( objectStatus "@baseboard_fab2_lib.baseboard_fab2(sch_1):page82_i187:dq(4)" )
			)
			( pin "J9U2.148"
				( objectStatus "@baseboard_fab2_lib.baseboard_fab2(sch_1):page82_i187:dq(5)" )
			)
			( pin "J9U2.10"
				( objectStatus "@baseboard_fab2_lib.baseboard_fab2(sch_1):page82_i187:dq(6)" )
			)
			( pin "J9U2.155"
				( objectStatus "@baseboard_fab2_lib.baseboard_fab2(sch_1):page82_i187:dq(7)" )
			)
			( pin "J9U2.16"
				( objectStatus "@baseboard_fab2_lib.baseboard_fab2(sch_1):page82_i187:dq(8)" )
			)
			( pin "J9U2.161"
				( objectStatus "@baseboard_fab2_lib.baseboard_fab2(sch_1):page82_i187:dq(9)" )
			)
			( pin "J9U2.23"
				( objectStatus "@baseboard_fab2_lib.baseboard_fab2(sch_1):page82_i187:dq(10)" )
			)
			( pin "J9U2.168"
				( objectStatus "@baseboard_fab2_lib.baseboard_fab2(sch_1):page82_i187:dq(11)" )
			)
			( pin "J9U2.14"
				( objectStatus "@baseboard_fab2_lib.baseboard_fab2(sch_1):page82_i187:dq(12)" )
			)
			( pin "J9U2.159"
				( objectStatus "@baseboard_fab2_lib.baseboard_fab2(sch_1):page82_i187:dq(13)" )
			)
			( pin "J9U2.21"
				( objectStatus "@baseboard_fab2_lib.baseboard_fab2(sch_1):page82_i187:dq(14)" )
			)
			( pin "J9U2.166"
				( objectStatus "@baseboard_fab2_lib.baseboard_fab2(sch_1):page82_i187:dq(15)" )
			)
			( pin "J9U2.27"
				( objectStatus "@baseboard_fab2_lib.baseboard_fab2(sch_1):page82_i187:dq(16)" )
			)
			( pin "J9U2.172"
				( objectStatus "@baseboard_fab2_lib.baseboard_fab2(sch_1):page82_i187:dq(17)" )
			)
			( pin "J9U2.34"
				( objectStatus "@baseboard_fab2_lib.baseboard_fab2(sch_1):page82_i187:dq(18)" )
			)
			( pin "J9U2.179"
				( objectStatus "@baseboard_fab2_lib.baseboard_fab2(sch_1):page82_i187:dq(19)" )
			)
			( pin "J9U2.25"
				( objectStatus "@baseboard_fab2_lib.baseboard_fab2(sch_1):page82_i187:dq(20)" )
			)
			( pin "J9U2.170"
				( objectStatus "@baseboard_fab2_lib.baseboard_fab2(sch_1):page82_i187:dq(21)" )
			)
			( pin "J9U2.32"
				( objectStatus "@baseboard_fab2_lib.baseboard_fab2(sch_1):page82_i187:dq(22)" )
			)
			( pin "J9U2.177"
				( objectStatus "@baseboard_fab2_lib.baseboard_fab2(sch_1):page82_i187:dq(23)" )
			)
			( pin "J9U2.38"
				( objectStatus "@baseboard_fab2_lib.baseboard_fab2(sch_1):page82_i187:dq(24)" )
			)
			( pin "J9U2.183"
				( objectStatus "@baseboard_fab2_lib.baseboard_fab2(sch_1):page82_i187:dq(25)" )
			)
			( pin "J9U2.45"
				( objectStatus "@baseboard_fab2_lib.baseboard_fab2(sch_1):page82_i187:dq(26)" )
			)
			( pin "J9U2.190"
				( objectStatus "@baseboard_fab2_lib.baseboard_fab2(sch_1):page82_i187:dq(27)" )
			)
			( pin "J9U2.36"
				( objectStatus "@baseboard_fab2_lib.baseboard_fab2(sch_1):page82_i187:dq(28)" )
			)
			( pin "J9U2.181"
				( objectStatus "@baseboard_fab2_lib.baseboard_fab2(sch_1):page82_i187:dq(29)" )
			)
			( pin "J9U2.43"
				( objectStatus "@baseboard_fab2_lib.baseboard_fab2(sch_1):page82_i187:dq(30)" )
			)
			( pin "J9U2.188"
				( objectStatus "@baseboard_fab2_lib.baseboard_fab2(sch_1):page82_i187:dq(31)" )
			)
			( pin "J9U2.97"
				( objectStatus "@baseboard_fab2_lib.baseboard_fab2(sch_1):page82_i187:dq(32)" )
			)
			( pin "J9U2.242"
				( objectStatus "@baseboard_fab2_lib.baseboard_fab2(sch_1):page82_i187:dq(33)" )
			)
			( pin "J9U2.104"
				( objectStatus "@baseboard_fab2_lib.baseboard_fab2(sch_1):page82_i187:dq(34)" )
			)
			( pin "J9U2.249"
				( objectStatus "@baseboard_fab2_lib.baseboard_fab2(sch_1):page82_i187:dq(35)" )
			)
			( pin "J9U2.95"
				( objectStatus "@baseboard_fab2_lib.baseboard_fab2(sch_1):page82_i187:dq(36)" )
			)
			( pin "J9U2.240"
				( objectStatus "@baseboard_fab2_lib.baseboard_fab2(sch_1):page82_i187:dq(37)" )
			)
			( pin "J9U2.102"
				( objectStatus "@baseboard_fab2_lib.baseboard_fab2(sch_1):page82_i187:dq(38)" )
			)
			( pin "J9U2.247"
				( objectStatus "@baseboard_fab2_lib.baseboard_fab2(sch_1):page82_i187:dq(39)" )
			)
			( pin "J9U2.108"
				( objectStatus "@baseboard_fab2_lib.baseboard_fab2(sch_1):page82_i187:dq(40)" )
			)
			( pin "J9U2.253"
				( objectStatus "@baseboard_fab2_lib.baseboard_fab2(sch_1):page82_i187:dq(41)" )
			)
			( pin "J9U2.115"
				( objectStatus "@baseboard_fab2_lib.baseboard_fab2(sch_1):page82_i187:dq(42)" )
			)
			( pin "J9U2.260"
				( objectStatus "@baseboard_fab2_lib.baseboard_fab2(sch_1):page82_i187:dq(43)" )
			)
			( pin "J9U2.106"
				( objectStatus "@baseboard_fab2_lib.baseboard_fab2(sch_1):page82_i187:dq(44)" )
			)
			( pin "J9U2.251"
				( objectStatus "@baseboard_fab2_lib.baseboard_fab2(sch_1):page82_i187:dq(45)" )
			)
			( pin "J9U2.113"
				( objectStatus "@baseboard_fab2_lib.baseboard_fab2(sch_1):page82_i187:dq(46)" )
			)
			( pin "J9U2.258"
				( objectStatus "@baseboard_fab2_lib.baseboard_fab2(sch_1):page82_i187:dq(47)" )
			)
			( pin "J9U2.119"
				( objectStatus "@baseboard_fab2_lib.baseboard_fab2(sch_1):page82_i187:dq(48)" )
			)
			( pin "J9U2.264"
				( objectStatus "@baseboard_fab2_lib.baseboard_fab2(sch_1):page82_i187:dq(49)" )
			)
			( pin "J9U2.126"
				( objectStatus "@baseboard_fab2_lib.baseboard_fab2(sch_1):page82_i187:dq(50)" )
			)
			( pin "J9U2.271"
				( objectStatus "@baseboard_fab2_lib.baseboard_fab2(sch_1):page82_i187:dq(51)" )
			)
			( pin "J9U2.117"
				( objectStatus "@baseboard_fab2_lib.baseboard_fab2(sch_1):page82_i187:dq(52)" )
			)
			( pin "J9U2.262"
				( objectStatus "@baseboard_fab2_lib.baseboard_fab2(sch_1):page82_i187:dq(53)" )
			)
			( pin "J9U2.124"
				( objectStatus "@baseboard_fab2_lib.baseboard_fab2(sch_1):page82_i187:dq(54)" )
			)
			( pin "J9U2.269"
				( objectStatus "@baseboard_fab2_lib.baseboard_fab2(sch_1):page82_i187:dq(55)" )
			)
			( pin "J9U2.130"
				( objectStatus "@baseboard_fab2_lib.baseboard_fab2(sch_1):page82_i187:dq(56)" )
			)
			( pin "J9U2.275"
				( objectStatus "@baseboard_fab2_lib.baseboard_fab2(sch_1):page82_i187:dq(57)" )
			)
			( pin "J9U2.137"
				( objectStatus "@baseboard_fab2_lib.baseboard_fab2(sch_1):page82_i187:dq(58)" )
			)
			( pin "J9U2.282"
				( objectStatus "@baseboard_fab2_lib.baseboard_fab2(sch_1):page82_i187:dq(59)" )
			)
			( pin "J9U2.128"
				( objectStatus "@baseboard_fab2_lib.baseboard_fab2(sch_1):page82_i187:dq(60)" )
			)
			( pin "J9U2.273"
				( objectStatus "@baseboard_fab2_lib.baseboard_fab2(sch_1):page82_i187:dq(61)" )
			)
			( pin "J9U2.135"
				( objectStatus "@baseboard_fab2_lib.baseboard_fab2(sch_1):page82_i187:dq(62)" )
			)
			( pin "J9U2.280"
				( objectStatus "@baseboard_fab2_lib.baseboard_fab2(sch_1):page82_i187:dq(63)" )
			)
			( pin "J9U2.78"
				( objectStatus "@baseboard_fab2_lib.baseboard_fab2(sch_1):page82_i187:event_n" )
			)
			( pin "J9U2.87"
				( objectStatus "@baseboard_fab2_lib.baseboard_fab2(sch_1):page82_i187:odt(0)" )
			)
			( pin "J9U2.91"
				( objectStatus "@baseboard_fab2_lib.baseboard_fab2(sch_1):page82_i187:odt(1)" )
			)
			( pin "J9U2.222"
				( objectStatus "@baseboard_fab2_lib.baseboard_fab2(sch_1):page82_i187:par" )
			)
			( pin "J9U2.58"
				( objectStatus "@baseboard_fab2_lib.baseboard_fab2(sch_1):page82_i187:reset_n" )
			)
			( pin "J9U2.205"
				( objectStatus "@baseboard_fab2_lib.baseboard_fab2(sch_1):page82_i187:rfu(0)" )
			)
			( pin "J9U2.227"
				( objectStatus "@baseboard_fab2_lib.baseboard_fab2(sch_1):page82_i187:rfu(1)" )
			)
			( pin "J9U2.144"
				( objectStatus "@baseboard_fab2_lib.baseboard_fab2(sch_1):page82_i187:rfu(2)" )
			)
			( pin "J9U2.84"
				( objectStatus "@baseboard_fab2_lib.baseboard_fab2(sch_1):page82_i187:s0_n" )
			)
			( pin "J9U2.89"
				( objectStatus "@baseboard_fab2_lib.baseboard_fab2(sch_1):page82_i187:s1_n" )
			)
			( pin "J9U2.93"
				( objectStatus "@baseboard_fab2_lib.baseboard_fab2(sch_1):page82_i187:s2_n_c(0)" )
			)
			( pin "J9U2.237"
				( objectStatus "@baseboard_fab2_lib.baseboard_fab2(sch_1):page82_i187:s3_n_c(1)" )
			)
			( pin "J9U2.139"
				( objectStatus "@baseboard_fab2_lib.baseboard_fab2(sch_1):page82_i187:sa(0)" )
			)
			( pin "J9U2.140"
				( objectStatus "@baseboard_fab2_lib.baseboard_fab2(sch_1):page82_i187:sa(1)" )
			)
			( pin "J9U2.238"
				( objectStatus "@baseboard_fab2_lib.baseboard_fab2(sch_1):page82_i187:sa(2)" )
			)
			( pin "J9U2.230"
				( objectStatus "@baseboard_fab2_lib.baseboard_fab2(sch_1):page82_i187:save_n_nc" )
			)
			( pin "J9U2.141"
				( objectStatus "@baseboard_fab2_lib.baseboard_fab2(sch_1):page82_i187:scl" )
			)
			( pin "J9U2.285"
				( objectStatus "@baseboard_fab2_lib.baseboard_fab2(sch_1):page82_i187:sda" )
			)
			( pin "J9U2.284"
				( objectStatus "@baseboard_fab2_lib.baseboard_fab2(sch_1):page82_i187:vddspd" )
			)
			( pin "J9U2.146"
				( objectStatus "@baseboard_fab2_lib.baseboard_fab2(sch_1):page82_i187:vrefca" )
			)
			( pin "J9U2.283"
				( objectStatus "@baseboard_fab2_lib.baseboard_fab2(sch_1):page82_i188:vss(0)" )
			)
			( pin "J9U2.281"
				( objectStatus "@baseboard_fab2_lib.baseboard_fab2(sch_1):page82_i188:vss(1)" )
			)
			( pin "J9U2.279"
				( objectStatus "@baseboard_fab2_lib.baseboard_fab2(sch_1):page82_i188:vss(2)" )
			)
			( pin "J9U2.276"
				( objectStatus "@baseboard_fab2_lib.baseboard_fab2(sch_1):page82_i188:vss(3)" )
			)
			( pin "J9U2.274"
				( objectStatus "@baseboard_fab2_lib.baseboard_fab2(sch_1):page82_i188:vss(4)" )
			)
			( pin "J9U2.272"
				( objectStatus "@baseboard_fab2_lib.baseboard_fab2(sch_1):page82_i188:vss(5)" )
			)
			( pin "J9U2.270"
				( objectStatus "@baseboard_fab2_lib.baseboard_fab2(sch_1):page82_i188:vss(6)" )
			)
			( pin "J9U2.268"
				( objectStatus "@baseboard_fab2_lib.baseboard_fab2(sch_1):page82_i188:vss(7)" )
			)
			( pin "J9U2.265"
				( objectStatus "@baseboard_fab2_lib.baseboard_fab2(sch_1):page82_i188:vss(8)" )
			)
			( pin "J9U2.263"
				( objectStatus "@baseboard_fab2_lib.baseboard_fab2(sch_1):page82_i188:vss(9)" )
			)
			( pin "J9U2.261"
				( objectStatus "@baseboard_fab2_lib.baseboard_fab2(sch_1):page82_i188:vss(10)" )
			)
			( pin "J9U2.259"
				( objectStatus "@baseboard_fab2_lib.baseboard_fab2(sch_1):page82_i188:vss(11)" )
			)
			( pin "J9U2.257"
				( objectStatus "@baseboard_fab2_lib.baseboard_fab2(sch_1):page82_i188:vss(12)" )
			)
			( pin "J9U2.254"
				( objectStatus "@baseboard_fab2_lib.baseboard_fab2(sch_1):page82_i188:vss(13)" )
			)
			( pin "J9U2.252"
				( objectStatus "@baseboard_fab2_lib.baseboard_fab2(sch_1):page82_i188:vss(14)" )
			)
			( pin "J9U2.250"
				( objectStatus "@baseboard_fab2_lib.baseboard_fab2(sch_1):page82_i188:vss(15)" )
			)
			( pin "J9U2.248"
				( objectStatus "@baseboard_fab2_lib.baseboard_fab2(sch_1):page82_i188:vss(16)" )
			)
			( pin "J9U2.246"
				( objectStatus "@baseboard_fab2_lib.baseboard_fab2(sch_1):page82_i188:vss(17)" )
			)
			( pin "J9U2.243"
				( objectStatus "@baseboard_fab2_lib.baseboard_fab2(sch_1):page82_i188:vss(18)" )
			)
			( pin "J9U2.241"
				( objectStatus "@baseboard_fab2_lib.baseboard_fab2(sch_1):page82_i188:vss(19)" )
			)
			( pin "J9U2.239"
				( objectStatus "@baseboard_fab2_lib.baseboard_fab2(sch_1):page82_i188:vss(20)" )
			)
			( pin "J9U2.202"
				( objectStatus "@baseboard_fab2_lib.baseboard_fab2(sch_1):page82_i188:vss(21)" )
			)
			( pin "J9U2.200"
				( objectStatus "@baseboard_fab2_lib.baseboard_fab2(sch_1):page82_i188:vss(22)" )
			)
			( pin "J9U2.198"
				( objectStatus "@baseboard_fab2_lib.baseboard_fab2(sch_1):page82_i188:vss(23)" )
			)
			( pin "J9U2.195"
				( objectStatus "@baseboard_fab2_lib.baseboard_fab2(sch_1):page82_i188:vss(24)" )
			)
			( pin "J9U2.193"
				( objectStatus "@baseboard_fab2_lib.baseboard_fab2(sch_1):page82_i188:vss(25)" )
			)
			( pin "J9U2.191"
				( objectStatus "@baseboard_fab2_lib.baseboard_fab2(sch_1):page82_i188:vss(26)" )
			)
			( pin "J9U2.189"
				( objectStatus "@baseboard_fab2_lib.baseboard_fab2(sch_1):page82_i188:vss(27)" )
			)
			( pin "J9U2.187"
				( objectStatus "@baseboard_fab2_lib.baseboard_fab2(sch_1):page82_i188:vss(28)" )
			)
			( pin "J9U2.184"
				( objectStatus "@baseboard_fab2_lib.baseboard_fab2(sch_1):page82_i188:vss(29)" )
			)
			( pin "J9U2.182"
				( objectStatus "@baseboard_fab2_lib.baseboard_fab2(sch_1):page82_i188:vss(30)" )
			)
			( pin "J9U2.180"
				( objectStatus "@baseboard_fab2_lib.baseboard_fab2(sch_1):page82_i188:vss(31)" )
			)
			( pin "J9U2.178"
				( objectStatus "@baseboard_fab2_lib.baseboard_fab2(sch_1):page82_i188:vss(32)" )
			)
			( pin "J9U2.176"
				( objectStatus "@baseboard_fab2_lib.baseboard_fab2(sch_1):page82_i188:vss(33)" )
			)
			( pin "J9U2.173"
				( objectStatus "@baseboard_fab2_lib.baseboard_fab2(sch_1):page82_i188:vss(34)" )
			)
			( pin "J9U2.171"
				( objectStatus "@baseboard_fab2_lib.baseboard_fab2(sch_1):page82_i188:vss(35)" )
			)
			( pin "J9U2.169"
				( objectStatus "@baseboard_fab2_lib.baseboard_fab2(sch_1):page82_i188:vss(36)" )
			)
			( pin "J9U2.167"
				( objectStatus "@baseboard_fab2_lib.baseboard_fab2(sch_1):page82_i188:vss(37)" )
			)
			( pin "J9U2.165"
				( objectStatus "@baseboard_fab2_lib.baseboard_fab2(sch_1):page82_i188:vss(38)" )
			)
			( pin "J9U2.162"
				( objectStatus "@baseboard_fab2_lib.baseboard_fab2(sch_1):page82_i188:vss(39)" )
			)
			( pin "J9U2.160"
				( objectStatus "@baseboard_fab2_lib.baseboard_fab2(sch_1):page82_i188:vss(40)" )
			)
			( pin "J9U2.158"
				( objectStatus "@baseboard_fab2_lib.baseboard_fab2(sch_1):page82_i188:vss(41)" )
			)
			( pin "J9U2.156"
				( objectStatus "@baseboard_fab2_lib.baseboard_fab2(sch_1):page82_i188:vss(42)" )
			)
			( pin "J9U2.154"
				( objectStatus "@baseboard_fab2_lib.baseboard_fab2(sch_1):page82_i188:vss(43)" )
			)
			( pin "J9U2.151"
				( objectStatus "@baseboard_fab2_lib.baseboard_fab2(sch_1):page82_i188:vss(44)" )
			)
			( pin "J9U2.149"
				( objectStatus "@baseboard_fab2_lib.baseboard_fab2(sch_1):page82_i188:vss(45)" )
			)
			( pin "J9U2.147"
				( objectStatus "@baseboard_fab2_lib.baseboard_fab2(sch_1):page82_i188:vss(46)" )
			)
			( pin "J9U2.138"
				( objectStatus "@baseboard_fab2_lib.baseboard_fab2(sch_1):page82_i188:vss(47)" )
			)
			( pin "J9U2.136"
				( objectStatus "@baseboard_fab2_lib.baseboard_fab2(sch_1):page82_i188:vss(48)" )
			)
			( pin "J9U2.134"
				( objectStatus "@baseboard_fab2_lib.baseboard_fab2(sch_1):page82_i188:vss(49)" )
			)
			( pin "J9U2.131"
				( objectStatus "@baseboard_fab2_lib.baseboard_fab2(sch_1):page82_i188:vss(50)" )
			)
			( pin "J9U2.129"
				( objectStatus "@baseboard_fab2_lib.baseboard_fab2(sch_1):page82_i188:vss(51)" )
			)
			( pin "J9U2.127"
				( objectStatus "@baseboard_fab2_lib.baseboard_fab2(sch_1):page82_i188:vss(52)" )
			)
			( pin "J9U2.125"
				( objectStatus "@baseboard_fab2_lib.baseboard_fab2(sch_1):page82_i188:vss(53)" )
			)
			( pin "J9U2.123"
				( objectStatus "@baseboard_fab2_lib.baseboard_fab2(sch_1):page82_i188:vss(54)" )
			)
			( pin "J9U2.120"
				( objectStatus "@baseboard_fab2_lib.baseboard_fab2(sch_1):page82_i188:vss(55)" )
			)
			( pin "J9U2.118"
				( objectStatus "@baseboard_fab2_lib.baseboard_fab2(sch_1):page82_i188:vss(56)" )
			)
			( pin "J9U2.116"
				( objectStatus "@baseboard_fab2_lib.baseboard_fab2(sch_1):page82_i188:vss(57)" )
			)
			( pin "J9U2.114"
				( objectStatus "@baseboard_fab2_lib.baseboard_fab2(sch_1):page82_i188:vss(58)" )
			)
			( pin "J9U2.112"
				( objectStatus "@baseboard_fab2_lib.baseboard_fab2(sch_1):page82_i188:vss(59)" )
			)
			( pin "J9U2.109"
				( objectStatus "@baseboard_fab2_lib.baseboard_fab2(sch_1):page82_i188:vss(60)" )
			)
			( pin "J9U2.107"
				( objectStatus "@baseboard_fab2_lib.baseboard_fab2(sch_1):page82_i188:vss(61)" )
			)
			( pin "J9U2.105"
				( objectStatus "@baseboard_fab2_lib.baseboard_fab2(sch_1):page82_i188:vss(62)" )
			)
			( pin "J9U2.103"
				( objectStatus "@baseboard_fab2_lib.baseboard_fab2(sch_1):page82_i188:vss(63)" )
			)
			( pin "J9U2.101"
				( objectStatus "@baseboard_fab2_lib.baseboard_fab2(sch_1):page82_i188:vss(64)" )
			)
			( pin "J9U2.98"
				( objectStatus "@baseboard_fab2_lib.baseboard_fab2(sch_1):page82_i188:vss(65)" )
			)
			( pin "J9U2.96"
				( objectStatus "@baseboard_fab2_lib.baseboard_fab2(sch_1):page82_i188:vss(66)" )
			)
			( pin "J9U2.94"
				( objectStatus "@baseboard_fab2_lib.baseboard_fab2(sch_1):page82_i188:vss(67)" )
			)
			( pin "J9U2.57"
				( objectStatus "@baseboard_fab2_lib.baseboard_fab2(sch_1):page82_i188:vss(68)" )
			)
			( pin "J9U2.55"
				( objectStatus "@baseboard_fab2_lib.baseboard_fab2(sch_1):page82_i188:vss(69)" )
			)
			( pin "J9U2.53"
				( objectStatus "@baseboard_fab2_lib.baseboard_fab2(sch_1):page82_i188:vss(70)" )
			)
			( pin "J9U2.50"
				( objectStatus "@baseboard_fab2_lib.baseboard_fab2(sch_1):page82_i188:vss(71)" )
			)
			( pin "J9U2.48"
				( objectStatus "@baseboard_fab2_lib.baseboard_fab2(sch_1):page82_i188:vss(72)" )
			)
			( pin "J9U2.46"
				( objectStatus "@baseboard_fab2_lib.baseboard_fab2(sch_1):page82_i188:vss(73)" )
			)
			( pin "J9U2.44"
				( objectStatus "@baseboard_fab2_lib.baseboard_fab2(sch_1):page82_i188:vss(74)" )
			)
			( pin "J9U2.42"
				( objectStatus "@baseboard_fab2_lib.baseboard_fab2(sch_1):page82_i188:vss(75)" )
			)
			( pin "J9U2.39"
				( objectStatus "@baseboard_fab2_lib.baseboard_fab2(sch_1):page82_i188:vss(76)" )
			)
			( pin "J9U2.37"
				( objectStatus "@baseboard_fab2_lib.baseboard_fab2(sch_1):page82_i188:vss(77)" )
			)
			( pin "J9U2.35"
				( objectStatus "@baseboard_fab2_lib.baseboard_fab2(sch_1):page82_i188:vss(78)" )
			)
			( pin "J9U2.33"
				( objectStatus "@baseboard_fab2_lib.baseboard_fab2(sch_1):page82_i188:vss(79)" )
			)
			( pin "J9U2.31"
				( objectStatus "@baseboard_fab2_lib.baseboard_fab2(sch_1):page82_i188:vss(80)" )
			)
			( pin "J9U2.28"
				( objectStatus "@baseboard_fab2_lib.baseboard_fab2(sch_1):page82_i188:vss(81)" )
			)
			( pin "J9U2.26"
				( objectStatus "@baseboard_fab2_lib.baseboard_fab2(sch_1):page82_i188:vss(82)" )
			)
			( pin "J9U2.24"
				( objectStatus "@baseboard_fab2_lib.baseboard_fab2(sch_1):page82_i188:vss(83)" )
			)
			( pin "J9U2.22"
				( objectStatus "@baseboard_fab2_lib.baseboard_fab2(sch_1):page82_i188:vss(84)" )
			)
			( pin "J9U2.20"
				( objectStatus "@baseboard_fab2_lib.baseboard_fab2(sch_1):page82_i188:vss(85)" )
			)
			( pin "J9U2.17"
				( objectStatus "@baseboard_fab2_lib.baseboard_fab2(sch_1):page82_i188:vss(86)" )
			)
			( pin "J9U2.15"
				( objectStatus "@baseboard_fab2_lib.baseboard_fab2(sch_1):page82_i188:vss(87)" )
			)
			( pin "J9U2.13"
				( objectStatus "@baseboard_fab2_lib.baseboard_fab2(sch_1):page82_i188:vss(88)" )
			)
			( pin "J9U2.11"
				( objectStatus "@baseboard_fab2_lib.baseboard_fab2(sch_1):page82_i188:vss(89)" )
			)
			( pin "J9U2.9"
				( objectStatus "@baseboard_fab2_lib.baseboard_fab2(sch_1):page82_i188:vss(90)" )
			)
			( pin "J9U2.6"
				( objectStatus "@baseboard_fab2_lib.baseboard_fab2(sch_1):page82_i188:vss(91)" )
			)
			( pin "J9U2.4"
				( objectStatus "@baseboard_fab2_lib.baseboard_fab2(sch_1):page82_i188:vss(92)" )
			)
			( pin "J9U2.2"
				( objectStatus "@baseboard_fab2_lib.baseboard_fab2(sch_1):page82_i188:vss(93)" )
			)
			( pin "J1B1.283"
				( objectStatus "@baseboard_fab2_lib.baseboard_fab2(sch_1):page83_i43:vss(0)" )
			)
			( pin "J1B1.281"
				( objectStatus "@baseboard_fab2_lib.baseboard_fab2(sch_1):page83_i43:vss(1)" )
			)
			( pin "J1B1.279"
				( objectStatus "@baseboard_fab2_lib.baseboard_fab2(sch_1):page83_i43:vss(2)" )
			)
			( pin "J1B1.276"
				( objectStatus "@baseboard_fab2_lib.baseboard_fab2(sch_1):page83_i43:vss(3)" )
			)
			( pin "J1B1.274"
				( objectStatus "@baseboard_fab2_lib.baseboard_fab2(sch_1):page83_i43:vss(4)" )
			)
			( pin "J1B1.272"
				( objectStatus "@baseboard_fab2_lib.baseboard_fab2(sch_1):page83_i43:vss(5)" )
			)
			( pin "J1B1.270"
				( objectStatus "@baseboard_fab2_lib.baseboard_fab2(sch_1):page83_i43:vss(6)" )
			)
			( pin "J1B1.268"
				( objectStatus "@baseboard_fab2_lib.baseboard_fab2(sch_1):page83_i43:vss(7)" )
			)
			( pin "J1B1.265"
				( objectStatus "@baseboard_fab2_lib.baseboard_fab2(sch_1):page83_i43:vss(8)" )
			)
			( pin "J1B1.263"
				( objectStatus "@baseboard_fab2_lib.baseboard_fab2(sch_1):page83_i43:vss(9)" )
			)
			( pin "J1B1.261"
				( objectStatus "@baseboard_fab2_lib.baseboard_fab2(sch_1):page83_i43:vss(10)" )
			)
			( pin "J1B1.259"
				( objectStatus "@baseboard_fab2_lib.baseboard_fab2(sch_1):page83_i43:vss(11)" )
			)
			( pin "J1B1.257"
				( objectStatus "@baseboard_fab2_lib.baseboard_fab2(sch_1):page83_i43:vss(12)" )
			)
			( pin "J1B1.254"
				( objectStatus "@baseboard_fab2_lib.baseboard_fab2(sch_1):page83_i43:vss(13)" )
			)
			( pin "J1B1.252"
				( objectStatus "@baseboard_fab2_lib.baseboard_fab2(sch_1):page83_i43:vss(14)" )
			)
			( pin "J1B1.250"
				( objectStatus "@baseboard_fab2_lib.baseboard_fab2(sch_1):page83_i43:vss(15)" )
			)
			( pin "J1B1.248"
				( objectStatus "@baseboard_fab2_lib.baseboard_fab2(sch_1):page83_i43:vss(16)" )
			)
			( pin "J1B1.246"
				( objectStatus "@baseboard_fab2_lib.baseboard_fab2(sch_1):page83_i43:vss(17)" )
			)
			( pin "J1B1.243"
				( objectStatus "@baseboard_fab2_lib.baseboard_fab2(sch_1):page83_i43:vss(18)" )
			)
			( pin "J1B1.241"
				( objectStatus "@baseboard_fab2_lib.baseboard_fab2(sch_1):page83_i43:vss(19)" )
			)
			( pin "J1B1.239"
				( objectStatus "@baseboard_fab2_lib.baseboard_fab2(sch_1):page83_i43:vss(20)" )
			)
			( pin "J1B1.202"
				( objectStatus "@baseboard_fab2_lib.baseboard_fab2(sch_1):page83_i43:vss(21)" )
			)
			( pin "J1B1.200"
				( objectStatus "@baseboard_fab2_lib.baseboard_fab2(sch_1):page83_i43:vss(22)" )
			)
			( pin "J1B1.198"
				( objectStatus "@baseboard_fab2_lib.baseboard_fab2(sch_1):page83_i43:vss(23)" )
			)
			( pin "J1B1.195"
				( objectStatus "@baseboard_fab2_lib.baseboard_fab2(sch_1):page83_i43:vss(24)" )
			)
			( pin "J1B1.193"
				( objectStatus "@baseboard_fab2_lib.baseboard_fab2(sch_1):page83_i43:vss(25)" )
			)
			( pin "J1B1.191"
				( objectStatus "@baseboard_fab2_lib.baseboard_fab2(sch_1):page83_i43:vss(26)" )
			)
			( pin "J1B1.189"
				( objectStatus "@baseboard_fab2_lib.baseboard_fab2(sch_1):page83_i43:vss(27)" )
			)
			( pin "J1B1.187"
				( objectStatus "@baseboard_fab2_lib.baseboard_fab2(sch_1):page83_i43:vss(28)" )
			)
			( pin "J1B1.184"
				( objectStatus "@baseboard_fab2_lib.baseboard_fab2(sch_1):page83_i43:vss(29)" )
			)
			( pin "J1B1.182"
				( objectStatus "@baseboard_fab2_lib.baseboard_fab2(sch_1):page83_i43:vss(30)" )
			)
			( pin "J1B1.180"
				( objectStatus "@baseboard_fab2_lib.baseboard_fab2(sch_1):page83_i43:vss(31)" )
			)
			( pin "J1B1.178"
				( objectStatus "@baseboard_fab2_lib.baseboard_fab2(sch_1):page83_i43:vss(32)" )
			)
			( pin "J1B1.176"
				( objectStatus "@baseboard_fab2_lib.baseboard_fab2(sch_1):page83_i43:vss(33)" )
			)
			( pin "J1B1.173"
				( objectStatus "@baseboard_fab2_lib.baseboard_fab2(sch_1):page83_i43:vss(34)" )
			)
			( pin "J1B1.171"
				( objectStatus "@baseboard_fab2_lib.baseboard_fab2(sch_1):page83_i43:vss(35)" )
			)
			( pin "J1B1.169"
				( objectStatus "@baseboard_fab2_lib.baseboard_fab2(sch_1):page83_i43:vss(36)" )
			)
			( pin "J1B1.167"
				( objectStatus "@baseboard_fab2_lib.baseboard_fab2(sch_1):page83_i43:vss(37)" )
			)
			( pin "J1B1.165"
				( objectStatus "@baseboard_fab2_lib.baseboard_fab2(sch_1):page83_i43:vss(38)" )
			)
			( pin "J1B1.162"
				( objectStatus "@baseboard_fab2_lib.baseboard_fab2(sch_1):page83_i43:vss(39)" )
			)
			( pin "J1B1.160"
				( objectStatus "@baseboard_fab2_lib.baseboard_fab2(sch_1):page83_i43:vss(40)" )
			)
			( pin "J1B1.158"
				( objectStatus "@baseboard_fab2_lib.baseboard_fab2(sch_1):page83_i43:vss(41)" )
			)
			( pin "J1B1.156"
				( objectStatus "@baseboard_fab2_lib.baseboard_fab2(sch_1):page83_i43:vss(42)" )
			)
			( pin "J1B1.154"
				( objectStatus "@baseboard_fab2_lib.baseboard_fab2(sch_1):page83_i43:vss(43)" )
			)
			( pin "J1B1.151"
				( objectStatus "@baseboard_fab2_lib.baseboard_fab2(sch_1):page83_i43:vss(44)" )
			)
			( pin "J1B1.149"
				( objectStatus "@baseboard_fab2_lib.baseboard_fab2(sch_1):page83_i43:vss(45)" )
			)
			( pin "J1B1.147"
				( objectStatus "@baseboard_fab2_lib.baseboard_fab2(sch_1):page83_i43:vss(46)" )
			)
			( pin "J1B1.138"
				( objectStatus "@baseboard_fab2_lib.baseboard_fab2(sch_1):page83_i43:vss(47)" )
			)
			( pin "J1B1.136"
				( objectStatus "@baseboard_fab2_lib.baseboard_fab2(sch_1):page83_i43:vss(48)" )
			)
			( pin "J1B1.134"
				( objectStatus "@baseboard_fab2_lib.baseboard_fab2(sch_1):page83_i43:vss(49)" )
			)
			( pin "J1B1.131"
				( objectStatus "@baseboard_fab2_lib.baseboard_fab2(sch_1):page83_i43:vss(50)" )
			)
			( pin "J1B1.129"
				( objectStatus "@baseboard_fab2_lib.baseboard_fab2(sch_1):page83_i43:vss(51)" )
			)
			( pin "J1B1.127"
				( objectStatus "@baseboard_fab2_lib.baseboard_fab2(sch_1):page83_i43:vss(52)" )
			)
			( pin "J1B1.125"
				( objectStatus "@baseboard_fab2_lib.baseboard_fab2(sch_1):page83_i43:vss(53)" )
			)
			( pin "J1B1.123"
				( objectStatus "@baseboard_fab2_lib.baseboard_fab2(sch_1):page83_i43:vss(54)" )
			)
			( pin "J1B1.120"
				( objectStatus "@baseboard_fab2_lib.baseboard_fab2(sch_1):page83_i43:vss(55)" )
			)
			( pin "J1B1.118"
				( objectStatus "@baseboard_fab2_lib.baseboard_fab2(sch_1):page83_i43:vss(56)" )
			)
			( pin "J1B1.116"
				( objectStatus "@baseboard_fab2_lib.baseboard_fab2(sch_1):page83_i43:vss(57)" )
			)
			( pin "J1B1.114"
				( objectStatus "@baseboard_fab2_lib.baseboard_fab2(sch_1):page83_i43:vss(58)" )
			)
			( pin "J1B1.112"
				( objectStatus "@baseboard_fab2_lib.baseboard_fab2(sch_1):page83_i43:vss(59)" )
			)
			( pin "J1B1.109"
				( objectStatus "@baseboard_fab2_lib.baseboard_fab2(sch_1):page83_i43:vss(60)" )
			)
			( pin "J1B1.107"
				( objectStatus "@baseboard_fab2_lib.baseboard_fab2(sch_1):page83_i43:vss(61)" )
			)
			( pin "J1B1.105"
				( objectStatus "@baseboard_fab2_lib.baseboard_fab2(sch_1):page83_i43:vss(62)" )
			)
			( pin "J1B1.103"
				( objectStatus "@baseboard_fab2_lib.baseboard_fab2(sch_1):page83_i43:vss(63)" )
			)
			( pin "J1B1.101"
				( objectStatus "@baseboard_fab2_lib.baseboard_fab2(sch_1):page83_i43:vss(64)" )
			)
			( pin "J1B1.98"
				( objectStatus "@baseboard_fab2_lib.baseboard_fab2(sch_1):page83_i43:vss(65)" )
			)
			( pin "J1B1.96"
				( objectStatus "@baseboard_fab2_lib.baseboard_fab2(sch_1):page83_i43:vss(66)" )
			)
			( pin "J1B1.94"
				( objectStatus "@baseboard_fab2_lib.baseboard_fab2(sch_1):page83_i43:vss(67)" )
			)
			( pin "J1B1.57"
				( objectStatus "@baseboard_fab2_lib.baseboard_fab2(sch_1):page83_i43:vss(68)" )
			)
			( pin "J1B1.55"
				( objectStatus "@baseboard_fab2_lib.baseboard_fab2(sch_1):page83_i43:vss(69)" )
			)
			( pin "J1B1.53"
				( objectStatus "@baseboard_fab2_lib.baseboard_fab2(sch_1):page83_i43:vss(70)" )
			)
			( pin "J1B1.50"
				( objectStatus "@baseboard_fab2_lib.baseboard_fab2(sch_1):page83_i43:vss(71)" )
			)
			( pin "J1B1.48"
				( objectStatus "@baseboard_fab2_lib.baseboard_fab2(sch_1):page83_i43:vss(72)" )
			)
			( pin "J1B1.46"
				( objectStatus "@baseboard_fab2_lib.baseboard_fab2(sch_1):page83_i43:vss(73)" )
			)
			( pin "J1B1.44"
				( objectStatus "@baseboard_fab2_lib.baseboard_fab2(sch_1):page83_i43:vss(74)" )
			)
			( pin "J1B1.42"
				( objectStatus "@baseboard_fab2_lib.baseboard_fab2(sch_1):page83_i43:vss(75)" )
			)
			( pin "J1B1.39"
				( objectStatus "@baseboard_fab2_lib.baseboard_fab2(sch_1):page83_i43:vss(76)" )
			)
			( pin "J1B1.37"
				( objectStatus "@baseboard_fab2_lib.baseboard_fab2(sch_1):page83_i43:vss(77)" )
			)
			( pin "J1B1.35"
				( objectStatus "@baseboard_fab2_lib.baseboard_fab2(sch_1):page83_i43:vss(78)" )
			)
			( pin "J1B1.33"
				( objectStatus "@baseboard_fab2_lib.baseboard_fab2(sch_1):page83_i43:vss(79)" )
			)
			( pin "J1B1.31"
				( objectStatus "@baseboard_fab2_lib.baseboard_fab2(sch_1):page83_i43:vss(80)" )
			)
			( pin "J1B1.28"
				( objectStatus "@baseboard_fab2_lib.baseboard_fab2(sch_1):page83_i43:vss(81)" )
			)
			( pin "J1B1.26"
				( objectStatus "@baseboard_fab2_lib.baseboard_fab2(sch_1):page83_i43:vss(82)" )
			)
			( pin "J1B1.24"
				( objectStatus "@baseboard_fab2_lib.baseboard_fab2(sch_1):page83_i43:vss(83)" )
			)
			( pin "J1B1.22"
				( objectStatus "@baseboard_fab2_lib.baseboard_fab2(sch_1):page83_i43:vss(84)" )
			)
			( pin "J1B1.20"
				( objectStatus "@baseboard_fab2_lib.baseboard_fab2(sch_1):page83_i43:vss(85)" )
			)
			( pin "J1B1.17"
				( objectStatus "@baseboard_fab2_lib.baseboard_fab2(sch_1):page83_i43:vss(86)" )
			)
			( pin "J1B1.15"
				( objectStatus "@baseboard_fab2_lib.baseboard_fab2(sch_1):page83_i43:vss(87)" )
			)
			( pin "J1B1.13"
				( objectStatus "@baseboard_fab2_lib.baseboard_fab2(sch_1):page83_i43:vss(88)" )
			)
			( pin "J1B1.11"
				( objectStatus "@baseboard_fab2_lib.baseboard_fab2(sch_1):page83_i43:vss(89)" )
			)
			( pin "J1B1.9"
				( objectStatus "@baseboard_fab2_lib.baseboard_fab2(sch_1):page83_i43:vss(90)" )
			)
			( pin "J1B1.6"
				( objectStatus "@baseboard_fab2_lib.baseboard_fab2(sch_1):page83_i43:vss(91)" )
			)
			( pin "J1B1.4"
				( objectStatus "@baseboard_fab2_lib.baseboard_fab2(sch_1):page83_i43:vss(92)" )
			)
			( pin "J1B1.2"
				( objectStatus "@baseboard_fab2_lib.baseboard_fab2(sch_1):page83_i43:vss(93)" )
			)
			( pin "J1B1.152"
				( objectStatus "@baseboard_fab2_lib.baseboard_fab2(sch_1):page83_i66:dqs0n" )
			)
			( pin "J1B1.153"
				( objectStatus "@baseboard_fab2_lib.baseboard_fab2(sch_1):page83_i66:dqs0p" )
			)
			( pin "J1B1.163"
				( objectStatus "@baseboard_fab2_lib.baseboard_fab2(sch_1):page83_i66:dqs1n" )
			)
			( pin "J1B1.164"
				( objectStatus "@baseboard_fab2_lib.baseboard_fab2(sch_1):page83_i66:dqs1p" )
			)
			( pin "J1B1.174"
				( objectStatus "@baseboard_fab2_lib.baseboard_fab2(sch_1):page83_i66:dqs2n" )
			)
			( pin "J1B1.175"
				( objectStatus "@baseboard_fab2_lib.baseboard_fab2(sch_1):page83_i66:dqs2p" )
			)
			( pin "J1B1.185"
				( objectStatus "@baseboard_fab2_lib.baseboard_fab2(sch_1):page83_i66:dqs3n" )
			)
			( pin "J1B1.186"
				( objectStatus "@baseboard_fab2_lib.baseboard_fab2(sch_1):page83_i66:dqs3p" )
			)
			( pin "J1B1.244"
				( objectStatus "@baseboard_fab2_lib.baseboard_fab2(sch_1):page83_i66:dqs4n" )
			)
			( pin "J1B1.245"
				( objectStatus "@baseboard_fab2_lib.baseboard_fab2(sch_1):page83_i66:dqs4p" )
			)
			( pin "J1B1.255"
				( objectStatus "@baseboard_fab2_lib.baseboard_fab2(sch_1):page83_i66:dqs5n" )
			)
			( pin "J1B1.256"
				( objectStatus "@baseboard_fab2_lib.baseboard_fab2(sch_1):page83_i66:dqs5p" )
			)
			( pin "J1B1.266"
				( objectStatus "@baseboard_fab2_lib.baseboard_fab2(sch_1):page83_i66:dqs6n" )
			)
			( pin "J1B1.267"
				( objectStatus "@baseboard_fab2_lib.baseboard_fab2(sch_1):page83_i66:dqs6p" )
			)
			( pin "J1B1.277"
				( objectStatus "@baseboard_fab2_lib.baseboard_fab2(sch_1):page83_i66:dqs7n" )
			)
			( pin "J1B1.278"
				( objectStatus "@baseboard_fab2_lib.baseboard_fab2(sch_1):page83_i66:dqs7p" )
			)
			( pin "J1B1.196"
				( objectStatus "@baseboard_fab2_lib.baseboard_fab2(sch_1):page83_i66:dqs8n" )
			)
			( pin "J1B1.197"
				( objectStatus "@baseboard_fab2_lib.baseboard_fab2(sch_1):page83_i66:dqs8p" )
			)
			( pin "J1B1.8"
				( objectStatus "@baseboard_fab2_lib.baseboard_fab2(sch_1):page83_i66:dqs9n" )
			)
			( pin "J1B1.7"
				( objectStatus "@baseboard_fab2_lib.baseboard_fab2(sch_1):page83_i66:dqs9p" )
			)
			( pin "J1B1.19"
				( objectStatus "@baseboard_fab2_lib.baseboard_fab2(sch_1):page83_i66:dqs10n" )
			)
			( pin "J1B1.18"
				( objectStatus "@baseboard_fab2_lib.baseboard_fab2(sch_1):page83_i66:dqs10p" )
			)
			( pin "J1B1.30"
				( objectStatus "@baseboard_fab2_lib.baseboard_fab2(sch_1):page83_i66:dqs11n" )
			)
			( pin "J1B1.29"
				( objectStatus "@baseboard_fab2_lib.baseboard_fab2(sch_1):page83_i66:dqs11p" )
			)
			( pin "J1B1.41"
				( objectStatus "@baseboard_fab2_lib.baseboard_fab2(sch_1):page83_i66:dqs12n" )
			)
			( pin "J1B1.40"
				( objectStatus "@baseboard_fab2_lib.baseboard_fab2(sch_1):page83_i66:dqs12p" )
			)
			( pin "J1B1.100"
				( objectStatus "@baseboard_fab2_lib.baseboard_fab2(sch_1):page83_i66:dqs13n" )
			)
			( pin "J1B1.99"
				( objectStatus "@baseboard_fab2_lib.baseboard_fab2(sch_1):page83_i66:dqs13p" )
			)
			( pin "J1B1.111"
				( objectStatus "@baseboard_fab2_lib.baseboard_fab2(sch_1):page83_i66:dqs14n" )
			)
			( pin "J1B1.110"
				( objectStatus "@baseboard_fab2_lib.baseboard_fab2(sch_1):page83_i66:dqs14p" )
			)
			( pin "J1B1.122"
				( objectStatus "@baseboard_fab2_lib.baseboard_fab2(sch_1):page83_i66:dqs15n" )
			)
			( pin "J1B1.121"
				( objectStatus "@baseboard_fab2_lib.baseboard_fab2(sch_1):page83_i66:dqs15p" )
			)
			( pin "J1B1.133"
				( objectStatus "@baseboard_fab2_lib.baseboard_fab2(sch_1):page83_i66:dqs16n" )
			)
			( pin "J1B1.132"
				( objectStatus "@baseboard_fab2_lib.baseboard_fab2(sch_1):page83_i66:dqs16p" )
			)
			( pin "J1B1.52"
				( objectStatus "@baseboard_fab2_lib.baseboard_fab2(sch_1):page83_i66:dqs17n" )
			)
			( pin "J1B1.51"
				( objectStatus "@baseboard_fab2_lib.baseboard_fab2(sch_1):page83_i66:dqs17p" )
			)
			( pin "J1B1.79"
				( objectStatus "@baseboard_fab2_lib.baseboard_fab2(sch_1):page83_i111:a0" )
			)
			( pin "J1B1.72"
				( objectStatus "@baseboard_fab2_lib.baseboard_fab2(sch_1):page83_i111:a1" )
			)
			( pin "J1B1.216"
				( objectStatus "@baseboard_fab2_lib.baseboard_fab2(sch_1):page83_i111:a2" )
			)
			( pin "J1B1.71"
				( objectStatus "@baseboard_fab2_lib.baseboard_fab2(sch_1):page83_i111:a3" )
			)
			( pin "J1B1.214"
				( objectStatus "@baseboard_fab2_lib.baseboard_fab2(sch_1):page83_i111:a4" )
			)
			( pin "J1B1.213"
				( objectStatus "@baseboard_fab2_lib.baseboard_fab2(sch_1):page83_i111:a5" )
			)
			( pin "J1B1.69"
				( objectStatus "@baseboard_fab2_lib.baseboard_fab2(sch_1):page83_i111:a6" )
			)
			( pin "J1B1.211"
				( objectStatus "@baseboard_fab2_lib.baseboard_fab2(sch_1):page83_i111:a7" )
			)
			( pin "J1B1.68"
				( objectStatus "@baseboard_fab2_lib.baseboard_fab2(sch_1):page83_i111:a8" )
			)
			( pin "J1B1.66"
				( objectStatus "@baseboard_fab2_lib.baseboard_fab2(sch_1):page83_i111:a9" )
			)
			( pin "J1B1.225"
				( objectStatus "@baseboard_fab2_lib.baseboard_fab2(sch_1):page83_i111:a10" )
			)
			( pin "J1B1.210"
				( objectStatus "@baseboard_fab2_lib.baseboard_fab2(sch_1):page83_i111:a11" )
			)
			( pin "J1B1.65"
				( objectStatus "@baseboard_fab2_lib.baseboard_fab2(sch_1):page83_i111:a12" )
			)
			( pin "J1B1.232"
				( objectStatus "@baseboard_fab2_lib.baseboard_fab2(sch_1):page83_i111:a13" )
			)
			( pin "J1B1.228"
				( objectStatus "@baseboard_fab2_lib.baseboard_fab2(sch_1):page83_i111:a14_we_n" )
			)
			( pin "J1B1.86"
				( objectStatus "@baseboard_fab2_lib.baseboard_fab2(sch_1):page83_i111:a15_cas_n" )
			)
			( pin "J1B1.82"
				( objectStatus "@baseboard_fab2_lib.baseboard_fab2(sch_1):page83_i111:a16_ras_n" )
			)
			( pin "J1B1.234"
				( objectStatus "@baseboard_fab2_lib.baseboard_fab2(sch_1):page83_i111:a17" )
			)
			( pin "J1B1.62"
				( objectStatus "@baseboard_fab2_lib.baseboard_fab2(sch_1):page83_i111:act_n" )
			)
			( pin "J1B1.208"
				( objectStatus "@baseboard_fab2_lib.baseboard_fab2(sch_1):page83_i111:alert_n" )
			)
			( pin "J1B1.81"
				( objectStatus "@baseboard_fab2_lib.baseboard_fab2(sch_1):page83_i111:ba(0)" )
			)
			( pin "J1B1.224"
				( objectStatus "@baseboard_fab2_lib.baseboard_fab2(sch_1):page83_i111:ba(1)" )
			)
			( pin "J1B1.63"
				( objectStatus "@baseboard_fab2_lib.baseboard_fab2(sch_1):page83_i111:bg(0)" )
			)
			( pin "J1B1.207"
				( objectStatus "@baseboard_fab2_lib.baseboard_fab2(sch_1):page83_i111:bg(1)" )
			)
			( pin "J1B1.235"
				( objectStatus "@baseboard_fab2_lib.baseboard_fab2(sch_1):page83_i111:c(2)" )
			)
			( pin "J1B1.49"
				( objectStatus "@baseboard_fab2_lib.baseboard_fab2(sch_1):page83_i111:cb(0)" )
			)
			( pin "J1B1.194"
				( objectStatus "@baseboard_fab2_lib.baseboard_fab2(sch_1):page83_i111:cb(1)" )
			)
			( pin "J1B1.56"
				( objectStatus "@baseboard_fab2_lib.baseboard_fab2(sch_1):page83_i111:cb(2)" )
			)
			( pin "J1B1.201"
				( objectStatus "@baseboard_fab2_lib.baseboard_fab2(sch_1):page83_i111:cb(3)" )
			)
			( pin "J1B1.47"
				( objectStatus "@baseboard_fab2_lib.baseboard_fab2(sch_1):page83_i111:cb(4)" )
			)
			( pin "J1B1.192"
				( objectStatus "@baseboard_fab2_lib.baseboard_fab2(sch_1):page83_i111:cb(5)" )
			)
			( pin "J1B1.54"
				( objectStatus "@baseboard_fab2_lib.baseboard_fab2(sch_1):page83_i111:cb(6)" )
			)
			( pin "J1B1.199"
				( objectStatus "@baseboard_fab2_lib.baseboard_fab2(sch_1):page83_i111:cb(7)" )
			)
			( pin "J1B1.75"
				( objectStatus "@baseboard_fab2_lib.baseboard_fab2(sch_1):page83_i111:ck0n" )
			)
			( pin "J1B1.74"
				( objectStatus "@baseboard_fab2_lib.baseboard_fab2(sch_1):page83_i111:ck0p" )
			)
			( pin "J1B1.219"
				( objectStatus "@baseboard_fab2_lib.baseboard_fab2(sch_1):page83_i111:ck1n" )
			)
			( pin "J1B1.218"
				( objectStatus "@baseboard_fab2_lib.baseboard_fab2(sch_1):page83_i111:ck1p" )
			)
			( pin "J1B1.60"
				( objectStatus "@baseboard_fab2_lib.baseboard_fab2(sch_1):page83_i111:cke(0)" )
			)
			( pin "J1B1.203"
				( objectStatus "@baseboard_fab2_lib.baseboard_fab2(sch_1):page83_i111:cke(1)" )
			)
			( pin "J1B1.5"
				( objectStatus "@baseboard_fab2_lib.baseboard_fab2(sch_1):page83_i111:dq(0)" )
			)
			( pin "J1B1.150"
				( objectStatus "@baseboard_fab2_lib.baseboard_fab2(sch_1):page83_i111:dq(1)" )
			)
			( pin "J1B1.12"
				( objectStatus "@baseboard_fab2_lib.baseboard_fab2(sch_1):page83_i111:dq(2)" )
			)
			( pin "J1B1.157"
				( objectStatus "@baseboard_fab2_lib.baseboard_fab2(sch_1):page83_i111:dq(3)" )
			)
			( pin "J1B1.3"
				( objectStatus "@baseboard_fab2_lib.baseboard_fab2(sch_1):page83_i111:dq(4)" )
			)
			( pin "J1B1.148"
				( objectStatus "@baseboard_fab2_lib.baseboard_fab2(sch_1):page83_i111:dq(5)" )
			)
			( pin "J1B1.10"
				( objectStatus "@baseboard_fab2_lib.baseboard_fab2(sch_1):page83_i111:dq(6)" )
			)
			( pin "J1B1.155"
				( objectStatus "@baseboard_fab2_lib.baseboard_fab2(sch_1):page83_i111:dq(7)" )
			)
			( pin "J1B1.16"
				( objectStatus "@baseboard_fab2_lib.baseboard_fab2(sch_1):page83_i111:dq(8)" )
			)
			( pin "J1B1.161"
				( objectStatus "@baseboard_fab2_lib.baseboard_fab2(sch_1):page83_i111:dq(9)" )
			)
			( pin "J1B1.23"
				( objectStatus "@baseboard_fab2_lib.baseboard_fab2(sch_1):page83_i111:dq(10)" )
			)
			( pin "J1B1.168"
				( objectStatus "@baseboard_fab2_lib.baseboard_fab2(sch_1):page83_i111:dq(11)" )
			)
			( pin "J1B1.14"
				( objectStatus "@baseboard_fab2_lib.baseboard_fab2(sch_1):page83_i111:dq(12)" )
			)
			( pin "J1B1.159"
				( objectStatus "@baseboard_fab2_lib.baseboard_fab2(sch_1):page83_i111:dq(13)" )
			)
			( pin "J1B1.21"
				( objectStatus "@baseboard_fab2_lib.baseboard_fab2(sch_1):page83_i111:dq(14)" )
			)
			( pin "J1B1.166"
				( objectStatus "@baseboard_fab2_lib.baseboard_fab2(sch_1):page83_i111:dq(15)" )
			)
			( pin "J1B1.27"
				( objectStatus "@baseboard_fab2_lib.baseboard_fab2(sch_1):page83_i111:dq(16)" )
			)
			( pin "J1B1.172"
				( objectStatus "@baseboard_fab2_lib.baseboard_fab2(sch_1):page83_i111:dq(17)" )
			)
			( pin "J1B1.34"
				( objectStatus "@baseboard_fab2_lib.baseboard_fab2(sch_1):page83_i111:dq(18)" )
			)
			( pin "J1B1.179"
				( objectStatus "@baseboard_fab2_lib.baseboard_fab2(sch_1):page83_i111:dq(19)" )
			)
			( pin "J1B1.25"
				( objectStatus "@baseboard_fab2_lib.baseboard_fab2(sch_1):page83_i111:dq(20)" )
			)
			( pin "J1B1.170"
				( objectStatus "@baseboard_fab2_lib.baseboard_fab2(sch_1):page83_i111:dq(21)" )
			)
			( pin "J1B1.32"
				( objectStatus "@baseboard_fab2_lib.baseboard_fab2(sch_1):page83_i111:dq(22)" )
			)
			( pin "J1B1.177"
				( objectStatus "@baseboard_fab2_lib.baseboard_fab2(sch_1):page83_i111:dq(23)" )
			)
			( pin "J1B1.38"
				( objectStatus "@baseboard_fab2_lib.baseboard_fab2(sch_1):page83_i111:dq(24)" )
			)
			( pin "J1B1.183"
				( objectStatus "@baseboard_fab2_lib.baseboard_fab2(sch_1):page83_i111:dq(25)" )
			)
			( pin "J1B1.45"
				( objectStatus "@baseboard_fab2_lib.baseboard_fab2(sch_1):page83_i111:dq(26)" )
			)
			( pin "J1B1.190"
				( objectStatus "@baseboard_fab2_lib.baseboard_fab2(sch_1):page83_i111:dq(27)" )
			)
			( pin "J1B1.36"
				( objectStatus "@baseboard_fab2_lib.baseboard_fab2(sch_1):page83_i111:dq(28)" )
			)
			( pin "J1B1.181"
				( objectStatus "@baseboard_fab2_lib.baseboard_fab2(sch_1):page83_i111:dq(29)" )
			)
			( pin "J1B1.43"
				( objectStatus "@baseboard_fab2_lib.baseboard_fab2(sch_1):page83_i111:dq(30)" )
			)
			( pin "J1B1.188"
				( objectStatus "@baseboard_fab2_lib.baseboard_fab2(sch_1):page83_i111:dq(31)" )
			)
			( pin "J1B1.97"
				( objectStatus "@baseboard_fab2_lib.baseboard_fab2(sch_1):page83_i111:dq(32)" )
			)
			( pin "J1B1.242"
				( objectStatus "@baseboard_fab2_lib.baseboard_fab2(sch_1):page83_i111:dq(33)" )
			)
			( pin "J1B1.104"
				( objectStatus "@baseboard_fab2_lib.baseboard_fab2(sch_1):page83_i111:dq(34)" )
			)
			( pin "J1B1.249"
				( objectStatus "@baseboard_fab2_lib.baseboard_fab2(sch_1):page83_i111:dq(35)" )
			)
			( pin "J1B1.95"
				( objectStatus "@baseboard_fab2_lib.baseboard_fab2(sch_1):page83_i111:dq(36)" )
			)
			( pin "J1B1.240"
				( objectStatus "@baseboard_fab2_lib.baseboard_fab2(sch_1):page83_i111:dq(37)" )
			)
			( pin "J1B1.102"
				( objectStatus "@baseboard_fab2_lib.baseboard_fab2(sch_1):page83_i111:dq(38)" )
			)
			( pin "J1B1.247"
				( objectStatus "@baseboard_fab2_lib.baseboard_fab2(sch_1):page83_i111:dq(39)" )
			)
			( pin "J1B1.108"
				( objectStatus "@baseboard_fab2_lib.baseboard_fab2(sch_1):page83_i111:dq(40)" )
			)
			( pin "J1B1.253"
				( objectStatus "@baseboard_fab2_lib.baseboard_fab2(sch_1):page83_i111:dq(41)" )
			)
			( pin "J1B1.115"
				( objectStatus "@baseboard_fab2_lib.baseboard_fab2(sch_1):page83_i111:dq(42)" )
			)
			( pin "J1B1.260"
				( objectStatus "@baseboard_fab2_lib.baseboard_fab2(sch_1):page83_i111:dq(43)" )
			)
			( pin "J1B1.106"
				( objectStatus "@baseboard_fab2_lib.baseboard_fab2(sch_1):page83_i111:dq(44)" )
			)
			( pin "J1B1.251"
				( objectStatus "@baseboard_fab2_lib.baseboard_fab2(sch_1):page83_i111:dq(45)" )
			)
			( pin "J1B1.113"
				( objectStatus "@baseboard_fab2_lib.baseboard_fab2(sch_1):page83_i111:dq(46)" )
			)
			( pin "J1B1.258"
				( objectStatus "@baseboard_fab2_lib.baseboard_fab2(sch_1):page83_i111:dq(47)" )
			)
			( pin "J1B1.119"
				( objectStatus "@baseboard_fab2_lib.baseboard_fab2(sch_1):page83_i111:dq(48)" )
			)
			( pin "J1B1.264"
				( objectStatus "@baseboard_fab2_lib.baseboard_fab2(sch_1):page83_i111:dq(49)" )
			)
			( pin "J1B1.126"
				( objectStatus "@baseboard_fab2_lib.baseboard_fab2(sch_1):page83_i111:dq(50)" )
			)
			( pin "J1B1.271"
				( objectStatus "@baseboard_fab2_lib.baseboard_fab2(sch_1):page83_i111:dq(51)" )
			)
			( pin "J1B1.117"
				( objectStatus "@baseboard_fab2_lib.baseboard_fab2(sch_1):page83_i111:dq(52)" )
			)
			( pin "J1B1.262"
				( objectStatus "@baseboard_fab2_lib.baseboard_fab2(sch_1):page83_i111:dq(53)" )
			)
			( pin "J1B1.124"
				( objectStatus "@baseboard_fab2_lib.baseboard_fab2(sch_1):page83_i111:dq(54)" )
			)
			( pin "J1B1.269"
				( objectStatus "@baseboard_fab2_lib.baseboard_fab2(sch_1):page83_i111:dq(55)" )
			)
			( pin "J1B1.130"
				( objectStatus "@baseboard_fab2_lib.baseboard_fab2(sch_1):page83_i111:dq(56)" )
			)
			( pin "J1B1.275"
				( objectStatus "@baseboard_fab2_lib.baseboard_fab2(sch_1):page83_i111:dq(57)" )
			)
			( pin "J1B1.137"
				( objectStatus "@baseboard_fab2_lib.baseboard_fab2(sch_1):page83_i111:dq(58)" )
			)
			( pin "J1B1.282"
				( objectStatus "@baseboard_fab2_lib.baseboard_fab2(sch_1):page83_i111:dq(59)" )
			)
			( pin "J1B1.128"
				( objectStatus "@baseboard_fab2_lib.baseboard_fab2(sch_1):page83_i111:dq(60)" )
			)
			( pin "J1B1.273"
				( objectStatus "@baseboard_fab2_lib.baseboard_fab2(sch_1):page83_i111:dq(61)" )
			)
			( pin "J1B1.135"
				( objectStatus "@baseboard_fab2_lib.baseboard_fab2(sch_1):page83_i111:dq(62)" )
			)
			( pin "J1B1.280"
				( objectStatus "@baseboard_fab2_lib.baseboard_fab2(sch_1):page83_i111:dq(63)" )
			)
			( pin "J1B1.78"
				( objectStatus "@baseboard_fab2_lib.baseboard_fab2(sch_1):page83_i111:event_n" )
			)
			( pin "J1B1.87"
				( objectStatus "@baseboard_fab2_lib.baseboard_fab2(sch_1):page83_i111:odt(0)" )
			)
			( pin "J1B1.91"
				( objectStatus "@baseboard_fab2_lib.baseboard_fab2(sch_1):page83_i111:odt(1)" )
			)
			( pin "J1B1.222"
				( objectStatus "@baseboard_fab2_lib.baseboard_fab2(sch_1):page83_i111:par" )
			)
			( pin "J1B1.58"
				( objectStatus "@baseboard_fab2_lib.baseboard_fab2(sch_1):page83_i111:reset_n" )
			)
			( pin "J1B1.205"
				( objectStatus "@baseboard_fab2_lib.baseboard_fab2(sch_1):page83_i111:rfu(0)" )
			)
			( pin "J1B1.227"
				( objectStatus "@baseboard_fab2_lib.baseboard_fab2(sch_1):page83_i111:rfu(1)" )
			)
			( pin "J1B1.144"
				( objectStatus "@baseboard_fab2_lib.baseboard_fab2(sch_1):page83_i111:rfu(2)" )
			)
			( pin "J1B1.84"
				( objectStatus "@baseboard_fab2_lib.baseboard_fab2(sch_1):page83_i111:s0_n" )
			)
			( pin "J1B1.89"
				( objectStatus "@baseboard_fab2_lib.baseboard_fab2(sch_1):page83_i111:s1_n" )
			)
			( pin "J1B1.93"
				( objectStatus "@baseboard_fab2_lib.baseboard_fab2(sch_1):page83_i111:s2_n_c(0)" )
			)
			( pin "J1B1.237"
				( objectStatus "@baseboard_fab2_lib.baseboard_fab2(sch_1):page83_i111:s3_n_c(1)" )
			)
			( pin "J1B1.139"
				( objectStatus "@baseboard_fab2_lib.baseboard_fab2(sch_1):page83_i111:sa(0)" )
			)
			( pin "J1B1.140"
				( objectStatus "@baseboard_fab2_lib.baseboard_fab2(sch_1):page83_i111:sa(1)" )
			)
			( pin "J1B1.238"
				( objectStatus "@baseboard_fab2_lib.baseboard_fab2(sch_1):page83_i111:sa(2)" )
			)
			( pin "J1B1.230"
				( objectStatus "@baseboard_fab2_lib.baseboard_fab2(sch_1):page83_i111:save_n_nc" )
			)
			( pin "J1B1.141"
				( objectStatus "@baseboard_fab2_lib.baseboard_fab2(sch_1):page83_i111:scl" )
			)
			( pin "J1B1.285"
				( objectStatus "@baseboard_fab2_lib.baseboard_fab2(sch_1):page83_i111:sda" )
			)
			( pin "J1B1.284"
				( objectStatus "@baseboard_fab2_lib.baseboard_fab2(sch_1):page83_i111:vddspd" )
			)
			( pin "J1B1.146"
				( objectStatus "@baseboard_fab2_lib.baseboard_fab2(sch_1):page83_i111:vrefca" )
			)
			( pin "J1B1.145"
				( objectStatus "@baseboard_fab2_lib.baseboard_fab2(sch_1):page83_i167:\12v\(0)" )
			)
			( pin "J1B1.1"
				( objectStatus "@baseboard_fab2_lib.baseboard_fab2(sch_1):page83_i167:\12v\(1)" )
			)
			( pin "J1B1.236"
				( objectStatus "@baseboard_fab2_lib.baseboard_fab2(sch_1):page83_i167:vdd(0)" )
			)
			( pin "J1B1.233"
				( objectStatus "@baseboard_fab2_lib.baseboard_fab2(sch_1):page83_i167:vdd(1)" )
			)
			( pin "J1B1.231"
				( objectStatus "@baseboard_fab2_lib.baseboard_fab2(sch_1):page83_i167:vdd(2)" )
			)
			( pin "J1B1.229"
				( objectStatus "@baseboard_fab2_lib.baseboard_fab2(sch_1):page83_i167:vdd(3)" )
			)
			( pin "J1B1.226"
				( objectStatus "@baseboard_fab2_lib.baseboard_fab2(sch_1):page83_i167:vdd(4)" )
			)
			( pin "J1B1.223"
				( objectStatus "@baseboard_fab2_lib.baseboard_fab2(sch_1):page83_i167:vdd(5)" )
			)
			( pin "J1B1.220"
				( objectStatus "@baseboard_fab2_lib.baseboard_fab2(sch_1):page83_i167:vdd(6)" )
			)
			( pin "J1B1.217"
				( objectStatus "@baseboard_fab2_lib.baseboard_fab2(sch_1):page83_i167:vdd(7)" )
			)
			( pin "J1B1.215"
				( objectStatus "@baseboard_fab2_lib.baseboard_fab2(sch_1):page83_i167:vdd(8)" )
			)
			( pin "J1B1.212"
				( objectStatus "@baseboard_fab2_lib.baseboard_fab2(sch_1):page83_i167:vdd(9)" )
			)
			( pin "J1B1.209"
				( objectStatus "@baseboard_fab2_lib.baseboard_fab2(sch_1):page83_i167:vdd(10)" )
			)
			( pin "J1B1.206"
				( objectStatus "@baseboard_fab2_lib.baseboard_fab2(sch_1):page83_i167:vdd(11)" )
			)
			( pin "J1B1.204"
				( objectStatus "@baseboard_fab2_lib.baseboard_fab2(sch_1):page83_i167:vdd(12)" )
			)
			( pin "J1B1.92"
				( objectStatus "@baseboard_fab2_lib.baseboard_fab2(sch_1):page83_i167:vdd(13)" )
			)
			( pin "J1B1.90"
				( objectStatus "@baseboard_fab2_lib.baseboard_fab2(sch_1):page83_i167:vdd(14)" )
			)
			( pin "J1B1.88"
				( objectStatus "@baseboard_fab2_lib.baseboard_fab2(sch_1):page83_i167:vdd(15)" )
			)
			( pin "J1B1.85"
				( objectStatus "@baseboard_fab2_lib.baseboard_fab2(sch_1):page83_i167:vdd(16)" )
			)
			( pin "J1B1.83"
				( objectStatus "@baseboard_fab2_lib.baseboard_fab2(sch_1):page83_i167:vdd(17)" )
			)
			( pin "J1B1.80"
				( objectStatus "@baseboard_fab2_lib.baseboard_fab2(sch_1):page83_i167:vdd(18)" )
			)
			( pin "J1B1.76"
				( objectStatus "@baseboard_fab2_lib.baseboard_fab2(sch_1):page83_i167:vdd(19)" )
			)
			( pin "J1B1.73"
				( objectStatus "@baseboard_fab2_lib.baseboard_fab2(sch_1):page83_i167:vdd(20)" )
			)
			( pin "J1B1.70"
				( objectStatus "@baseboard_fab2_lib.baseboard_fab2(sch_1):page83_i167:vdd(21)" )
			)
			( pin "J1B1.67"
				( objectStatus "@baseboard_fab2_lib.baseboard_fab2(sch_1):page83_i167:vdd(22)" )
			)
			( pin "J1B1.64"
				( objectStatus "@baseboard_fab2_lib.baseboard_fab2(sch_1):page83_i167:vdd(23)" )
			)
			( pin "J1B1.61"
				( objectStatus "@baseboard_fab2_lib.baseboard_fab2(sch_1):page83_i167:vdd(24)" )
			)
			( pin "J1B1.59"
				( objectStatus "@baseboard_fab2_lib.baseboard_fab2(sch_1):page83_i167:vdd(25)" )
			)
			( pin "J1B1.287"
				( objectStatus "@baseboard_fab2_lib.baseboard_fab2(sch_1):page83_i167:vpp(0)" )
			)
			( pin "J1B1.286"
				( objectStatus "@baseboard_fab2_lib.baseboard_fab2(sch_1):page83_i167:vpp(1)" )
			)
			( pin "J1B1.288"
				( objectStatus "@baseboard_fab2_lib.baseboard_fab2(sch_1):page83_i167:vpp(2)" )
			)
			( pin "J1B1.143"
				( objectStatus "@baseboard_fab2_lib.baseboard_fab2(sch_1):page83_i167:vpp(3)" )
			)
			( pin "J1B1.142"
				( objectStatus "@baseboard_fab2_lib.baseboard_fab2(sch_1):page83_i167:vpp(4)" )
			)
			( pin "J1B1.221"
				( objectStatus "@baseboard_fab2_lib.baseboard_fab2(sch_1):page83_i167:vtt(0)" )
			)
			( pin "J1B1.77"
				( objectStatus "@baseboard_fab2_lib.baseboard_fab2(sch_1):page83_i167:vtt(1)" )
			)
			( pin "C1B9.1"
				( objectStatus "@baseboard_fab2_lib.baseboard_fab2(sch_1):page83_i176:a" )
			)
			( pin "C1B9.2"
				( objectStatus "@baseboard_fab2_lib.baseboard_fab2(sch_1):page83_i176:b" )
			)
			( pin "C9M1.1"
				( objectStatus "@baseboard_fab2_lib.baseboard_fab2(sch_1):page84_i4:a" )
			)
			( pin "C9M1.2"
				( objectStatus "@baseboard_fab2_lib.baseboard_fab2(sch_1):page84_i4:b" )
			)
			( pin "J9M1.79"
				( objectStatus "@baseboard_fab2_lib.baseboard_fab2(sch_1):page84_i14:a0" )
			)
			( pin "J9M1.72"
				( objectStatus "@baseboard_fab2_lib.baseboard_fab2(sch_1):page84_i14:a1" )
			)
			( pin "J9M1.216"
				( objectStatus "@baseboard_fab2_lib.baseboard_fab2(sch_1):page84_i14:a2" )
			)
			( pin "J9M1.71"
				( objectStatus "@baseboard_fab2_lib.baseboard_fab2(sch_1):page84_i14:a3" )
			)
			( pin "J9M1.214"
				( objectStatus "@baseboard_fab2_lib.baseboard_fab2(sch_1):page84_i14:a4" )
			)
			( pin "J9M1.213"
				( objectStatus "@baseboard_fab2_lib.baseboard_fab2(sch_1):page84_i14:a5" )
			)
			( pin "J9M1.69"
				( objectStatus "@baseboard_fab2_lib.baseboard_fab2(sch_1):page84_i14:a6" )
			)
			( pin "J9M1.211"
				( objectStatus "@baseboard_fab2_lib.baseboard_fab2(sch_1):page84_i14:a7" )
			)
			( pin "J9M1.68"
				( objectStatus "@baseboard_fab2_lib.baseboard_fab2(sch_1):page84_i14:a8" )
			)
			( pin "J9M1.66"
				( objectStatus "@baseboard_fab2_lib.baseboard_fab2(sch_1):page84_i14:a9" )
			)
			( pin "J9M1.225"
				( objectStatus "@baseboard_fab2_lib.baseboard_fab2(sch_1):page84_i14:a10" )
			)
			( pin "J9M1.210"
				( objectStatus "@baseboard_fab2_lib.baseboard_fab2(sch_1):page84_i14:a11" )
			)
			( pin "J9M1.65"
				( objectStatus "@baseboard_fab2_lib.baseboard_fab2(sch_1):page84_i14:a12" )
			)
			( pin "J9M1.232"
				( objectStatus "@baseboard_fab2_lib.baseboard_fab2(sch_1):page84_i14:a13" )
			)
			( pin "J9M1.228"
				( objectStatus "@baseboard_fab2_lib.baseboard_fab2(sch_1):page84_i14:a14_we_n" )
			)
			( pin "J9M1.86"
				( objectStatus "@baseboard_fab2_lib.baseboard_fab2(sch_1):page84_i14:a15_cas_n" )
			)
			( pin "J9M1.82"
				( objectStatus "@baseboard_fab2_lib.baseboard_fab2(sch_1):page84_i14:a16_ras_n" )
			)
			( pin "J9M1.234"
				( objectStatus "@baseboard_fab2_lib.baseboard_fab2(sch_1):page84_i14:a17" )
			)
			( pin "J9M1.62"
				( objectStatus "@baseboard_fab2_lib.baseboard_fab2(sch_1):page84_i14:act_n" )
			)
			( pin "J9M1.208"
				( objectStatus "@baseboard_fab2_lib.baseboard_fab2(sch_1):page84_i14:alert_n" )
			)
			( pin "J9M1.81"
				( objectStatus "@baseboard_fab2_lib.baseboard_fab2(sch_1):page84_i14:ba(0)" )
			)
			( pin "J9M1.224"
				( objectStatus "@baseboard_fab2_lib.baseboard_fab2(sch_1):page84_i14:ba(1)" )
			)
			( pin "J9M1.63"
				( objectStatus "@baseboard_fab2_lib.baseboard_fab2(sch_1):page84_i14:bg(0)" )
			)
			( pin "J9M1.207"
				( objectStatus "@baseboard_fab2_lib.baseboard_fab2(sch_1):page84_i14:bg(1)" )
			)
			( pin "J9M1.235"
				( objectStatus "@baseboard_fab2_lib.baseboard_fab2(sch_1):page84_i14:c(2)" )
			)
			( pin "J9M1.49"
				( objectStatus "@baseboard_fab2_lib.baseboard_fab2(sch_1):page84_i14:cb(0)" )
			)
			( pin "J9M1.194"
				( objectStatus "@baseboard_fab2_lib.baseboard_fab2(sch_1):page84_i14:cb(1)" )
			)
			( pin "J9M1.56"
				( objectStatus "@baseboard_fab2_lib.baseboard_fab2(sch_1):page84_i14:cb(2)" )
			)
			( pin "J9M1.201"
				( objectStatus "@baseboard_fab2_lib.baseboard_fab2(sch_1):page84_i14:cb(3)" )
			)
			( pin "J9M1.47"
				( objectStatus "@baseboard_fab2_lib.baseboard_fab2(sch_1):page84_i14:cb(4)" )
			)
			( pin "J9M1.192"
				( objectStatus "@baseboard_fab2_lib.baseboard_fab2(sch_1):page84_i14:cb(5)" )
			)
			( pin "J9M1.54"
				( objectStatus "@baseboard_fab2_lib.baseboard_fab2(sch_1):page84_i14:cb(6)" )
			)
			( pin "J9M1.199"
				( objectStatus "@baseboard_fab2_lib.baseboard_fab2(sch_1):page84_i14:cb(7)" )
			)
			( pin "J9M1.75"
				( objectStatus "@baseboard_fab2_lib.baseboard_fab2(sch_1):page84_i14:ck0n" )
			)
			( pin "J9M1.74"
				( objectStatus "@baseboard_fab2_lib.baseboard_fab2(sch_1):page84_i14:ck0p" )
			)
			( pin "J9M1.219"
				( objectStatus "@baseboard_fab2_lib.baseboard_fab2(sch_1):page84_i14:ck1n" )
			)
			( pin "J9M1.218"
				( objectStatus "@baseboard_fab2_lib.baseboard_fab2(sch_1):page84_i14:ck1p" )
			)
			( pin "J9M1.60"
				( objectStatus "@baseboard_fab2_lib.baseboard_fab2(sch_1):page84_i14:cke(0)" )
			)
			( pin "J9M1.203"
				( objectStatus "@baseboard_fab2_lib.baseboard_fab2(sch_1):page84_i14:cke(1)" )
			)
			( pin "J9M1.5"
				( objectStatus "@baseboard_fab2_lib.baseboard_fab2(sch_1):page84_i14:dq(0)" )
			)
			( pin "J9M1.150"
				( objectStatus "@baseboard_fab2_lib.baseboard_fab2(sch_1):page84_i14:dq(1)" )
			)
			( pin "J9M1.12"
				( objectStatus "@baseboard_fab2_lib.baseboard_fab2(sch_1):page84_i14:dq(2)" )
			)
			( pin "J9M1.157"
				( objectStatus "@baseboard_fab2_lib.baseboard_fab2(sch_1):page84_i14:dq(3)" )
			)
			( pin "J9M1.3"
				( objectStatus "@baseboard_fab2_lib.baseboard_fab2(sch_1):page84_i14:dq(4)" )
			)
			( pin "J9M1.148"
				( objectStatus "@baseboard_fab2_lib.baseboard_fab2(sch_1):page84_i14:dq(5)" )
			)
			( pin "J9M1.10"
				( objectStatus "@baseboard_fab2_lib.baseboard_fab2(sch_1):page84_i14:dq(6)" )
			)
			( pin "J9M1.155"
				( objectStatus "@baseboard_fab2_lib.baseboard_fab2(sch_1):page84_i14:dq(7)" )
			)
			( pin "J9M1.16"
				( objectStatus "@baseboard_fab2_lib.baseboard_fab2(sch_1):page84_i14:dq(8)" )
			)
			( pin "J9M1.161"
				( objectStatus "@baseboard_fab2_lib.baseboard_fab2(sch_1):page84_i14:dq(9)" )
			)
			( pin "J9M1.23"
				( objectStatus "@baseboard_fab2_lib.baseboard_fab2(sch_1):page84_i14:dq(10)" )
			)
			( pin "J9M1.168"
				( objectStatus "@baseboard_fab2_lib.baseboard_fab2(sch_1):page84_i14:dq(11)" )
			)
			( pin "J9M1.14"
				( objectStatus "@baseboard_fab2_lib.baseboard_fab2(sch_1):page84_i14:dq(12)" )
			)
			( pin "J9M1.159"
				( objectStatus "@baseboard_fab2_lib.baseboard_fab2(sch_1):page84_i14:dq(13)" )
			)
			( pin "J9M1.21"
				( objectStatus "@baseboard_fab2_lib.baseboard_fab2(sch_1):page84_i14:dq(14)" )
			)
			( pin "J9M1.166"
				( objectStatus "@baseboard_fab2_lib.baseboard_fab2(sch_1):page84_i14:dq(15)" )
			)
			( pin "J9M1.27"
				( objectStatus "@baseboard_fab2_lib.baseboard_fab2(sch_1):page84_i14:dq(16)" )
			)
			( pin "J9M1.172"
				( objectStatus "@baseboard_fab2_lib.baseboard_fab2(sch_1):page84_i14:dq(17)" )
			)
			( pin "J9M1.34"
				( objectStatus "@baseboard_fab2_lib.baseboard_fab2(sch_1):page84_i14:dq(18)" )
			)
			( pin "J9M1.179"
				( objectStatus "@baseboard_fab2_lib.baseboard_fab2(sch_1):page84_i14:dq(19)" )
			)
			( pin "J9M1.25"
				( objectStatus "@baseboard_fab2_lib.baseboard_fab2(sch_1):page84_i14:dq(20)" )
			)
			( pin "J9M1.170"
				( objectStatus "@baseboard_fab2_lib.baseboard_fab2(sch_1):page84_i14:dq(21)" )
			)
			( pin "J9M1.32"
				( objectStatus "@baseboard_fab2_lib.baseboard_fab2(sch_1):page84_i14:dq(22)" )
			)
			( pin "J9M1.177"
				( objectStatus "@baseboard_fab2_lib.baseboard_fab2(sch_1):page84_i14:dq(23)" )
			)
			( pin "J9M1.38"
				( objectStatus "@baseboard_fab2_lib.baseboard_fab2(sch_1):page84_i14:dq(24)" )
			)
			( pin "J9M1.183"
				( objectStatus "@baseboard_fab2_lib.baseboard_fab2(sch_1):page84_i14:dq(25)" )
			)
			( pin "J9M1.45"
				( objectStatus "@baseboard_fab2_lib.baseboard_fab2(sch_1):page84_i14:dq(26)" )
			)
			( pin "J9M1.190"
				( objectStatus "@baseboard_fab2_lib.baseboard_fab2(sch_1):page84_i14:dq(27)" )
			)
			( pin "J9M1.36"
				( objectStatus "@baseboard_fab2_lib.baseboard_fab2(sch_1):page84_i14:dq(28)" )
			)
			( pin "J9M1.181"
				( objectStatus "@baseboard_fab2_lib.baseboard_fab2(sch_1):page84_i14:dq(29)" )
			)
			( pin "J9M1.43"
				( objectStatus "@baseboard_fab2_lib.baseboard_fab2(sch_1):page84_i14:dq(30)" )
			)
			( pin "J9M1.188"
				( objectStatus "@baseboard_fab2_lib.baseboard_fab2(sch_1):page84_i14:dq(31)" )
			)
			( pin "J9M1.97"
				( objectStatus "@baseboard_fab2_lib.baseboard_fab2(sch_1):page84_i14:dq(32)" )
			)
			( pin "J9M1.242"
				( objectStatus "@baseboard_fab2_lib.baseboard_fab2(sch_1):page84_i14:dq(33)" )
			)
			( pin "J9M1.104"
				( objectStatus "@baseboard_fab2_lib.baseboard_fab2(sch_1):page84_i14:dq(34)" )
			)
			( pin "J9M1.249"
				( objectStatus "@baseboard_fab2_lib.baseboard_fab2(sch_1):page84_i14:dq(35)" )
			)
			( pin "J9M1.95"
				( objectStatus "@baseboard_fab2_lib.baseboard_fab2(sch_1):page84_i14:dq(36)" )
			)
			( pin "J9M1.240"
				( objectStatus "@baseboard_fab2_lib.baseboard_fab2(sch_1):page84_i14:dq(37)" )
			)
			( pin "J9M1.102"
				( objectStatus "@baseboard_fab2_lib.baseboard_fab2(sch_1):page84_i14:dq(38)" )
			)
			( pin "J9M1.247"
				( objectStatus "@baseboard_fab2_lib.baseboard_fab2(sch_1):page84_i14:dq(39)" )
			)
			( pin "J9M1.108"
				( objectStatus "@baseboard_fab2_lib.baseboard_fab2(sch_1):page84_i14:dq(40)" )
			)
			( pin "J9M1.253"
				( objectStatus "@baseboard_fab2_lib.baseboard_fab2(sch_1):page84_i14:dq(41)" )
			)
			( pin "J9M1.115"
				( objectStatus "@baseboard_fab2_lib.baseboard_fab2(sch_1):page84_i14:dq(42)" )
			)
			( pin "J9M1.260"
				( objectStatus "@baseboard_fab2_lib.baseboard_fab2(sch_1):page84_i14:dq(43)" )
			)
			( pin "J9M1.106"
				( objectStatus "@baseboard_fab2_lib.baseboard_fab2(sch_1):page84_i14:dq(44)" )
			)
			( pin "J9M1.251"
				( objectStatus "@baseboard_fab2_lib.baseboard_fab2(sch_1):page84_i14:dq(45)" )
			)
			( pin "J9M1.113"
				( objectStatus "@baseboard_fab2_lib.baseboard_fab2(sch_1):page84_i14:dq(46)" )
			)
			( pin "J9M1.258"
				( objectStatus "@baseboard_fab2_lib.baseboard_fab2(sch_1):page84_i14:dq(47)" )
			)
			( pin "J9M1.119"
				( objectStatus "@baseboard_fab2_lib.baseboard_fab2(sch_1):page84_i14:dq(48)" )
			)
			( pin "J9M1.264"
				( objectStatus "@baseboard_fab2_lib.baseboard_fab2(sch_1):page84_i14:dq(49)" )
			)
			( pin "J9M1.126"
				( objectStatus "@baseboard_fab2_lib.baseboard_fab2(sch_1):page84_i14:dq(50)" )
			)
			( pin "J9M1.271"
				( objectStatus "@baseboard_fab2_lib.baseboard_fab2(sch_1):page84_i14:dq(51)" )
			)
			( pin "J9M1.117"
				( objectStatus "@baseboard_fab2_lib.baseboard_fab2(sch_1):page84_i14:dq(52)" )
			)
			( pin "J9M1.262"
				( objectStatus "@baseboard_fab2_lib.baseboard_fab2(sch_1):page84_i14:dq(53)" )
			)
			( pin "J9M1.124"
				( objectStatus "@baseboard_fab2_lib.baseboard_fab2(sch_1):page84_i14:dq(54)" )
			)
			( pin "J9M1.269"
				( objectStatus "@baseboard_fab2_lib.baseboard_fab2(sch_1):page84_i14:dq(55)" )
			)
			( pin "J9M1.130"
				( objectStatus "@baseboard_fab2_lib.baseboard_fab2(sch_1):page84_i14:dq(56)" )
			)
			( pin "J9M1.275"
				( objectStatus "@baseboard_fab2_lib.baseboard_fab2(sch_1):page84_i14:dq(57)" )
			)
			( pin "J9M1.137"
				( objectStatus "@baseboard_fab2_lib.baseboard_fab2(sch_1):page84_i14:dq(58)" )
			)
			( pin "J9M1.282"
				( objectStatus "@baseboard_fab2_lib.baseboard_fab2(sch_1):page84_i14:dq(59)" )
			)
			( pin "J9M1.128"
				( objectStatus "@baseboard_fab2_lib.baseboard_fab2(sch_1):page84_i14:dq(60)" )
			)
			( pin "J9M1.273"
				( objectStatus "@baseboard_fab2_lib.baseboard_fab2(sch_1):page84_i14:dq(61)" )
			)
			( pin "J9M1.135"
				( objectStatus "@baseboard_fab2_lib.baseboard_fab2(sch_1):page84_i14:dq(62)" )
			)
			( pin "J9M1.280"
				( objectStatus "@baseboard_fab2_lib.baseboard_fab2(sch_1):page84_i14:dq(63)" )
			)
			( pin "J9M1.78"
				( objectStatus "@baseboard_fab2_lib.baseboard_fab2(sch_1):page84_i14:event_n" )
			)
			( pin "J9M1.87"
				( objectStatus "@baseboard_fab2_lib.baseboard_fab2(sch_1):page84_i14:odt(0)" )
			)
			( pin "J9M1.91"
				( objectStatus "@baseboard_fab2_lib.baseboard_fab2(sch_1):page84_i14:odt(1)" )
			)
			( pin "J9M1.222"
				( objectStatus "@baseboard_fab2_lib.baseboard_fab2(sch_1):page84_i14:par" )
			)
			( pin "J9M1.58"
				( objectStatus "@baseboard_fab2_lib.baseboard_fab2(sch_1):page84_i14:reset_n" )
			)
			( pin "J9M1.205"
				( objectStatus "@baseboard_fab2_lib.baseboard_fab2(sch_1):page84_i14:rfu(0)" )
			)
			( pin "J9M1.227"
				( objectStatus "@baseboard_fab2_lib.baseboard_fab2(sch_1):page84_i14:rfu(1)" )
			)
			( pin "J9M1.144"
				( objectStatus "@baseboard_fab2_lib.baseboard_fab2(sch_1):page84_i14:rfu(2)" )
			)
			( pin "J9M1.84"
				( objectStatus "@baseboard_fab2_lib.baseboard_fab2(sch_1):page84_i14:s0_n" )
			)
			( pin "J9M1.89"
				( objectStatus "@baseboard_fab2_lib.baseboard_fab2(sch_1):page84_i14:s1_n" )
			)
			( pin "J9M1.93"
				( objectStatus "@baseboard_fab2_lib.baseboard_fab2(sch_1):page84_i14:s2_n_c(0)" )
			)
			( pin "J9M1.237"
				( objectStatus "@baseboard_fab2_lib.baseboard_fab2(sch_1):page84_i14:s3_n_c(1)" )
			)
			( pin "J9M1.139"
				( objectStatus "@baseboard_fab2_lib.baseboard_fab2(sch_1):page84_i14:sa(0)" )
			)
			( pin "J9M1.140"
				( objectStatus "@baseboard_fab2_lib.baseboard_fab2(sch_1):page84_i14:sa(1)" )
			)
			( pin "J9M1.238"
				( objectStatus "@baseboard_fab2_lib.baseboard_fab2(sch_1):page84_i14:sa(2)" )
			)
			( pin "J9M1.230"
				( objectStatus "@baseboard_fab2_lib.baseboard_fab2(sch_1):page84_i14:save_n_nc" )
			)
			( pin "J9M1.141"
				( objectStatus "@baseboard_fab2_lib.baseboard_fab2(sch_1):page84_i14:scl" )
			)
			( pin "J9M1.285"
				( objectStatus "@baseboard_fab2_lib.baseboard_fab2(sch_1):page84_i14:sda" )
			)
			( pin "J9M1.284"
				( objectStatus "@baseboard_fab2_lib.baseboard_fab2(sch_1):page84_i14:vddspd" )
			)
			( pin "J9M1.146"
				( objectStatus "@baseboard_fab2_lib.baseboard_fab2(sch_1):page84_i14:vrefca" )
			)
			( pin "J9M1.145"
				( objectStatus "@baseboard_fab2_lib.baseboard_fab2(sch_1):page84_i57:\12v\(0)" )
			)
			( pin "J9M1.1"
				( objectStatus "@baseboard_fab2_lib.baseboard_fab2(sch_1):page84_i57:\12v\(1)" )
			)
			( pin "J9M1.236"
				( objectStatus "@baseboard_fab2_lib.baseboard_fab2(sch_1):page84_i57:vdd(0)" )
			)
			( pin "J9M1.233"
				( objectStatus "@baseboard_fab2_lib.baseboard_fab2(sch_1):page84_i57:vdd(1)" )
			)
			( pin "J9M1.231"
				( objectStatus "@baseboard_fab2_lib.baseboard_fab2(sch_1):page84_i57:vdd(2)" )
			)
			( pin "J9M1.229"
				( objectStatus "@baseboard_fab2_lib.baseboard_fab2(sch_1):page84_i57:vdd(3)" )
			)
			( pin "J9M1.226"
				( objectStatus "@baseboard_fab2_lib.baseboard_fab2(sch_1):page84_i57:vdd(4)" )
			)
			( pin "J9M1.223"
				( objectStatus "@baseboard_fab2_lib.baseboard_fab2(sch_1):page84_i57:vdd(5)" )
			)
			( pin "J9M1.220"
				( objectStatus "@baseboard_fab2_lib.baseboard_fab2(sch_1):page84_i57:vdd(6)" )
			)
			( pin "J9M1.217"
				( objectStatus "@baseboard_fab2_lib.baseboard_fab2(sch_1):page84_i57:vdd(7)" )
			)
			( pin "J9M1.215"
				( objectStatus "@baseboard_fab2_lib.baseboard_fab2(sch_1):page84_i57:vdd(8)" )
			)
			( pin "J9M1.212"
				( objectStatus "@baseboard_fab2_lib.baseboard_fab2(sch_1):page84_i57:vdd(9)" )
			)
			( pin "J9M1.209"
				( objectStatus "@baseboard_fab2_lib.baseboard_fab2(sch_1):page84_i57:vdd(10)" )
			)
			( pin "J9M1.206"
				( objectStatus "@baseboard_fab2_lib.baseboard_fab2(sch_1):page84_i57:vdd(11)" )
			)
			( pin "J9M1.204"
				( objectStatus "@baseboard_fab2_lib.baseboard_fab2(sch_1):page84_i57:vdd(12)" )
			)
			( pin "J9M1.92"
				( objectStatus "@baseboard_fab2_lib.baseboard_fab2(sch_1):page84_i57:vdd(13)" )
			)
			( pin "J9M1.90"
				( objectStatus "@baseboard_fab2_lib.baseboard_fab2(sch_1):page84_i57:vdd(14)" )
			)
			( pin "J9M1.88"
				( objectStatus "@baseboard_fab2_lib.baseboard_fab2(sch_1):page84_i57:vdd(15)" )
			)
			( pin "J9M1.85"
				( objectStatus "@baseboard_fab2_lib.baseboard_fab2(sch_1):page84_i57:vdd(16)" )
			)
			( pin "J9M1.83"
				( objectStatus "@baseboard_fab2_lib.baseboard_fab2(sch_1):page84_i57:vdd(17)" )
			)
			( pin "J9M1.80"
				( objectStatus "@baseboard_fab2_lib.baseboard_fab2(sch_1):page84_i57:vdd(18)" )
			)
			( pin "J9M1.76"
				( objectStatus "@baseboard_fab2_lib.baseboard_fab2(sch_1):page84_i57:vdd(19)" )
			)
			( pin "J9M1.73"
				( objectStatus "@baseboard_fab2_lib.baseboard_fab2(sch_1):page84_i57:vdd(20)" )
			)
			( pin "J9M1.70"
				( objectStatus "@baseboard_fab2_lib.baseboard_fab2(sch_1):page84_i57:vdd(21)" )
			)
			( pin "J9M1.67"
				( objectStatus "@baseboard_fab2_lib.baseboard_fab2(sch_1):page84_i57:vdd(22)" )
			)
			( pin "J9M1.64"
				( objectStatus "@baseboard_fab2_lib.baseboard_fab2(sch_1):page84_i57:vdd(23)" )
			)
			( pin "J9M1.61"
				( objectStatus "@baseboard_fab2_lib.baseboard_fab2(sch_1):page84_i57:vdd(24)" )
			)
			( pin "J9M1.59"
				( objectStatus "@baseboard_fab2_lib.baseboard_fab2(sch_1):page84_i57:vdd(25)" )
			)
			( pin "J9M1.287"
				( objectStatus "@baseboard_fab2_lib.baseboard_fab2(sch_1):page84_i57:vpp(0)" )
			)
			( pin "J9M1.286"
				( objectStatus "@baseboard_fab2_lib.baseboard_fab2(sch_1):page84_i57:vpp(1)" )
			)
			( pin "J9M1.288"
				( objectStatus "@baseboard_fab2_lib.baseboard_fab2(sch_1):page84_i57:vpp(2)" )
			)
			( pin "J9M1.143"
				( objectStatus "@baseboard_fab2_lib.baseboard_fab2(sch_1):page84_i57:vpp(3)" )
			)
			( pin "J9M1.142"
				( objectStatus "@baseboard_fab2_lib.baseboard_fab2(sch_1):page84_i57:vpp(4)" )
			)
			( pin "J9M1.221"
				( objectStatus "@baseboard_fab2_lib.baseboard_fab2(sch_1):page84_i57:vtt(0)" )
			)
			( pin "J9M1.77"
				( objectStatus "@baseboard_fab2_lib.baseboard_fab2(sch_1):page84_i57:vtt(1)" )
			)
			( pin "J9M1.152"
				( objectStatus "@baseboard_fab2_lib.baseboard_fab2(sch_1):page84_i102:dqs0n" )
			)
			( pin "J9M1.153"
				( objectStatus "@baseboard_fab2_lib.baseboard_fab2(sch_1):page84_i102:dqs0p" )
			)
			( pin "J9M1.163"
				( objectStatus "@baseboard_fab2_lib.baseboard_fab2(sch_1):page84_i102:dqs1n" )
			)
			( pin "J9M1.164"
				( objectStatus "@baseboard_fab2_lib.baseboard_fab2(sch_1):page84_i102:dqs1p" )
			)
			( pin "J9M1.174"
				( objectStatus "@baseboard_fab2_lib.baseboard_fab2(sch_1):page84_i102:dqs2n" )
			)
			( pin "J9M1.175"
				( objectStatus "@baseboard_fab2_lib.baseboard_fab2(sch_1):page84_i102:dqs2p" )
			)
			( pin "J9M1.185"
				( objectStatus "@baseboard_fab2_lib.baseboard_fab2(sch_1):page84_i102:dqs3n" )
			)
			( pin "J9M1.186"
				( objectStatus "@baseboard_fab2_lib.baseboard_fab2(sch_1):page84_i102:dqs3p" )
			)
			( pin "J9M1.244"
				( objectStatus "@baseboard_fab2_lib.baseboard_fab2(sch_1):page84_i102:dqs4n" )
			)
			( pin "J9M1.245"
				( objectStatus "@baseboard_fab2_lib.baseboard_fab2(sch_1):page84_i102:dqs4p" )
			)
			( pin "J9M1.255"
				( objectStatus "@baseboard_fab2_lib.baseboard_fab2(sch_1):page84_i102:dqs5n" )
			)
			( pin "J9M1.256"
				( objectStatus "@baseboard_fab2_lib.baseboard_fab2(sch_1):page84_i102:dqs5p" )
			)
			( pin "J9M1.266"
				( objectStatus "@baseboard_fab2_lib.baseboard_fab2(sch_1):page84_i102:dqs6n" )
			)
			( pin "J9M1.267"
				( objectStatus "@baseboard_fab2_lib.baseboard_fab2(sch_1):page84_i102:dqs6p" )
			)
			( pin "J9M1.277"
				( objectStatus "@baseboard_fab2_lib.baseboard_fab2(sch_1):page84_i102:dqs7n" )
			)
			( pin "J9M1.278"
				( objectStatus "@baseboard_fab2_lib.baseboard_fab2(sch_1):page84_i102:dqs7p" )
			)
			( pin "J9M1.196"
				( objectStatus "@baseboard_fab2_lib.baseboard_fab2(sch_1):page84_i102:dqs8n" )
			)
			( pin "J9M1.197"
				( objectStatus "@baseboard_fab2_lib.baseboard_fab2(sch_1):page84_i102:dqs8p" )
			)
			( pin "J9M1.8"
				( objectStatus "@baseboard_fab2_lib.baseboard_fab2(sch_1):page84_i102:dqs9n" )
			)
			( pin "J9M1.7"
				( objectStatus "@baseboard_fab2_lib.baseboard_fab2(sch_1):page84_i102:dqs9p" )
			)
			( pin "J9M1.19"
				( objectStatus "@baseboard_fab2_lib.baseboard_fab2(sch_1):page84_i102:dqs10n" )
			)
			( pin "J9M1.18"
				( objectStatus "@baseboard_fab2_lib.baseboard_fab2(sch_1):page84_i102:dqs10p" )
			)
			( pin "J9M1.30"
				( objectStatus "@baseboard_fab2_lib.baseboard_fab2(sch_1):page84_i102:dqs11n" )
			)
			( pin "J9M1.29"
				( objectStatus "@baseboard_fab2_lib.baseboard_fab2(sch_1):page84_i102:dqs11p" )
			)
			( pin "J9M1.41"
				( objectStatus "@baseboard_fab2_lib.baseboard_fab2(sch_1):page84_i102:dqs12n" )
			)
			( pin "J9M1.40"
				( objectStatus "@baseboard_fab2_lib.baseboard_fab2(sch_1):page84_i102:dqs12p" )
			)
			( pin "J9M1.100"
				( objectStatus "@baseboard_fab2_lib.baseboard_fab2(sch_1):page84_i102:dqs13n" )
			)
			( pin "J9M1.99"
				( objectStatus "@baseboard_fab2_lib.baseboard_fab2(sch_1):page84_i102:dqs13p" )
			)
			( pin "J9M1.111"
				( objectStatus "@baseboard_fab2_lib.baseboard_fab2(sch_1):page84_i102:dqs14n" )
			)
			( pin "J9M1.110"
				( objectStatus "@baseboard_fab2_lib.baseboard_fab2(sch_1):page84_i102:dqs14p" )
			)
			( pin "J9M1.122"
				( objectStatus "@baseboard_fab2_lib.baseboard_fab2(sch_1):page84_i102:dqs15n" )
			)
			( pin "J9M1.121"
				( objectStatus "@baseboard_fab2_lib.baseboard_fab2(sch_1):page84_i102:dqs15p" )
			)
			( pin "J9M1.133"
				( objectStatus "@baseboard_fab2_lib.baseboard_fab2(sch_1):page84_i102:dqs16n" )
			)
			( pin "J9M1.132"
				( objectStatus "@baseboard_fab2_lib.baseboard_fab2(sch_1):page84_i102:dqs16p" )
			)
			( pin "J9M1.52"
				( objectStatus "@baseboard_fab2_lib.baseboard_fab2(sch_1):page84_i102:dqs17n" )
			)
			( pin "J9M1.51"
				( objectStatus "@baseboard_fab2_lib.baseboard_fab2(sch_1):page84_i102:dqs17p" )
			)
			( pin "J9M1.283"
				( objectStatus "@baseboard_fab2_lib.baseboard_fab2(sch_1):page84_i138:vss(0)" )
			)
			( pin "J9M1.281"
				( objectStatus "@baseboard_fab2_lib.baseboard_fab2(sch_1):page84_i138:vss(1)" )
			)
			( pin "J9M1.279"
				( objectStatus "@baseboard_fab2_lib.baseboard_fab2(sch_1):page84_i138:vss(2)" )
			)
			( pin "J9M1.276"
				( objectStatus "@baseboard_fab2_lib.baseboard_fab2(sch_1):page84_i138:vss(3)" )
			)
			( pin "J9M1.274"
				( objectStatus "@baseboard_fab2_lib.baseboard_fab2(sch_1):page84_i138:vss(4)" )
			)
			( pin "J9M1.272"
				( objectStatus "@baseboard_fab2_lib.baseboard_fab2(sch_1):page84_i138:vss(5)" )
			)
			( pin "J9M1.270"
				( objectStatus "@baseboard_fab2_lib.baseboard_fab2(sch_1):page84_i138:vss(6)" )
			)
			( pin "J9M1.268"
				( objectStatus "@baseboard_fab2_lib.baseboard_fab2(sch_1):page84_i138:vss(7)" )
			)
			( pin "J9M1.265"
				( objectStatus "@baseboard_fab2_lib.baseboard_fab2(sch_1):page84_i138:vss(8)" )
			)
			( pin "J9M1.263"
				( objectStatus "@baseboard_fab2_lib.baseboard_fab2(sch_1):page84_i138:vss(9)" )
			)
			( pin "J9M1.261"
				( objectStatus "@baseboard_fab2_lib.baseboard_fab2(sch_1):page84_i138:vss(10)" )
			)
			( pin "J9M1.259"
				( objectStatus "@baseboard_fab2_lib.baseboard_fab2(sch_1):page84_i138:vss(11)" )
			)
			( pin "J9M1.257"
				( objectStatus "@baseboard_fab2_lib.baseboard_fab2(sch_1):page84_i138:vss(12)" )
			)
			( pin "J9M1.254"
				( objectStatus "@baseboard_fab2_lib.baseboard_fab2(sch_1):page84_i138:vss(13)" )
			)
			( pin "J9M1.252"
				( objectStatus "@baseboard_fab2_lib.baseboard_fab2(sch_1):page84_i138:vss(14)" )
			)
			( pin "J9M1.250"
				( objectStatus "@baseboard_fab2_lib.baseboard_fab2(sch_1):page84_i138:vss(15)" )
			)
			( pin "J9M1.248"
				( objectStatus "@baseboard_fab2_lib.baseboard_fab2(sch_1):page84_i138:vss(16)" )
			)
			( pin "J9M1.246"
				( objectStatus "@baseboard_fab2_lib.baseboard_fab2(sch_1):page84_i138:vss(17)" )
			)
			( pin "J9M1.243"
				( objectStatus "@baseboard_fab2_lib.baseboard_fab2(sch_1):page84_i138:vss(18)" )
			)
			( pin "J9M1.241"
				( objectStatus "@baseboard_fab2_lib.baseboard_fab2(sch_1):page84_i138:vss(19)" )
			)
			( pin "J9M1.239"
				( objectStatus "@baseboard_fab2_lib.baseboard_fab2(sch_1):page84_i138:vss(20)" )
			)
			( pin "J9M1.202"
				( objectStatus "@baseboard_fab2_lib.baseboard_fab2(sch_1):page84_i138:vss(21)" )
			)
			( pin "J9M1.200"
				( objectStatus "@baseboard_fab2_lib.baseboard_fab2(sch_1):page84_i138:vss(22)" )
			)
			( pin "J9M1.198"
				( objectStatus "@baseboard_fab2_lib.baseboard_fab2(sch_1):page84_i138:vss(23)" )
			)
			( pin "J9M1.195"
				( objectStatus "@baseboard_fab2_lib.baseboard_fab2(sch_1):page84_i138:vss(24)" )
			)
			( pin "J9M1.193"
				( objectStatus "@baseboard_fab2_lib.baseboard_fab2(sch_1):page84_i138:vss(25)" )
			)
			( pin "J9M1.191"
				( objectStatus "@baseboard_fab2_lib.baseboard_fab2(sch_1):page84_i138:vss(26)" )
			)
			( pin "J9M1.189"
				( objectStatus "@baseboard_fab2_lib.baseboard_fab2(sch_1):page84_i138:vss(27)" )
			)
			( pin "J9M1.187"
				( objectStatus "@baseboard_fab2_lib.baseboard_fab2(sch_1):page84_i138:vss(28)" )
			)
			( pin "J9M1.184"
				( objectStatus "@baseboard_fab2_lib.baseboard_fab2(sch_1):page84_i138:vss(29)" )
			)
			( pin "J9M1.182"
				( objectStatus "@baseboard_fab2_lib.baseboard_fab2(sch_1):page84_i138:vss(30)" )
			)
			( pin "J9M1.180"
				( objectStatus "@baseboard_fab2_lib.baseboard_fab2(sch_1):page84_i138:vss(31)" )
			)
			( pin "J9M1.178"
				( objectStatus "@baseboard_fab2_lib.baseboard_fab2(sch_1):page84_i138:vss(32)" )
			)
			( pin "J9M1.176"
				( objectStatus "@baseboard_fab2_lib.baseboard_fab2(sch_1):page84_i138:vss(33)" )
			)
			( pin "J9M1.173"
				( objectStatus "@baseboard_fab2_lib.baseboard_fab2(sch_1):page84_i138:vss(34)" )
			)
			( pin "J9M1.171"
				( objectStatus "@baseboard_fab2_lib.baseboard_fab2(sch_1):page84_i138:vss(35)" )
			)
			( pin "J9M1.169"
				( objectStatus "@baseboard_fab2_lib.baseboard_fab2(sch_1):page84_i138:vss(36)" )
			)
			( pin "J9M1.167"
				( objectStatus "@baseboard_fab2_lib.baseboard_fab2(sch_1):page84_i138:vss(37)" )
			)
			( pin "J9M1.165"
				( objectStatus "@baseboard_fab2_lib.baseboard_fab2(sch_1):page84_i138:vss(38)" )
			)
			( pin "J9M1.162"
				( objectStatus "@baseboard_fab2_lib.baseboard_fab2(sch_1):page84_i138:vss(39)" )
			)
			( pin "J9M1.160"
				( objectStatus "@baseboard_fab2_lib.baseboard_fab2(sch_1):page84_i138:vss(40)" )
			)
			( pin "J9M1.158"
				( objectStatus "@baseboard_fab2_lib.baseboard_fab2(sch_1):page84_i138:vss(41)" )
			)
			( pin "J9M1.156"
				( objectStatus "@baseboard_fab2_lib.baseboard_fab2(sch_1):page84_i138:vss(42)" )
			)
			( pin "J9M1.154"
				( objectStatus "@baseboard_fab2_lib.baseboard_fab2(sch_1):page84_i138:vss(43)" )
			)
			( pin "J9M1.151"
				( objectStatus "@baseboard_fab2_lib.baseboard_fab2(sch_1):page84_i138:vss(44)" )
			)
			( pin "J9M1.149"
				( objectStatus "@baseboard_fab2_lib.baseboard_fab2(sch_1):page84_i138:vss(45)" )
			)
			( pin "J9M1.147"
				( objectStatus "@baseboard_fab2_lib.baseboard_fab2(sch_1):page84_i138:vss(46)" )
			)
			( pin "J9M1.138"
				( objectStatus "@baseboard_fab2_lib.baseboard_fab2(sch_1):page84_i138:vss(47)" )
			)
			( pin "J9M1.136"
				( objectStatus "@baseboard_fab2_lib.baseboard_fab2(sch_1):page84_i138:vss(48)" )
			)
			( pin "J9M1.134"
				( objectStatus "@baseboard_fab2_lib.baseboard_fab2(sch_1):page84_i138:vss(49)" )
			)
			( pin "J9M1.131"
				( objectStatus "@baseboard_fab2_lib.baseboard_fab2(sch_1):page84_i138:vss(50)" )
			)
			( pin "J9M1.129"
				( objectStatus "@baseboard_fab2_lib.baseboard_fab2(sch_1):page84_i138:vss(51)" )
			)
			( pin "J9M1.127"
				( objectStatus "@baseboard_fab2_lib.baseboard_fab2(sch_1):page84_i138:vss(52)" )
			)
			( pin "J9M1.125"
				( objectStatus "@baseboard_fab2_lib.baseboard_fab2(sch_1):page84_i138:vss(53)" )
			)
			( pin "J9M1.123"
				( objectStatus "@baseboard_fab2_lib.baseboard_fab2(sch_1):page84_i138:vss(54)" )
			)
			( pin "J9M1.120"
				( objectStatus "@baseboard_fab2_lib.baseboard_fab2(sch_1):page84_i138:vss(55)" )
			)
			( pin "J9M1.118"
				( objectStatus "@baseboard_fab2_lib.baseboard_fab2(sch_1):page84_i138:vss(56)" )
			)
			( pin "J9M1.116"
				( objectStatus "@baseboard_fab2_lib.baseboard_fab2(sch_1):page84_i138:vss(57)" )
			)
			( pin "J9M1.114"
				( objectStatus "@baseboard_fab2_lib.baseboard_fab2(sch_1):page84_i138:vss(58)" )
			)
			( pin "J9M1.112"
				( objectStatus "@baseboard_fab2_lib.baseboard_fab2(sch_1):page84_i138:vss(59)" )
			)
			( pin "J9M1.109"
				( objectStatus "@baseboard_fab2_lib.baseboard_fab2(sch_1):page84_i138:vss(60)" )
			)
			( pin "J9M1.107"
				( objectStatus "@baseboard_fab2_lib.baseboard_fab2(sch_1):page84_i138:vss(61)" )
			)
			( pin "J9M1.105"
				( objectStatus "@baseboard_fab2_lib.baseboard_fab2(sch_1):page84_i138:vss(62)" )
			)
			( pin "J9M1.103"
				( objectStatus "@baseboard_fab2_lib.baseboard_fab2(sch_1):page84_i138:vss(63)" )
			)
			( pin "J9M1.101"
				( objectStatus "@baseboard_fab2_lib.baseboard_fab2(sch_1):page84_i138:vss(64)" )
			)
			( pin "J9M1.98"
				( objectStatus "@baseboard_fab2_lib.baseboard_fab2(sch_1):page84_i138:vss(65)" )
			)
			( pin "J9M1.96"
				( objectStatus "@baseboard_fab2_lib.baseboard_fab2(sch_1):page84_i138:vss(66)" )
			)
			( pin "J9M1.94"
				( objectStatus "@baseboard_fab2_lib.baseboard_fab2(sch_1):page84_i138:vss(67)" )
			)
			( pin "J9M1.57"
				( objectStatus "@baseboard_fab2_lib.baseboard_fab2(sch_1):page84_i138:vss(68)" )
			)
			( pin "J9M1.55"
				( objectStatus "@baseboard_fab2_lib.baseboard_fab2(sch_1):page84_i138:vss(69)" )
			)
			( pin "J9M1.53"
				( objectStatus "@baseboard_fab2_lib.baseboard_fab2(sch_1):page84_i138:vss(70)" )
			)
			( pin "J9M1.50"
				( objectStatus "@baseboard_fab2_lib.baseboard_fab2(sch_1):page84_i138:vss(71)" )
			)
			( pin "J9M1.48"
				( objectStatus "@baseboard_fab2_lib.baseboard_fab2(sch_1):page84_i138:vss(72)" )
			)
			( pin "J9M1.46"
				( objectStatus "@baseboard_fab2_lib.baseboard_fab2(sch_1):page84_i138:vss(73)" )
			)
			( pin "J9M1.44"
				( objectStatus "@baseboard_fab2_lib.baseboard_fab2(sch_1):page84_i138:vss(74)" )
			)
			( pin "J9M1.42"
				( objectStatus "@baseboard_fab2_lib.baseboard_fab2(sch_1):page84_i138:vss(75)" )
			)
			( pin "J9M1.39"
				( objectStatus "@baseboard_fab2_lib.baseboard_fab2(sch_1):page84_i138:vss(76)" )
			)
			( pin "J9M1.37"
				( objectStatus "@baseboard_fab2_lib.baseboard_fab2(sch_1):page84_i138:vss(77)" )
			)
			( pin "J9M1.35"
				( objectStatus "@baseboard_fab2_lib.baseboard_fab2(sch_1):page84_i138:vss(78)" )
			)
			( pin "J9M1.33"
				( objectStatus "@baseboard_fab2_lib.baseboard_fab2(sch_1):page84_i138:vss(79)" )
			)
			( pin "J9M1.31"
				( objectStatus "@baseboard_fab2_lib.baseboard_fab2(sch_1):page84_i138:vss(80)" )
			)
			( pin "J9M1.28"
				( objectStatus "@baseboard_fab2_lib.baseboard_fab2(sch_1):page84_i138:vss(81)" )
			)
			( pin "J9M1.26"
				( objectStatus "@baseboard_fab2_lib.baseboard_fab2(sch_1):page84_i138:vss(82)" )
			)
			( pin "J9M1.24"
				( objectStatus "@baseboard_fab2_lib.baseboard_fab2(sch_1):page84_i138:vss(83)" )
			)
			( pin "J9M1.22"
				( objectStatus "@baseboard_fab2_lib.baseboard_fab2(sch_1):page84_i138:vss(84)" )
			)
			( pin "J9M1.20"
				( objectStatus "@baseboard_fab2_lib.baseboard_fab2(sch_1):page84_i138:vss(85)" )
			)
			( pin "J9M1.17"
				( objectStatus "@baseboard_fab2_lib.baseboard_fab2(sch_1):page84_i138:vss(86)" )
			)
			( pin "J9M1.15"
				( objectStatus "@baseboard_fab2_lib.baseboard_fab2(sch_1):page84_i138:vss(87)" )
			)
			( pin "J9M1.13"
				( objectStatus "@baseboard_fab2_lib.baseboard_fab2(sch_1):page84_i138:vss(88)" )
			)
			( pin "J9M1.11"
				( objectStatus "@baseboard_fab2_lib.baseboard_fab2(sch_1):page84_i138:vss(89)" )
			)
			( pin "J9M1.9"
				( objectStatus "@baseboard_fab2_lib.baseboard_fab2(sch_1):page84_i138:vss(90)" )
			)
			( pin "J9M1.6"
				( objectStatus "@baseboard_fab2_lib.baseboard_fab2(sch_1):page84_i138:vss(91)" )
			)
			( pin "J9M1.4"
				( objectStatus "@baseboard_fab2_lib.baseboard_fab2(sch_1):page84_i138:vss(92)" )
			)
			( pin "J9M1.2"
				( objectStatus "@baseboard_fab2_lib.baseboard_fab2(sch_1):page84_i138:vss(93)" )
			)
			( pin "J1A2.283"
				( objectStatus "@baseboard_fab2_lib.baseboard_fab2(sch_1):page85_i43:vss(0)" )
			)
			( pin "J1A2.281"
				( objectStatus "@baseboard_fab2_lib.baseboard_fab2(sch_1):page85_i43:vss(1)" )
			)
			( pin "J1A2.279"
				( objectStatus "@baseboard_fab2_lib.baseboard_fab2(sch_1):page85_i43:vss(2)" )
			)
			( pin "J1A2.276"
				( objectStatus "@baseboard_fab2_lib.baseboard_fab2(sch_1):page85_i43:vss(3)" )
			)
			( pin "J1A2.274"
				( objectStatus "@baseboard_fab2_lib.baseboard_fab2(sch_1):page85_i43:vss(4)" )
			)
			( pin "J1A2.272"
				( objectStatus "@baseboard_fab2_lib.baseboard_fab2(sch_1):page85_i43:vss(5)" )
			)
			( pin "J1A2.270"
				( objectStatus "@baseboard_fab2_lib.baseboard_fab2(sch_1):page85_i43:vss(6)" )
			)
			( pin "J1A2.268"
				( objectStatus "@baseboard_fab2_lib.baseboard_fab2(sch_1):page85_i43:vss(7)" )
			)
			( pin "J1A2.265"
				( objectStatus "@baseboard_fab2_lib.baseboard_fab2(sch_1):page85_i43:vss(8)" )
			)
			( pin "J1A2.263"
				( objectStatus "@baseboard_fab2_lib.baseboard_fab2(sch_1):page85_i43:vss(9)" )
			)
			( pin "J1A2.261"
				( objectStatus "@baseboard_fab2_lib.baseboard_fab2(sch_1):page85_i43:vss(10)" )
			)
			( pin "J1A2.259"
				( objectStatus "@baseboard_fab2_lib.baseboard_fab2(sch_1):page85_i43:vss(11)" )
			)
			( pin "J1A2.257"
				( objectStatus "@baseboard_fab2_lib.baseboard_fab2(sch_1):page85_i43:vss(12)" )
			)
			( pin "J1A2.254"
				( objectStatus "@baseboard_fab2_lib.baseboard_fab2(sch_1):page85_i43:vss(13)" )
			)
			( pin "J1A2.252"
				( objectStatus "@baseboard_fab2_lib.baseboard_fab2(sch_1):page85_i43:vss(14)" )
			)
			( pin "J1A2.250"
				( objectStatus "@baseboard_fab2_lib.baseboard_fab2(sch_1):page85_i43:vss(15)" )
			)
			( pin "J1A2.248"
				( objectStatus "@baseboard_fab2_lib.baseboard_fab2(sch_1):page85_i43:vss(16)" )
			)
			( pin "J1A2.246"
				( objectStatus "@baseboard_fab2_lib.baseboard_fab2(sch_1):page85_i43:vss(17)" )
			)
			( pin "J1A2.243"
				( objectStatus "@baseboard_fab2_lib.baseboard_fab2(sch_1):page85_i43:vss(18)" )
			)
			( pin "J1A2.241"
				( objectStatus "@baseboard_fab2_lib.baseboard_fab2(sch_1):page85_i43:vss(19)" )
			)
			( pin "J1A2.239"
				( objectStatus "@baseboard_fab2_lib.baseboard_fab2(sch_1):page85_i43:vss(20)" )
			)
			( pin "J1A2.202"
				( objectStatus "@baseboard_fab2_lib.baseboard_fab2(sch_1):page85_i43:vss(21)" )
			)
			( pin "J1A2.200"
				( objectStatus "@baseboard_fab2_lib.baseboard_fab2(sch_1):page85_i43:vss(22)" )
			)
			( pin "J1A2.198"
				( objectStatus "@baseboard_fab2_lib.baseboard_fab2(sch_1):page85_i43:vss(23)" )
			)
			( pin "J1A2.195"
				( objectStatus "@baseboard_fab2_lib.baseboard_fab2(sch_1):page85_i43:vss(24)" )
			)
			( pin "J1A2.193"
				( objectStatus "@baseboard_fab2_lib.baseboard_fab2(sch_1):page85_i43:vss(25)" )
			)
			( pin "J1A2.191"
				( objectStatus "@baseboard_fab2_lib.baseboard_fab2(sch_1):page85_i43:vss(26)" )
			)
			( pin "J1A2.189"
				( objectStatus "@baseboard_fab2_lib.baseboard_fab2(sch_1):page85_i43:vss(27)" )
			)
			( pin "J1A2.187"
				( objectStatus "@baseboard_fab2_lib.baseboard_fab2(sch_1):page85_i43:vss(28)" )
			)
			( pin "J1A2.184"
				( objectStatus "@baseboard_fab2_lib.baseboard_fab2(sch_1):page85_i43:vss(29)" )
			)
			( pin "J1A2.182"
				( objectStatus "@baseboard_fab2_lib.baseboard_fab2(sch_1):page85_i43:vss(30)" )
			)
			( pin "J1A2.180"
				( objectStatus "@baseboard_fab2_lib.baseboard_fab2(sch_1):page85_i43:vss(31)" )
			)
			( pin "J1A2.178"
				( objectStatus "@baseboard_fab2_lib.baseboard_fab2(sch_1):page85_i43:vss(32)" )
			)
			( pin "J1A2.176"
				( objectStatus "@baseboard_fab2_lib.baseboard_fab2(sch_1):page85_i43:vss(33)" )
			)
			( pin "J1A2.173"
				( objectStatus "@baseboard_fab2_lib.baseboard_fab2(sch_1):page85_i43:vss(34)" )
			)
			( pin "J1A2.171"
				( objectStatus "@baseboard_fab2_lib.baseboard_fab2(sch_1):page85_i43:vss(35)" )
			)
			( pin "J1A2.169"
				( objectStatus "@baseboard_fab2_lib.baseboard_fab2(sch_1):page85_i43:vss(36)" )
			)
			( pin "J1A2.167"
				( objectStatus "@baseboard_fab2_lib.baseboard_fab2(sch_1):page85_i43:vss(37)" )
			)
			( pin "J1A2.165"
				( objectStatus "@baseboard_fab2_lib.baseboard_fab2(sch_1):page85_i43:vss(38)" )
			)
			( pin "J1A2.162"
				( objectStatus "@baseboard_fab2_lib.baseboard_fab2(sch_1):page85_i43:vss(39)" )
			)
			( pin "J1A2.160"
				( objectStatus "@baseboard_fab2_lib.baseboard_fab2(sch_1):page85_i43:vss(40)" )
			)
			( pin "J1A2.158"
				( objectStatus "@baseboard_fab2_lib.baseboard_fab2(sch_1):page85_i43:vss(41)" )
			)
			( pin "J1A2.156"
				( objectStatus "@baseboard_fab2_lib.baseboard_fab2(sch_1):page85_i43:vss(42)" )
			)
			( pin "J1A2.154"
				( objectStatus "@baseboard_fab2_lib.baseboard_fab2(sch_1):page85_i43:vss(43)" )
			)
			( pin "J1A2.151"
				( objectStatus "@baseboard_fab2_lib.baseboard_fab2(sch_1):page85_i43:vss(44)" )
			)
			( pin "J1A2.149"
				( objectStatus "@baseboard_fab2_lib.baseboard_fab2(sch_1):page85_i43:vss(45)" )
			)
			( pin "J1A2.147"
				( objectStatus "@baseboard_fab2_lib.baseboard_fab2(sch_1):page85_i43:vss(46)" )
			)
			( pin "J1A2.138"
				( objectStatus "@baseboard_fab2_lib.baseboard_fab2(sch_1):page85_i43:vss(47)" )
			)
			( pin "J1A2.136"
				( objectStatus "@baseboard_fab2_lib.baseboard_fab2(sch_1):page85_i43:vss(48)" )
			)
			( pin "J1A2.134"
				( objectStatus "@baseboard_fab2_lib.baseboard_fab2(sch_1):page85_i43:vss(49)" )
			)
			( pin "J1A2.131"
				( objectStatus "@baseboard_fab2_lib.baseboard_fab2(sch_1):page85_i43:vss(50)" )
			)
			( pin "J1A2.129"
				( objectStatus "@baseboard_fab2_lib.baseboard_fab2(sch_1):page85_i43:vss(51)" )
			)
			( pin "J1A2.127"
				( objectStatus "@baseboard_fab2_lib.baseboard_fab2(sch_1):page85_i43:vss(52)" )
			)
			( pin "J1A2.125"
				( objectStatus "@baseboard_fab2_lib.baseboard_fab2(sch_1):page85_i43:vss(53)" )
			)
			( pin "J1A2.123"
				( objectStatus "@baseboard_fab2_lib.baseboard_fab2(sch_1):page85_i43:vss(54)" )
			)
			( pin "J1A2.120"
				( objectStatus "@baseboard_fab2_lib.baseboard_fab2(sch_1):page85_i43:vss(55)" )
			)
			( pin "J1A2.118"
				( objectStatus "@baseboard_fab2_lib.baseboard_fab2(sch_1):page85_i43:vss(56)" )
			)
			( pin "J1A2.116"
				( objectStatus "@baseboard_fab2_lib.baseboard_fab2(sch_1):page85_i43:vss(57)" )
			)
			( pin "J1A2.114"
				( objectStatus "@baseboard_fab2_lib.baseboard_fab2(sch_1):page85_i43:vss(58)" )
			)
			( pin "J1A2.112"
				( objectStatus "@baseboard_fab2_lib.baseboard_fab2(sch_1):page85_i43:vss(59)" )
			)
			( pin "J1A2.109"
				( objectStatus "@baseboard_fab2_lib.baseboard_fab2(sch_1):page85_i43:vss(60)" )
			)
			( pin "J1A2.107"
				( objectStatus "@baseboard_fab2_lib.baseboard_fab2(sch_1):page85_i43:vss(61)" )
			)
			( pin "J1A2.105"
				( objectStatus "@baseboard_fab2_lib.baseboard_fab2(sch_1):page85_i43:vss(62)" )
			)
			( pin "J1A2.103"
				( objectStatus "@baseboard_fab2_lib.baseboard_fab2(sch_1):page85_i43:vss(63)" )
			)
			( pin "J1A2.101"
				( objectStatus "@baseboard_fab2_lib.baseboard_fab2(sch_1):page85_i43:vss(64)" )
			)
			( pin "J1A2.98"
				( objectStatus "@baseboard_fab2_lib.baseboard_fab2(sch_1):page85_i43:vss(65)" )
			)
			( pin "J1A2.96"
				( objectStatus "@baseboard_fab2_lib.baseboard_fab2(sch_1):page85_i43:vss(66)" )
			)
			( pin "J1A2.94"
				( objectStatus "@baseboard_fab2_lib.baseboard_fab2(sch_1):page85_i43:vss(67)" )
			)
			( pin "J1A2.57"
				( objectStatus "@baseboard_fab2_lib.baseboard_fab2(sch_1):page85_i43:vss(68)" )
			)
			( pin "J1A2.55"
				( objectStatus "@baseboard_fab2_lib.baseboard_fab2(sch_1):page85_i43:vss(69)" )
			)
			( pin "J1A2.53"
				( objectStatus "@baseboard_fab2_lib.baseboard_fab2(sch_1):page85_i43:vss(70)" )
			)
			( pin "J1A2.50"
				( objectStatus "@baseboard_fab2_lib.baseboard_fab2(sch_1):page85_i43:vss(71)" )
			)
			( pin "J1A2.48"
				( objectStatus "@baseboard_fab2_lib.baseboard_fab2(sch_1):page85_i43:vss(72)" )
			)
			( pin "J1A2.46"
				( objectStatus "@baseboard_fab2_lib.baseboard_fab2(sch_1):page85_i43:vss(73)" )
			)
			( pin "J1A2.44"
				( objectStatus "@baseboard_fab2_lib.baseboard_fab2(sch_1):page85_i43:vss(74)" )
			)
			( pin "J1A2.42"
				( objectStatus "@baseboard_fab2_lib.baseboard_fab2(sch_1):page85_i43:vss(75)" )
			)
			( pin "J1A2.39"
				( objectStatus "@baseboard_fab2_lib.baseboard_fab2(sch_1):page85_i43:vss(76)" )
			)
			( pin "J1A2.37"
				( objectStatus "@baseboard_fab2_lib.baseboard_fab2(sch_1):page85_i43:vss(77)" )
			)
			( pin "J1A2.35"
				( objectStatus "@baseboard_fab2_lib.baseboard_fab2(sch_1):page85_i43:vss(78)" )
			)
			( pin "J1A2.33"
				( objectStatus "@baseboard_fab2_lib.baseboard_fab2(sch_1):page85_i43:vss(79)" )
			)
			( pin "J1A2.31"
				( objectStatus "@baseboard_fab2_lib.baseboard_fab2(sch_1):page85_i43:vss(80)" )
			)
			( pin "J1A2.28"
				( objectStatus "@baseboard_fab2_lib.baseboard_fab2(sch_1):page85_i43:vss(81)" )
			)
			( pin "J1A2.26"
				( objectStatus "@baseboard_fab2_lib.baseboard_fab2(sch_1):page85_i43:vss(82)" )
			)
			( pin "J1A2.24"
				( objectStatus "@baseboard_fab2_lib.baseboard_fab2(sch_1):page85_i43:vss(83)" )
			)
			( pin "J1A2.22"
				( objectStatus "@baseboard_fab2_lib.baseboard_fab2(sch_1):page85_i43:vss(84)" )
			)
			( pin "J1A2.20"
				( objectStatus "@baseboard_fab2_lib.baseboard_fab2(sch_1):page85_i43:vss(85)" )
			)
			( pin "J1A2.17"
				( objectStatus "@baseboard_fab2_lib.baseboard_fab2(sch_1):page85_i43:vss(86)" )
			)
			( pin "J1A2.15"
				( objectStatus "@baseboard_fab2_lib.baseboard_fab2(sch_1):page85_i43:vss(87)" )
			)
			( pin "J1A2.13"
				( objectStatus "@baseboard_fab2_lib.baseboard_fab2(sch_1):page85_i43:vss(88)" )
			)
			( pin "J1A2.11"
				( objectStatus "@baseboard_fab2_lib.baseboard_fab2(sch_1):page85_i43:vss(89)" )
			)
			( pin "J1A2.9"
				( objectStatus "@baseboard_fab2_lib.baseboard_fab2(sch_1):page85_i43:vss(90)" )
			)
			( pin "J1A2.6"
				( objectStatus "@baseboard_fab2_lib.baseboard_fab2(sch_1):page85_i43:vss(91)" )
			)
			( pin "J1A2.4"
				( objectStatus "@baseboard_fab2_lib.baseboard_fab2(sch_1):page85_i43:vss(92)" )
			)
			( pin "J1A2.2"
				( objectStatus "@baseboard_fab2_lib.baseboard_fab2(sch_1):page85_i43:vss(93)" )
			)
			( pin "J1A2.152"
				( objectStatus "@baseboard_fab2_lib.baseboard_fab2(sch_1):page85_i66:dqs0n" )
			)
			( pin "J1A2.153"
				( objectStatus "@baseboard_fab2_lib.baseboard_fab2(sch_1):page85_i66:dqs0p" )
			)
			( pin "J1A2.163"
				( objectStatus "@baseboard_fab2_lib.baseboard_fab2(sch_1):page85_i66:dqs1n" )
			)
			( pin "J1A2.164"
				( objectStatus "@baseboard_fab2_lib.baseboard_fab2(sch_1):page85_i66:dqs1p" )
			)
			( pin "J1A2.174"
				( objectStatus "@baseboard_fab2_lib.baseboard_fab2(sch_1):page85_i66:dqs2n" )
			)
			( pin "J1A2.175"
				( objectStatus "@baseboard_fab2_lib.baseboard_fab2(sch_1):page85_i66:dqs2p" )
			)
			( pin "J1A2.185"
				( objectStatus "@baseboard_fab2_lib.baseboard_fab2(sch_1):page85_i66:dqs3n" )
			)
			( pin "J1A2.186"
				( objectStatus "@baseboard_fab2_lib.baseboard_fab2(sch_1):page85_i66:dqs3p" )
			)
			( pin "J1A2.244"
				( objectStatus "@baseboard_fab2_lib.baseboard_fab2(sch_1):page85_i66:dqs4n" )
			)
			( pin "J1A2.245"
				( objectStatus "@baseboard_fab2_lib.baseboard_fab2(sch_1):page85_i66:dqs4p" )
			)
			( pin "J1A2.255"
				( objectStatus "@baseboard_fab2_lib.baseboard_fab2(sch_1):page85_i66:dqs5n" )
			)
			( pin "J1A2.256"
				( objectStatus "@baseboard_fab2_lib.baseboard_fab2(sch_1):page85_i66:dqs5p" )
			)
			( pin "J1A2.266"
				( objectStatus "@baseboard_fab2_lib.baseboard_fab2(sch_1):page85_i66:dqs6n" )
			)
			( pin "J1A2.267"
				( objectStatus "@baseboard_fab2_lib.baseboard_fab2(sch_1):page85_i66:dqs6p" )
			)
			( pin "J1A2.277"
				( objectStatus "@baseboard_fab2_lib.baseboard_fab2(sch_1):page85_i66:dqs7n" )
			)
			( pin "J1A2.278"
				( objectStatus "@baseboard_fab2_lib.baseboard_fab2(sch_1):page85_i66:dqs7p" )
			)
			( pin "J1A2.196"
				( objectStatus "@baseboard_fab2_lib.baseboard_fab2(sch_1):page85_i66:dqs8n" )
			)
			( pin "J1A2.197"
				( objectStatus "@baseboard_fab2_lib.baseboard_fab2(sch_1):page85_i66:dqs8p" )
			)
			( pin "J1A2.8"
				( objectStatus "@baseboard_fab2_lib.baseboard_fab2(sch_1):page85_i66:dqs9n" )
			)
			( pin "J1A2.7"
				( objectStatus "@baseboard_fab2_lib.baseboard_fab2(sch_1):page85_i66:dqs9p" )
			)
			( pin "J1A2.19"
				( objectStatus "@baseboard_fab2_lib.baseboard_fab2(sch_1):page85_i66:dqs10n" )
			)
			( pin "J1A2.18"
				( objectStatus "@baseboard_fab2_lib.baseboard_fab2(sch_1):page85_i66:dqs10p" )
			)
			( pin "J1A2.30"
				( objectStatus "@baseboard_fab2_lib.baseboard_fab2(sch_1):page85_i66:dqs11n" )
			)
			( pin "J1A2.29"
				( objectStatus "@baseboard_fab2_lib.baseboard_fab2(sch_1):page85_i66:dqs11p" )
			)
			( pin "J1A2.41"
				( objectStatus "@baseboard_fab2_lib.baseboard_fab2(sch_1):page85_i66:dqs12n" )
			)
			( pin "J1A2.40"
				( objectStatus "@baseboard_fab2_lib.baseboard_fab2(sch_1):page85_i66:dqs12p" )
			)
			( pin "J1A2.100"
				( objectStatus "@baseboard_fab2_lib.baseboard_fab2(sch_1):page85_i66:dqs13n" )
			)
			( pin "J1A2.99"
				( objectStatus "@baseboard_fab2_lib.baseboard_fab2(sch_1):page85_i66:dqs13p" )
			)
			( pin "J1A2.111"
				( objectStatus "@baseboard_fab2_lib.baseboard_fab2(sch_1):page85_i66:dqs14n" )
			)
			( pin "J1A2.110"
				( objectStatus "@baseboard_fab2_lib.baseboard_fab2(sch_1):page85_i66:dqs14p" )
			)
			( pin "J1A2.122"
				( objectStatus "@baseboard_fab2_lib.baseboard_fab2(sch_1):page85_i66:dqs15n" )
			)
			( pin "J1A2.121"
				( objectStatus "@baseboard_fab2_lib.baseboard_fab2(sch_1):page85_i66:dqs15p" )
			)
			( pin "J1A2.133"
				( objectStatus "@baseboard_fab2_lib.baseboard_fab2(sch_1):page85_i66:dqs16n" )
			)
			( pin "J1A2.132"
				( objectStatus "@baseboard_fab2_lib.baseboard_fab2(sch_1):page85_i66:dqs16p" )
			)
			( pin "J1A2.52"
				( objectStatus "@baseboard_fab2_lib.baseboard_fab2(sch_1):page85_i66:dqs17n" )
			)
			( pin "J1A2.51"
				( objectStatus "@baseboard_fab2_lib.baseboard_fab2(sch_1):page85_i66:dqs17p" )
			)
			( pin "J1A2.79"
				( objectStatus "@baseboard_fab2_lib.baseboard_fab2(sch_1):page85_i111:a0" )
			)
			( pin "J1A2.72"
				( objectStatus "@baseboard_fab2_lib.baseboard_fab2(sch_1):page85_i111:a1" )
			)
			( pin "J1A2.216"
				( objectStatus "@baseboard_fab2_lib.baseboard_fab2(sch_1):page85_i111:a2" )
			)
			( pin "J1A2.71"
				( objectStatus "@baseboard_fab2_lib.baseboard_fab2(sch_1):page85_i111:a3" )
			)
			( pin "J1A2.214"
				( objectStatus "@baseboard_fab2_lib.baseboard_fab2(sch_1):page85_i111:a4" )
			)
			( pin "J1A2.213"
				( objectStatus "@baseboard_fab2_lib.baseboard_fab2(sch_1):page85_i111:a5" )
			)
			( pin "J1A2.69"
				( objectStatus "@baseboard_fab2_lib.baseboard_fab2(sch_1):page85_i111:a6" )
			)
			( pin "J1A2.211"
				( objectStatus "@baseboard_fab2_lib.baseboard_fab2(sch_1):page85_i111:a7" )
			)
			( pin "J1A2.68"
				( objectStatus "@baseboard_fab2_lib.baseboard_fab2(sch_1):page85_i111:a8" )
			)
			( pin "J1A2.66"
				( objectStatus "@baseboard_fab2_lib.baseboard_fab2(sch_1):page85_i111:a9" )
			)
			( pin "J1A2.225"
				( objectStatus "@baseboard_fab2_lib.baseboard_fab2(sch_1):page85_i111:a10" )
			)
			( pin "J1A2.210"
				( objectStatus "@baseboard_fab2_lib.baseboard_fab2(sch_1):page85_i111:a11" )
			)
			( pin "J1A2.65"
				( objectStatus "@baseboard_fab2_lib.baseboard_fab2(sch_1):page85_i111:a12" )
			)
			( pin "J1A2.232"
				( objectStatus "@baseboard_fab2_lib.baseboard_fab2(sch_1):page85_i111:a13" )
			)
			( pin "J1A2.228"
				( objectStatus "@baseboard_fab2_lib.baseboard_fab2(sch_1):page85_i111:a14_we_n" )
			)
			( pin "J1A2.86"
				( objectStatus "@baseboard_fab2_lib.baseboard_fab2(sch_1):page85_i111:a15_cas_n" )
			)
			( pin "J1A2.82"
				( objectStatus "@baseboard_fab2_lib.baseboard_fab2(sch_1):page85_i111:a16_ras_n" )
			)
			( pin "J1A2.234"
				( objectStatus "@baseboard_fab2_lib.baseboard_fab2(sch_1):page85_i111:a17" )
			)
			( pin "J1A2.62"
				( objectStatus "@baseboard_fab2_lib.baseboard_fab2(sch_1):page85_i111:act_n" )
			)
			( pin "J1A2.208"
				( objectStatus "@baseboard_fab2_lib.baseboard_fab2(sch_1):page85_i111:alert_n" )
			)
			( pin "J1A2.81"
				( objectStatus "@baseboard_fab2_lib.baseboard_fab2(sch_1):page85_i111:ba(0)" )
			)
			( pin "J1A2.224"
				( objectStatus "@baseboard_fab2_lib.baseboard_fab2(sch_1):page85_i111:ba(1)" )
			)
			( pin "J1A2.63"
				( objectStatus "@baseboard_fab2_lib.baseboard_fab2(sch_1):page85_i111:bg(0)" )
			)
			( pin "J1A2.207"
				( objectStatus "@baseboard_fab2_lib.baseboard_fab2(sch_1):page85_i111:bg(1)" )
			)
			( pin "J1A2.235"
				( objectStatus "@baseboard_fab2_lib.baseboard_fab2(sch_1):page85_i111:c(2)" )
			)
			( pin "J1A2.49"
				( objectStatus "@baseboard_fab2_lib.baseboard_fab2(sch_1):page85_i111:cb(0)" )
			)
			( pin "J1A2.194"
				( objectStatus "@baseboard_fab2_lib.baseboard_fab2(sch_1):page85_i111:cb(1)" )
			)
			( pin "J1A2.56"
				( objectStatus "@baseboard_fab2_lib.baseboard_fab2(sch_1):page85_i111:cb(2)" )
			)
			( pin "J1A2.201"
				( objectStatus "@baseboard_fab2_lib.baseboard_fab2(sch_1):page85_i111:cb(3)" )
			)
			( pin "J1A2.47"
				( objectStatus "@baseboard_fab2_lib.baseboard_fab2(sch_1):page85_i111:cb(4)" )
			)
			( pin "J1A2.192"
				( objectStatus "@baseboard_fab2_lib.baseboard_fab2(sch_1):page85_i111:cb(5)" )
			)
			( pin "J1A2.54"
				( objectStatus "@baseboard_fab2_lib.baseboard_fab2(sch_1):page85_i111:cb(6)" )
			)
			( pin "J1A2.199"
				( objectStatus "@baseboard_fab2_lib.baseboard_fab2(sch_1):page85_i111:cb(7)" )
			)
			( pin "J1A2.75"
				( objectStatus "@baseboard_fab2_lib.baseboard_fab2(sch_1):page85_i111:ck0n" )
			)
			( pin "J1A2.74"
				( objectStatus "@baseboard_fab2_lib.baseboard_fab2(sch_1):page85_i111:ck0p" )
			)
			( pin "J1A2.219"
				( objectStatus "@baseboard_fab2_lib.baseboard_fab2(sch_1):page85_i111:ck1n" )
			)
			( pin "J1A2.218"
				( objectStatus "@baseboard_fab2_lib.baseboard_fab2(sch_1):page85_i111:ck1p" )
			)
			( pin "J1A2.60"
				( objectStatus "@baseboard_fab2_lib.baseboard_fab2(sch_1):page85_i111:cke(0)" )
			)
			( pin "J1A2.203"
				( objectStatus "@baseboard_fab2_lib.baseboard_fab2(sch_1):page85_i111:cke(1)" )
			)
			( pin "J1A2.5"
				( objectStatus "@baseboard_fab2_lib.baseboard_fab2(sch_1):page85_i111:dq(0)" )
			)
			( pin "J1A2.150"
				( objectStatus "@baseboard_fab2_lib.baseboard_fab2(sch_1):page85_i111:dq(1)" )
			)
			( pin "J1A2.12"
				( objectStatus "@baseboard_fab2_lib.baseboard_fab2(sch_1):page85_i111:dq(2)" )
			)
			( pin "J1A2.157"
				( objectStatus "@baseboard_fab2_lib.baseboard_fab2(sch_1):page85_i111:dq(3)" )
			)
			( pin "J1A2.3"
				( objectStatus "@baseboard_fab2_lib.baseboard_fab2(sch_1):page85_i111:dq(4)" )
			)
			( pin "J1A2.148"
				( objectStatus "@baseboard_fab2_lib.baseboard_fab2(sch_1):page85_i111:dq(5)" )
			)
			( pin "J1A2.10"
				( objectStatus "@baseboard_fab2_lib.baseboard_fab2(sch_1):page85_i111:dq(6)" )
			)
			( pin "J1A2.155"
				( objectStatus "@baseboard_fab2_lib.baseboard_fab2(sch_1):page85_i111:dq(7)" )
			)
			( pin "J1A2.16"
				( objectStatus "@baseboard_fab2_lib.baseboard_fab2(sch_1):page85_i111:dq(8)" )
			)
			( pin "J1A2.161"
				( objectStatus "@baseboard_fab2_lib.baseboard_fab2(sch_1):page85_i111:dq(9)" )
			)
			( pin "J1A2.23"
				( objectStatus "@baseboard_fab2_lib.baseboard_fab2(sch_1):page85_i111:dq(10)" )
			)
			( pin "J1A2.168"
				( objectStatus "@baseboard_fab2_lib.baseboard_fab2(sch_1):page85_i111:dq(11)" )
			)
			( pin "J1A2.14"
				( objectStatus "@baseboard_fab2_lib.baseboard_fab2(sch_1):page85_i111:dq(12)" )
			)
			( pin "J1A2.159"
				( objectStatus "@baseboard_fab2_lib.baseboard_fab2(sch_1):page85_i111:dq(13)" )
			)
			( pin "J1A2.21"
				( objectStatus "@baseboard_fab2_lib.baseboard_fab2(sch_1):page85_i111:dq(14)" )
			)
			( pin "J1A2.166"
				( objectStatus "@baseboard_fab2_lib.baseboard_fab2(sch_1):page85_i111:dq(15)" )
			)
			( pin "J1A2.27"
				( objectStatus "@baseboard_fab2_lib.baseboard_fab2(sch_1):page85_i111:dq(16)" )
			)
			( pin "J1A2.172"
				( objectStatus "@baseboard_fab2_lib.baseboard_fab2(sch_1):page85_i111:dq(17)" )
			)
			( pin "J1A2.34"
				( objectStatus "@baseboard_fab2_lib.baseboard_fab2(sch_1):page85_i111:dq(18)" )
			)
			( pin "J1A2.179"
				( objectStatus "@baseboard_fab2_lib.baseboard_fab2(sch_1):page85_i111:dq(19)" )
			)
			( pin "J1A2.25"
				( objectStatus "@baseboard_fab2_lib.baseboard_fab2(sch_1):page85_i111:dq(20)" )
			)
			( pin "J1A2.170"
				( objectStatus "@baseboard_fab2_lib.baseboard_fab2(sch_1):page85_i111:dq(21)" )
			)
			( pin "J1A2.32"
				( objectStatus "@baseboard_fab2_lib.baseboard_fab2(sch_1):page85_i111:dq(22)" )
			)
			( pin "J1A2.177"
				( objectStatus "@baseboard_fab2_lib.baseboard_fab2(sch_1):page85_i111:dq(23)" )
			)
			( pin "J1A2.38"
				( objectStatus "@baseboard_fab2_lib.baseboard_fab2(sch_1):page85_i111:dq(24)" )
			)
			( pin "J1A2.183"
				( objectStatus "@baseboard_fab2_lib.baseboard_fab2(sch_1):page85_i111:dq(25)" )
			)
			( pin "J1A2.45"
				( objectStatus "@baseboard_fab2_lib.baseboard_fab2(sch_1):page85_i111:dq(26)" )
			)
			( pin "J1A2.190"
				( objectStatus "@baseboard_fab2_lib.baseboard_fab2(sch_1):page85_i111:dq(27)" )
			)
			( pin "J1A2.36"
				( objectStatus "@baseboard_fab2_lib.baseboard_fab2(sch_1):page85_i111:dq(28)" )
			)
			( pin "J1A2.181"
				( objectStatus "@baseboard_fab2_lib.baseboard_fab2(sch_1):page85_i111:dq(29)" )
			)
			( pin "J1A2.43"
				( objectStatus "@baseboard_fab2_lib.baseboard_fab2(sch_1):page85_i111:dq(30)" )
			)
			( pin "J1A2.188"
				( objectStatus "@baseboard_fab2_lib.baseboard_fab2(sch_1):page85_i111:dq(31)" )
			)
			( pin "J1A2.97"
				( objectStatus "@baseboard_fab2_lib.baseboard_fab2(sch_1):page85_i111:dq(32)" )
			)
			( pin "J1A2.242"
				( objectStatus "@baseboard_fab2_lib.baseboard_fab2(sch_1):page85_i111:dq(33)" )
			)
			( pin "J1A2.104"
				( objectStatus "@baseboard_fab2_lib.baseboard_fab2(sch_1):page85_i111:dq(34)" )
			)
			( pin "J1A2.249"
				( objectStatus "@baseboard_fab2_lib.baseboard_fab2(sch_1):page85_i111:dq(35)" )
			)
			( pin "J1A2.95"
				( objectStatus "@baseboard_fab2_lib.baseboard_fab2(sch_1):page85_i111:dq(36)" )
			)
			( pin "J1A2.240"
				( objectStatus "@baseboard_fab2_lib.baseboard_fab2(sch_1):page85_i111:dq(37)" )
			)
			( pin "J1A2.102"
				( objectStatus "@baseboard_fab2_lib.baseboard_fab2(sch_1):page85_i111:dq(38)" )
			)
			( pin "J1A2.247"
				( objectStatus "@baseboard_fab2_lib.baseboard_fab2(sch_1):page85_i111:dq(39)" )
			)
			( pin "J1A2.108"
				( objectStatus "@baseboard_fab2_lib.baseboard_fab2(sch_1):page85_i111:dq(40)" )
			)
			( pin "J1A2.253"
				( objectStatus "@baseboard_fab2_lib.baseboard_fab2(sch_1):page85_i111:dq(41)" )
			)
			( pin "J1A2.115"
				( objectStatus "@baseboard_fab2_lib.baseboard_fab2(sch_1):page85_i111:dq(42)" )
			)
			( pin "J1A2.260"
				( objectStatus "@baseboard_fab2_lib.baseboard_fab2(sch_1):page85_i111:dq(43)" )
			)
			( pin "J1A2.106"
				( objectStatus "@baseboard_fab2_lib.baseboard_fab2(sch_1):page85_i111:dq(44)" )
			)
			( pin "J1A2.251"
				( objectStatus "@baseboard_fab2_lib.baseboard_fab2(sch_1):page85_i111:dq(45)" )
			)
			( pin "J1A2.113"
				( objectStatus "@baseboard_fab2_lib.baseboard_fab2(sch_1):page85_i111:dq(46)" )
			)
			( pin "J1A2.258"
				( objectStatus "@baseboard_fab2_lib.baseboard_fab2(sch_1):page85_i111:dq(47)" )
			)
			( pin "J1A2.119"
				( objectStatus "@baseboard_fab2_lib.baseboard_fab2(sch_1):page85_i111:dq(48)" )
			)
			( pin "J1A2.264"
				( objectStatus "@baseboard_fab2_lib.baseboard_fab2(sch_1):page85_i111:dq(49)" )
			)
			( pin "J1A2.126"
				( objectStatus "@baseboard_fab2_lib.baseboard_fab2(sch_1):page85_i111:dq(50)" )
			)
			( pin "J1A2.271"
				( objectStatus "@baseboard_fab2_lib.baseboard_fab2(sch_1):page85_i111:dq(51)" )
			)
			( pin "J1A2.117"
				( objectStatus "@baseboard_fab2_lib.baseboard_fab2(sch_1):page85_i111:dq(52)" )
			)
			( pin "J1A2.262"
				( objectStatus "@baseboard_fab2_lib.baseboard_fab2(sch_1):page85_i111:dq(53)" )
			)
			( pin "J1A2.124"
				( objectStatus "@baseboard_fab2_lib.baseboard_fab2(sch_1):page85_i111:dq(54)" )
			)
			( pin "J1A2.269"
				( objectStatus "@baseboard_fab2_lib.baseboard_fab2(sch_1):page85_i111:dq(55)" )
			)
			( pin "J1A2.130"
				( objectStatus "@baseboard_fab2_lib.baseboard_fab2(sch_1):page85_i111:dq(56)" )
			)
			( pin "J1A2.275"
				( objectStatus "@baseboard_fab2_lib.baseboard_fab2(sch_1):page85_i111:dq(57)" )
			)
			( pin "J1A2.137"
				( objectStatus "@baseboard_fab2_lib.baseboard_fab2(sch_1):page85_i111:dq(58)" )
			)
			( pin "J1A2.282"
				( objectStatus "@baseboard_fab2_lib.baseboard_fab2(sch_1):page85_i111:dq(59)" )
			)
			( pin "J1A2.128"
				( objectStatus "@baseboard_fab2_lib.baseboard_fab2(sch_1):page85_i111:dq(60)" )
			)
			( pin "J1A2.273"
				( objectStatus "@baseboard_fab2_lib.baseboard_fab2(sch_1):page85_i111:dq(61)" )
			)
			( pin "J1A2.135"
				( objectStatus "@baseboard_fab2_lib.baseboard_fab2(sch_1):page85_i111:dq(62)" )
			)
			( pin "J1A2.280"
				( objectStatus "@baseboard_fab2_lib.baseboard_fab2(sch_1):page85_i111:dq(63)" )
			)
			( pin "J1A2.78"
				( objectStatus "@baseboard_fab2_lib.baseboard_fab2(sch_1):page85_i111:event_n" )
			)
			( pin "J1A2.87"
				( objectStatus "@baseboard_fab2_lib.baseboard_fab2(sch_1):page85_i111:odt(0)" )
			)
			( pin "J1A2.91"
				( objectStatus "@baseboard_fab2_lib.baseboard_fab2(sch_1):page85_i111:odt(1)" )
			)
			( pin "J1A2.222"
				( objectStatus "@baseboard_fab2_lib.baseboard_fab2(sch_1):page85_i111:par" )
			)
			( pin "J1A2.58"
				( objectStatus "@baseboard_fab2_lib.baseboard_fab2(sch_1):page85_i111:reset_n" )
			)
			( pin "J1A2.205"
				( objectStatus "@baseboard_fab2_lib.baseboard_fab2(sch_1):page85_i111:rfu(0)" )
			)
			( pin "J1A2.227"
				( objectStatus "@baseboard_fab2_lib.baseboard_fab2(sch_1):page85_i111:rfu(1)" )
			)
			( pin "J1A2.144"
				( objectStatus "@baseboard_fab2_lib.baseboard_fab2(sch_1):page85_i111:rfu(2)" )
			)
			( pin "J1A2.84"
				( objectStatus "@baseboard_fab2_lib.baseboard_fab2(sch_1):page85_i111:s0_n" )
			)
			( pin "J1A2.89"
				( objectStatus "@baseboard_fab2_lib.baseboard_fab2(sch_1):page85_i111:s1_n" )
			)
			( pin "J1A2.93"
				( objectStatus "@baseboard_fab2_lib.baseboard_fab2(sch_1):page85_i111:s2_n_c(0)" )
			)
			( pin "J1A2.237"
				( objectStatus "@baseboard_fab2_lib.baseboard_fab2(sch_1):page85_i111:s3_n_c(1)" )
			)
			( pin "J1A2.139"
				( objectStatus "@baseboard_fab2_lib.baseboard_fab2(sch_1):page85_i111:sa(0)" )
			)
			( pin "J1A2.140"
				( objectStatus "@baseboard_fab2_lib.baseboard_fab2(sch_1):page85_i111:sa(1)" )
			)
			( pin "J1A2.238"
				( objectStatus "@baseboard_fab2_lib.baseboard_fab2(sch_1):page85_i111:sa(2)" )
			)
			( pin "J1A2.230"
				( objectStatus "@baseboard_fab2_lib.baseboard_fab2(sch_1):page85_i111:save_n_nc" )
			)
			( pin "J1A2.141"
				( objectStatus "@baseboard_fab2_lib.baseboard_fab2(sch_1):page85_i111:scl" )
			)
			( pin "J1A2.285"
				( objectStatus "@baseboard_fab2_lib.baseboard_fab2(sch_1):page85_i111:sda" )
			)
			( pin "J1A2.284"
				( objectStatus "@baseboard_fab2_lib.baseboard_fab2(sch_1):page85_i111:vddspd" )
			)
			( pin "J1A2.146"
				( objectStatus "@baseboard_fab2_lib.baseboard_fab2(sch_1):page85_i111:vrefca" )
			)
			( pin "J1A2.145"
				( objectStatus "@baseboard_fab2_lib.baseboard_fab2(sch_1):page85_i172:\12v\(0)" )
			)
			( pin "J1A2.1"
				( objectStatus "@baseboard_fab2_lib.baseboard_fab2(sch_1):page85_i172:\12v\(1)" )
			)
			( pin "J1A2.236"
				( objectStatus "@baseboard_fab2_lib.baseboard_fab2(sch_1):page85_i172:vdd(0)" )
			)
			( pin "J1A2.233"
				( objectStatus "@baseboard_fab2_lib.baseboard_fab2(sch_1):page85_i172:vdd(1)" )
			)
			( pin "J1A2.231"
				( objectStatus "@baseboard_fab2_lib.baseboard_fab2(sch_1):page85_i172:vdd(2)" )
			)
			( pin "J1A2.229"
				( objectStatus "@baseboard_fab2_lib.baseboard_fab2(sch_1):page85_i172:vdd(3)" )
			)
			( pin "J1A2.226"
				( objectStatus "@baseboard_fab2_lib.baseboard_fab2(sch_1):page85_i172:vdd(4)" )
			)
			( pin "J1A2.223"
				( objectStatus "@baseboard_fab2_lib.baseboard_fab2(sch_1):page85_i172:vdd(5)" )
			)
			( pin "J1A2.220"
				( objectStatus "@baseboard_fab2_lib.baseboard_fab2(sch_1):page85_i172:vdd(6)" )
			)
			( pin "J1A2.217"
				( objectStatus "@baseboard_fab2_lib.baseboard_fab2(sch_1):page85_i172:vdd(7)" )
			)
			( pin "J1A2.215"
				( objectStatus "@baseboard_fab2_lib.baseboard_fab2(sch_1):page85_i172:vdd(8)" )
			)
			( pin "J1A2.212"
				( objectStatus "@baseboard_fab2_lib.baseboard_fab2(sch_1):page85_i172:vdd(9)" )
			)
			( pin "J1A2.209"
				( objectStatus "@baseboard_fab2_lib.baseboard_fab2(sch_1):page85_i172:vdd(10)" )
			)
			( pin "J1A2.206"
				( objectStatus "@baseboard_fab2_lib.baseboard_fab2(sch_1):page85_i172:vdd(11)" )
			)
			( pin "J1A2.204"
				( objectStatus "@baseboard_fab2_lib.baseboard_fab2(sch_1):page85_i172:vdd(12)" )
			)
			( pin "J1A2.92"
				( objectStatus "@baseboard_fab2_lib.baseboard_fab2(sch_1):page85_i172:vdd(13)" )
			)
			( pin "J1A2.90"
				( objectStatus "@baseboard_fab2_lib.baseboard_fab2(sch_1):page85_i172:vdd(14)" )
			)
			( pin "J1A2.88"
				( objectStatus "@baseboard_fab2_lib.baseboard_fab2(sch_1):page85_i172:vdd(15)" )
			)
			( pin "J1A2.85"
				( objectStatus "@baseboard_fab2_lib.baseboard_fab2(sch_1):page85_i172:vdd(16)" )
			)
			( pin "J1A2.83"
				( objectStatus "@baseboard_fab2_lib.baseboard_fab2(sch_1):page85_i172:vdd(17)" )
			)
			( pin "J1A2.80"
				( objectStatus "@baseboard_fab2_lib.baseboard_fab2(sch_1):page85_i172:vdd(18)" )
			)
			( pin "J1A2.76"
				( objectStatus "@baseboard_fab2_lib.baseboard_fab2(sch_1):page85_i172:vdd(19)" )
			)
			( pin "J1A2.73"
				( objectStatus "@baseboard_fab2_lib.baseboard_fab2(sch_1):page85_i172:vdd(20)" )
			)
			( pin "J1A2.70"
				( objectStatus "@baseboard_fab2_lib.baseboard_fab2(sch_1):page85_i172:vdd(21)" )
			)
			( pin "J1A2.67"
				( objectStatus "@baseboard_fab2_lib.baseboard_fab2(sch_1):page85_i172:vdd(22)" )
			)
			( pin "J1A2.64"
				( objectStatus "@baseboard_fab2_lib.baseboard_fab2(sch_1):page85_i172:vdd(23)" )
			)
			( pin "J1A2.61"
				( objectStatus "@baseboard_fab2_lib.baseboard_fab2(sch_1):page85_i172:vdd(24)" )
			)
			( pin "J1A2.59"
				( objectStatus "@baseboard_fab2_lib.baseboard_fab2(sch_1):page85_i172:vdd(25)" )
			)
			( pin "J1A2.287"
				( objectStatus "@baseboard_fab2_lib.baseboard_fab2(sch_1):page85_i172:vpp(0)" )
			)
			( pin "J1A2.286"
				( objectStatus "@baseboard_fab2_lib.baseboard_fab2(sch_1):page85_i172:vpp(1)" )
			)
			( pin "J1A2.288"
				( objectStatus "@baseboard_fab2_lib.baseboard_fab2(sch_1):page85_i172:vpp(2)" )
			)
			( pin "J1A2.143"
				( objectStatus "@baseboard_fab2_lib.baseboard_fab2(sch_1):page85_i172:vpp(3)" )
			)
			( pin "J1A2.142"
				( objectStatus "@baseboard_fab2_lib.baseboard_fab2(sch_1):page85_i172:vpp(4)" )
			)
			( pin "J1A2.221"
				( objectStatus "@baseboard_fab2_lib.baseboard_fab2(sch_1):page85_i172:vtt(0)" )
			)
			( pin "J1A2.77"
				( objectStatus "@baseboard_fab2_lib.baseboard_fab2(sch_1):page85_i172:vtt(1)" )
			)
			( pin "C9L7.1"
				( objectStatus "@baseboard_fab2_lib.baseboard_fab2(sch_1):page85_i181:a" )
			)
			( pin "C9L7.2"
				( objectStatus "@baseboard_fab2_lib.baseboard_fab2(sch_1):page85_i181:b" )
			)
			( pin "J9L2.79"
				( objectStatus "@baseboard_fab2_lib.baseboard_fab2(sch_1):page86_i12:a0" )
			)
			( pin "J9L2.72"
				( objectStatus "@baseboard_fab2_lib.baseboard_fab2(sch_1):page86_i12:a1" )
			)
			( pin "J9L2.216"
				( objectStatus "@baseboard_fab2_lib.baseboard_fab2(sch_1):page86_i12:a2" )
			)
			( pin "J9L2.71"
				( objectStatus "@baseboard_fab2_lib.baseboard_fab2(sch_1):page86_i12:a3" )
			)
			( pin "J9L2.214"
				( objectStatus "@baseboard_fab2_lib.baseboard_fab2(sch_1):page86_i12:a4" )
			)
			( pin "J9L2.213"
				( objectStatus "@baseboard_fab2_lib.baseboard_fab2(sch_1):page86_i12:a5" )
			)
			( pin "J9L2.69"
				( objectStatus "@baseboard_fab2_lib.baseboard_fab2(sch_1):page86_i12:a6" )
			)
			( pin "J9L2.211"
				( objectStatus "@baseboard_fab2_lib.baseboard_fab2(sch_1):page86_i12:a7" )
			)
			( pin "J9L2.68"
				( objectStatus "@baseboard_fab2_lib.baseboard_fab2(sch_1):page86_i12:a8" )
			)
			( pin "J9L2.66"
				( objectStatus "@baseboard_fab2_lib.baseboard_fab2(sch_1):page86_i12:a9" )
			)
			( pin "J9L2.225"
				( objectStatus "@baseboard_fab2_lib.baseboard_fab2(sch_1):page86_i12:a10" )
			)
			( pin "J9L2.210"
				( objectStatus "@baseboard_fab2_lib.baseboard_fab2(sch_1):page86_i12:a11" )
			)
			( pin "J9L2.65"
				( objectStatus "@baseboard_fab2_lib.baseboard_fab2(sch_1):page86_i12:a12" )
			)
			( pin "J9L2.232"
				( objectStatus "@baseboard_fab2_lib.baseboard_fab2(sch_1):page86_i12:a13" )
			)
			( pin "J9L2.228"
				( objectStatus "@baseboard_fab2_lib.baseboard_fab2(sch_1):page86_i12:a14_we_n" )
			)
			( pin "J9L2.86"
				( objectStatus "@baseboard_fab2_lib.baseboard_fab2(sch_1):page86_i12:a15_cas_n" )
			)
			( pin "J9L2.82"
				( objectStatus "@baseboard_fab2_lib.baseboard_fab2(sch_1):page86_i12:a16_ras_n" )
			)
			( pin "J9L2.234"
				( objectStatus "@baseboard_fab2_lib.baseboard_fab2(sch_1):page86_i12:a17" )
			)
			( pin "J9L2.62"
				( objectStatus "@baseboard_fab2_lib.baseboard_fab2(sch_1):page86_i12:act_n" )
			)
			( pin "J9L2.208"
				( objectStatus "@baseboard_fab2_lib.baseboard_fab2(sch_1):page86_i12:alert_n" )
			)
			( pin "J9L2.81"
				( objectStatus "@baseboard_fab2_lib.baseboard_fab2(sch_1):page86_i12:ba(0)" )
			)
			( pin "J9L2.224"
				( objectStatus "@baseboard_fab2_lib.baseboard_fab2(sch_1):page86_i12:ba(1)" )
			)
			( pin "J9L2.63"
				( objectStatus "@baseboard_fab2_lib.baseboard_fab2(sch_1):page86_i12:bg(0)" )
			)
			( pin "J9L2.207"
				( objectStatus "@baseboard_fab2_lib.baseboard_fab2(sch_1):page86_i12:bg(1)" )
			)
			( pin "J9L2.235"
				( objectStatus "@baseboard_fab2_lib.baseboard_fab2(sch_1):page86_i12:c(2)" )
			)
			( pin "J9L2.49"
				( objectStatus "@baseboard_fab2_lib.baseboard_fab2(sch_1):page86_i12:cb(0)" )
			)
			( pin "J9L2.194"
				( objectStatus "@baseboard_fab2_lib.baseboard_fab2(sch_1):page86_i12:cb(1)" )
			)
			( pin "J9L2.56"
				( objectStatus "@baseboard_fab2_lib.baseboard_fab2(sch_1):page86_i12:cb(2)" )
			)
			( pin "J9L2.201"
				( objectStatus "@baseboard_fab2_lib.baseboard_fab2(sch_1):page86_i12:cb(3)" )
			)
			( pin "J9L2.47"
				( objectStatus "@baseboard_fab2_lib.baseboard_fab2(sch_1):page86_i12:cb(4)" )
			)
			( pin "J9L2.192"
				( objectStatus "@baseboard_fab2_lib.baseboard_fab2(sch_1):page86_i12:cb(5)" )
			)
			( pin "J9L2.54"
				( objectStatus "@baseboard_fab2_lib.baseboard_fab2(sch_1):page86_i12:cb(6)" )
			)
			( pin "J9L2.199"
				( objectStatus "@baseboard_fab2_lib.baseboard_fab2(sch_1):page86_i12:cb(7)" )
			)
			( pin "J9L2.75"
				( objectStatus "@baseboard_fab2_lib.baseboard_fab2(sch_1):page86_i12:ck0n" )
			)
			( pin "J9L2.74"
				( objectStatus "@baseboard_fab2_lib.baseboard_fab2(sch_1):page86_i12:ck0p" )
			)
			( pin "J9L2.219"
				( objectStatus "@baseboard_fab2_lib.baseboard_fab2(sch_1):page86_i12:ck1n" )
			)
			( pin "J9L2.218"
				( objectStatus "@baseboard_fab2_lib.baseboard_fab2(sch_1):page86_i12:ck1p" )
			)
			( pin "J9L2.60"
				( objectStatus "@baseboard_fab2_lib.baseboard_fab2(sch_1):page86_i12:cke(0)" )
			)
			( pin "J9L2.203"
				( objectStatus "@baseboard_fab2_lib.baseboard_fab2(sch_1):page86_i12:cke(1)" )
			)
			( pin "J9L2.5"
				( objectStatus "@baseboard_fab2_lib.baseboard_fab2(sch_1):page86_i12:dq(0)" )
			)
			( pin "J9L2.150"
				( objectStatus "@baseboard_fab2_lib.baseboard_fab2(sch_1):page86_i12:dq(1)" )
			)
			( pin "J9L2.12"
				( objectStatus "@baseboard_fab2_lib.baseboard_fab2(sch_1):page86_i12:dq(2)" )
			)
			( pin "J9L2.157"
				( objectStatus "@baseboard_fab2_lib.baseboard_fab2(sch_1):page86_i12:dq(3)" )
			)
			( pin "J9L2.3"
				( objectStatus "@baseboard_fab2_lib.baseboard_fab2(sch_1):page86_i12:dq(4)" )
			)
			( pin "J9L2.148"
				( objectStatus "@baseboard_fab2_lib.baseboard_fab2(sch_1):page86_i12:dq(5)" )
			)
			( pin "J9L2.10"
				( objectStatus "@baseboard_fab2_lib.baseboard_fab2(sch_1):page86_i12:dq(6)" )
			)
			( pin "J9L2.155"
				( objectStatus "@baseboard_fab2_lib.baseboard_fab2(sch_1):page86_i12:dq(7)" )
			)
			( pin "J9L2.16"
				( objectStatus "@baseboard_fab2_lib.baseboard_fab2(sch_1):page86_i12:dq(8)" )
			)
			( pin "J9L2.161"
				( objectStatus "@baseboard_fab2_lib.baseboard_fab2(sch_1):page86_i12:dq(9)" )
			)
			( pin "J9L2.23"
				( objectStatus "@baseboard_fab2_lib.baseboard_fab2(sch_1):page86_i12:dq(10)" )
			)
			( pin "J9L2.168"
				( objectStatus "@baseboard_fab2_lib.baseboard_fab2(sch_1):page86_i12:dq(11)" )
			)
			( pin "J9L2.14"
				( objectStatus "@baseboard_fab2_lib.baseboard_fab2(sch_1):page86_i12:dq(12)" )
			)
			( pin "J9L2.159"
				( objectStatus "@baseboard_fab2_lib.baseboard_fab2(sch_1):page86_i12:dq(13)" )
			)
			( pin "J9L2.21"
				( objectStatus "@baseboard_fab2_lib.baseboard_fab2(sch_1):page86_i12:dq(14)" )
			)
			( pin "J9L2.166"
				( objectStatus "@baseboard_fab2_lib.baseboard_fab2(sch_1):page86_i12:dq(15)" )
			)
			( pin "J9L2.27"
				( objectStatus "@baseboard_fab2_lib.baseboard_fab2(sch_1):page86_i12:dq(16)" )
			)
			( pin "J9L2.172"
				( objectStatus "@baseboard_fab2_lib.baseboard_fab2(sch_1):page86_i12:dq(17)" )
			)
			( pin "J9L2.34"
				( objectStatus "@baseboard_fab2_lib.baseboard_fab2(sch_1):page86_i12:dq(18)" )
			)
			( pin "J9L2.179"
				( objectStatus "@baseboard_fab2_lib.baseboard_fab2(sch_1):page86_i12:dq(19)" )
			)
			( pin "J9L2.25"
				( objectStatus "@baseboard_fab2_lib.baseboard_fab2(sch_1):page86_i12:dq(20)" )
			)
			( pin "J9L2.170"
				( objectStatus "@baseboard_fab2_lib.baseboard_fab2(sch_1):page86_i12:dq(21)" )
			)
			( pin "J9L2.32"
				( objectStatus "@baseboard_fab2_lib.baseboard_fab2(sch_1):page86_i12:dq(22)" )
			)
			( pin "J9L2.177"
				( objectStatus "@baseboard_fab2_lib.baseboard_fab2(sch_1):page86_i12:dq(23)" )
			)
			( pin "J9L2.38"
				( objectStatus "@baseboard_fab2_lib.baseboard_fab2(sch_1):page86_i12:dq(24)" )
			)
			( pin "J9L2.183"
				( objectStatus "@baseboard_fab2_lib.baseboard_fab2(sch_1):page86_i12:dq(25)" )
			)
			( pin "J9L2.45"
				( objectStatus "@baseboard_fab2_lib.baseboard_fab2(sch_1):page86_i12:dq(26)" )
			)
			( pin "J9L2.190"
				( objectStatus "@baseboard_fab2_lib.baseboard_fab2(sch_1):page86_i12:dq(27)" )
			)
			( pin "J9L2.36"
				( objectStatus "@baseboard_fab2_lib.baseboard_fab2(sch_1):page86_i12:dq(28)" )
			)
			( pin "J9L2.181"
				( objectStatus "@baseboard_fab2_lib.baseboard_fab2(sch_1):page86_i12:dq(29)" )
			)
			( pin "J9L2.43"
				( objectStatus "@baseboard_fab2_lib.baseboard_fab2(sch_1):page86_i12:dq(30)" )
			)
			( pin "J9L2.188"
				( objectStatus "@baseboard_fab2_lib.baseboard_fab2(sch_1):page86_i12:dq(31)" )
			)
			( pin "J9L2.97"
				( objectStatus "@baseboard_fab2_lib.baseboard_fab2(sch_1):page86_i12:dq(32)" )
			)
			( pin "J9L2.242"
				( objectStatus "@baseboard_fab2_lib.baseboard_fab2(sch_1):page86_i12:dq(33)" )
			)
			( pin "J9L2.104"
				( objectStatus "@baseboard_fab2_lib.baseboard_fab2(sch_1):page86_i12:dq(34)" )
			)
			( pin "J9L2.249"
				( objectStatus "@baseboard_fab2_lib.baseboard_fab2(sch_1):page86_i12:dq(35)" )
			)
			( pin "J9L2.95"
				( objectStatus "@baseboard_fab2_lib.baseboard_fab2(sch_1):page86_i12:dq(36)" )
			)
			( pin "J9L2.240"
				( objectStatus "@baseboard_fab2_lib.baseboard_fab2(sch_1):page86_i12:dq(37)" )
			)
			( pin "J9L2.102"
				( objectStatus "@baseboard_fab2_lib.baseboard_fab2(sch_1):page86_i12:dq(38)" )
			)
			( pin "J9L2.247"
				( objectStatus "@baseboard_fab2_lib.baseboard_fab2(sch_1):page86_i12:dq(39)" )
			)
			( pin "J9L2.108"
				( objectStatus "@baseboard_fab2_lib.baseboard_fab2(sch_1):page86_i12:dq(40)" )
			)
			( pin "J9L2.253"
				( objectStatus "@baseboard_fab2_lib.baseboard_fab2(sch_1):page86_i12:dq(41)" )
			)
			( pin "J9L2.115"
				( objectStatus "@baseboard_fab2_lib.baseboard_fab2(sch_1):page86_i12:dq(42)" )
			)
			( pin "J9L2.260"
				( objectStatus "@baseboard_fab2_lib.baseboard_fab2(sch_1):page86_i12:dq(43)" )
			)
			( pin "J9L2.106"
				( objectStatus "@baseboard_fab2_lib.baseboard_fab2(sch_1):page86_i12:dq(44)" )
			)
			( pin "J9L2.251"
				( objectStatus "@baseboard_fab2_lib.baseboard_fab2(sch_1):page86_i12:dq(45)" )
			)
			( pin "J9L2.113"
				( objectStatus "@baseboard_fab2_lib.baseboard_fab2(sch_1):page86_i12:dq(46)" )
			)
			( pin "J9L2.258"
				( objectStatus "@baseboard_fab2_lib.baseboard_fab2(sch_1):page86_i12:dq(47)" )
			)
			( pin "J9L2.119"
				( objectStatus "@baseboard_fab2_lib.baseboard_fab2(sch_1):page86_i12:dq(48)" )
			)
			( pin "J9L2.264"
				( objectStatus "@baseboard_fab2_lib.baseboard_fab2(sch_1):page86_i12:dq(49)" )
			)
			( pin "J9L2.126"
				( objectStatus "@baseboard_fab2_lib.baseboard_fab2(sch_1):page86_i12:dq(50)" )
			)
			( pin "J9L2.271"
				( objectStatus "@baseboard_fab2_lib.baseboard_fab2(sch_1):page86_i12:dq(51)" )
			)
			( pin "J9L2.117"
				( objectStatus "@baseboard_fab2_lib.baseboard_fab2(sch_1):page86_i12:dq(52)" )
			)
			( pin "J9L2.262"
				( objectStatus "@baseboard_fab2_lib.baseboard_fab2(sch_1):page86_i12:dq(53)" )
			)
			( pin "J9L2.124"
				( objectStatus "@baseboard_fab2_lib.baseboard_fab2(sch_1):page86_i12:dq(54)" )
			)
			( pin "J9L2.269"
				( objectStatus "@baseboard_fab2_lib.baseboard_fab2(sch_1):page86_i12:dq(55)" )
			)
			( pin "J9L2.130"
				( objectStatus "@baseboard_fab2_lib.baseboard_fab2(sch_1):page86_i12:dq(56)" )
			)
			( pin "J9L2.275"
				( objectStatus "@baseboard_fab2_lib.baseboard_fab2(sch_1):page86_i12:dq(57)" )
			)
			( pin "J9L2.137"
				( objectStatus "@baseboard_fab2_lib.baseboard_fab2(sch_1):page86_i12:dq(58)" )
			)
			( pin "J9L2.282"
				( objectStatus "@baseboard_fab2_lib.baseboard_fab2(sch_1):page86_i12:dq(59)" )
			)
			( pin "J9L2.128"
				( objectStatus "@baseboard_fab2_lib.baseboard_fab2(sch_1):page86_i12:dq(60)" )
			)
			( pin "J9L2.273"
				( objectStatus "@baseboard_fab2_lib.baseboard_fab2(sch_1):page86_i12:dq(61)" )
			)
			( pin "J9L2.135"
				( objectStatus "@baseboard_fab2_lib.baseboard_fab2(sch_1):page86_i12:dq(62)" )
			)
			( pin "J9L2.280"
				( objectStatus "@baseboard_fab2_lib.baseboard_fab2(sch_1):page86_i12:dq(63)" )
			)
			( pin "J9L2.78"
				( objectStatus "@baseboard_fab2_lib.baseboard_fab2(sch_1):page86_i12:event_n" )
			)
			( pin "J9L2.87"
				( objectStatus "@baseboard_fab2_lib.baseboard_fab2(sch_1):page86_i12:odt(0)" )
			)
			( pin "J9L2.91"
				( objectStatus "@baseboard_fab2_lib.baseboard_fab2(sch_1):page86_i12:odt(1)" )
			)
			( pin "J9L2.222"
				( objectStatus "@baseboard_fab2_lib.baseboard_fab2(sch_1):page86_i12:par" )
			)
			( pin "J9L2.58"
				( objectStatus "@baseboard_fab2_lib.baseboard_fab2(sch_1):page86_i12:reset_n" )
			)
			( pin "J9L2.205"
				( objectStatus "@baseboard_fab2_lib.baseboard_fab2(sch_1):page86_i12:rfu(0)" )
			)
			( pin "J9L2.227"
				( objectStatus "@baseboard_fab2_lib.baseboard_fab2(sch_1):page86_i12:rfu(1)" )
			)
			( pin "J9L2.144"
				( objectStatus "@baseboard_fab2_lib.baseboard_fab2(sch_1):page86_i12:rfu(2)" )
			)
			( pin "J9L2.84"
				( objectStatus "@baseboard_fab2_lib.baseboard_fab2(sch_1):page86_i12:s0_n" )
			)
			( pin "J9L2.89"
				( objectStatus "@baseboard_fab2_lib.baseboard_fab2(sch_1):page86_i12:s1_n" )
			)
			( pin "J9L2.93"
				( objectStatus "@baseboard_fab2_lib.baseboard_fab2(sch_1):page86_i12:s2_n_c(0)" )
			)
			( pin "J9L2.237"
				( objectStatus "@baseboard_fab2_lib.baseboard_fab2(sch_1):page86_i12:s3_n_c(1)" )
			)
			( pin "J9L2.139"
				( objectStatus "@baseboard_fab2_lib.baseboard_fab2(sch_1):page86_i12:sa(0)" )
			)
			( pin "J9L2.140"
				( objectStatus "@baseboard_fab2_lib.baseboard_fab2(sch_1):page86_i12:sa(1)" )
			)
			( pin "J9L2.238"
				( objectStatus "@baseboard_fab2_lib.baseboard_fab2(sch_1):page86_i12:sa(2)" )
			)
			( pin "J9L2.230"
				( objectStatus "@baseboard_fab2_lib.baseboard_fab2(sch_1):page86_i12:save_n_nc" )
			)
			( pin "J9L2.141"
				( objectStatus "@baseboard_fab2_lib.baseboard_fab2(sch_1):page86_i12:scl" )
			)
			( pin "J9L2.285"
				( objectStatus "@baseboard_fab2_lib.baseboard_fab2(sch_1):page86_i12:sda" )
			)
			( pin "J9L2.284"
				( objectStatus "@baseboard_fab2_lib.baseboard_fab2(sch_1):page86_i12:vddspd" )
			)
			( pin "J9L2.146"
				( objectStatus "@baseboard_fab2_lib.baseboard_fab2(sch_1):page86_i12:vrefca" )
			)
			( pin "J9L2.145"
				( objectStatus "@baseboard_fab2_lib.baseboard_fab2(sch_1):page86_i55:\12v\(0)" )
			)
			( pin "J9L2.1"
				( objectStatus "@baseboard_fab2_lib.baseboard_fab2(sch_1):page86_i55:\12v\(1)" )
			)
			( pin "J9L2.236"
				( objectStatus "@baseboard_fab2_lib.baseboard_fab2(sch_1):page86_i55:vdd(0)" )
			)
			( pin "J9L2.233"
				( objectStatus "@baseboard_fab2_lib.baseboard_fab2(sch_1):page86_i55:vdd(1)" )
			)
			( pin "J9L2.231"
				( objectStatus "@baseboard_fab2_lib.baseboard_fab2(sch_1):page86_i55:vdd(2)" )
			)
			( pin "J9L2.229"
				( objectStatus "@baseboard_fab2_lib.baseboard_fab2(sch_1):page86_i55:vdd(3)" )
			)
			( pin "J9L2.226"
				( objectStatus "@baseboard_fab2_lib.baseboard_fab2(sch_1):page86_i55:vdd(4)" )
			)
			( pin "J9L2.223"
				( objectStatus "@baseboard_fab2_lib.baseboard_fab2(sch_1):page86_i55:vdd(5)" )
			)
			( pin "J9L2.220"
				( objectStatus "@baseboard_fab2_lib.baseboard_fab2(sch_1):page86_i55:vdd(6)" )
			)
			( pin "J9L2.217"
				( objectStatus "@baseboard_fab2_lib.baseboard_fab2(sch_1):page86_i55:vdd(7)" )
			)
			( pin "J9L2.215"
				( objectStatus "@baseboard_fab2_lib.baseboard_fab2(sch_1):page86_i55:vdd(8)" )
			)
			( pin "J9L2.212"
				( objectStatus "@baseboard_fab2_lib.baseboard_fab2(sch_1):page86_i55:vdd(9)" )
			)
			( pin "J9L2.209"
				( objectStatus "@baseboard_fab2_lib.baseboard_fab2(sch_1):page86_i55:vdd(10)" )
			)
			( pin "J9L2.206"
				( objectStatus "@baseboard_fab2_lib.baseboard_fab2(sch_1):page86_i55:vdd(11)" )
			)
			( pin "J9L2.204"
				( objectStatus "@baseboard_fab2_lib.baseboard_fab2(sch_1):page86_i55:vdd(12)" )
			)
			( pin "J9L2.92"
				( objectStatus "@baseboard_fab2_lib.baseboard_fab2(sch_1):page86_i55:vdd(13)" )
			)
			( pin "J9L2.90"
				( objectStatus "@baseboard_fab2_lib.baseboard_fab2(sch_1):page86_i55:vdd(14)" )
			)
			( pin "J9L2.88"
				( objectStatus "@baseboard_fab2_lib.baseboard_fab2(sch_1):page86_i55:vdd(15)" )
			)
			( pin "J9L2.85"
				( objectStatus "@baseboard_fab2_lib.baseboard_fab2(sch_1):page86_i55:vdd(16)" )
			)
			( pin "J9L2.83"
				( objectStatus "@baseboard_fab2_lib.baseboard_fab2(sch_1):page86_i55:vdd(17)" )
			)
			( pin "J9L2.80"
				( objectStatus "@baseboard_fab2_lib.baseboard_fab2(sch_1):page86_i55:vdd(18)" )
			)
			( pin "J9L2.76"
				( objectStatus "@baseboard_fab2_lib.baseboard_fab2(sch_1):page86_i55:vdd(19)" )
			)
			( pin "J9L2.73"
				( objectStatus "@baseboard_fab2_lib.baseboard_fab2(sch_1):page86_i55:vdd(20)" )
			)
			( pin "J9L2.70"
				( objectStatus "@baseboard_fab2_lib.baseboard_fab2(sch_1):page86_i55:vdd(21)" )
			)
			( pin "J9L2.67"
				( objectStatus "@baseboard_fab2_lib.baseboard_fab2(sch_1):page86_i55:vdd(22)" )
			)
			( pin "J9L2.64"
				( objectStatus "@baseboard_fab2_lib.baseboard_fab2(sch_1):page86_i55:vdd(23)" )
			)
			( pin "J9L2.61"
				( objectStatus "@baseboard_fab2_lib.baseboard_fab2(sch_1):page86_i55:vdd(24)" )
			)
			( pin "J9L2.59"
				( objectStatus "@baseboard_fab2_lib.baseboard_fab2(sch_1):page86_i55:vdd(25)" )
			)
			( pin "J9L2.287"
				( objectStatus "@baseboard_fab2_lib.baseboard_fab2(sch_1):page86_i55:vpp(0)" )
			)
			( pin "J9L2.286"
				( objectStatus "@baseboard_fab2_lib.baseboard_fab2(sch_1):page86_i55:vpp(1)" )
			)
			( pin "J9L2.288"
				( objectStatus "@baseboard_fab2_lib.baseboard_fab2(sch_1):page86_i55:vpp(2)" )
			)
			( pin "J9L2.143"
				( objectStatus "@baseboard_fab2_lib.baseboard_fab2(sch_1):page86_i55:vpp(3)" )
			)
			( pin "J9L2.142"
				( objectStatus "@baseboard_fab2_lib.baseboard_fab2(sch_1):page86_i55:vpp(4)" )
			)
			( pin "J9L2.221"
				( objectStatus "@baseboard_fab2_lib.baseboard_fab2(sch_1):page86_i55:vtt(0)" )
			)
			( pin "J9L2.77"
				( objectStatus "@baseboard_fab2_lib.baseboard_fab2(sch_1):page86_i55:vtt(1)" )
			)
			( pin "J9L2.152"
				( objectStatus "@baseboard_fab2_lib.baseboard_fab2(sch_1):page86_i100:dqs0n" )
			)
			( pin "J9L2.153"
				( objectStatus "@baseboard_fab2_lib.baseboard_fab2(sch_1):page86_i100:dqs0p" )
			)
			( pin "J9L2.163"
				( objectStatus "@baseboard_fab2_lib.baseboard_fab2(sch_1):page86_i100:dqs1n" )
			)
			( pin "J9L2.164"
				( objectStatus "@baseboard_fab2_lib.baseboard_fab2(sch_1):page86_i100:dqs1p" )
			)
			( pin "J9L2.174"
				( objectStatus "@baseboard_fab2_lib.baseboard_fab2(sch_1):page86_i100:dqs2n" )
			)
			( pin "J9L2.175"
				( objectStatus "@baseboard_fab2_lib.baseboard_fab2(sch_1):page86_i100:dqs2p" )
			)
			( pin "J9L2.185"
				( objectStatus "@baseboard_fab2_lib.baseboard_fab2(sch_1):page86_i100:dqs3n" )
			)
			( pin "J9L2.186"
				( objectStatus "@baseboard_fab2_lib.baseboard_fab2(sch_1):page86_i100:dqs3p" )
			)
			( pin "J9L2.244"
				( objectStatus "@baseboard_fab2_lib.baseboard_fab2(sch_1):page86_i100:dqs4n" )
			)
			( pin "J9L2.245"
				( objectStatus "@baseboard_fab2_lib.baseboard_fab2(sch_1):page86_i100:dqs4p" )
			)
			( pin "J9L2.255"
				( objectStatus "@baseboard_fab2_lib.baseboard_fab2(sch_1):page86_i100:dqs5n" )
			)
			( pin "J9L2.256"
				( objectStatus "@baseboard_fab2_lib.baseboard_fab2(sch_1):page86_i100:dqs5p" )
			)
			( pin "J9L2.266"
				( objectStatus "@baseboard_fab2_lib.baseboard_fab2(sch_1):page86_i100:dqs6n" )
			)
			( pin "J9L2.267"
				( objectStatus "@baseboard_fab2_lib.baseboard_fab2(sch_1):page86_i100:dqs6p" )
			)
			( pin "J9L2.277"
				( objectStatus "@baseboard_fab2_lib.baseboard_fab2(sch_1):page86_i100:dqs7n" )
			)
			( pin "J9L2.278"
				( objectStatus "@baseboard_fab2_lib.baseboard_fab2(sch_1):page86_i100:dqs7p" )
			)
			( pin "J9L2.196"
				( objectStatus "@baseboard_fab2_lib.baseboard_fab2(sch_1):page86_i100:dqs8n" )
			)
			( pin "J9L2.197"
				( objectStatus "@baseboard_fab2_lib.baseboard_fab2(sch_1):page86_i100:dqs8p" )
			)
			( pin "J9L2.8"
				( objectStatus "@baseboard_fab2_lib.baseboard_fab2(sch_1):page86_i100:dqs9n" )
			)
			( pin "J9L2.7"
				( objectStatus "@baseboard_fab2_lib.baseboard_fab2(sch_1):page86_i100:dqs9p" )
			)
			( pin "J9L2.19"
				( objectStatus "@baseboard_fab2_lib.baseboard_fab2(sch_1):page86_i100:dqs10n" )
			)
			( pin "J9L2.18"
				( objectStatus "@baseboard_fab2_lib.baseboard_fab2(sch_1):page86_i100:dqs10p" )
			)
			( pin "J9L2.30"
				( objectStatus "@baseboard_fab2_lib.baseboard_fab2(sch_1):page86_i100:dqs11n" )
			)
			( pin "J9L2.29"
				( objectStatus "@baseboard_fab2_lib.baseboard_fab2(sch_1):page86_i100:dqs11p" )
			)
			( pin "J9L2.41"
				( objectStatus "@baseboard_fab2_lib.baseboard_fab2(sch_1):page86_i100:dqs12n" )
			)
			( pin "J9L2.40"
				( objectStatus "@baseboard_fab2_lib.baseboard_fab2(sch_1):page86_i100:dqs12p" )
			)
			( pin "J9L2.100"
				( objectStatus "@baseboard_fab2_lib.baseboard_fab2(sch_1):page86_i100:dqs13n" )
			)
			( pin "J9L2.99"
				( objectStatus "@baseboard_fab2_lib.baseboard_fab2(sch_1):page86_i100:dqs13p" )
			)
			( pin "J9L2.111"
				( objectStatus "@baseboard_fab2_lib.baseboard_fab2(sch_1):page86_i100:dqs14n" )
			)
			( pin "J9L2.110"
				( objectStatus "@baseboard_fab2_lib.baseboard_fab2(sch_1):page86_i100:dqs14p" )
			)
			( pin "J9L2.122"
				( objectStatus "@baseboard_fab2_lib.baseboard_fab2(sch_1):page86_i100:dqs15n" )
			)
			( pin "J9L2.121"
				( objectStatus "@baseboard_fab2_lib.baseboard_fab2(sch_1):page86_i100:dqs15p" )
			)
			( pin "J9L2.133"
				( objectStatus "@baseboard_fab2_lib.baseboard_fab2(sch_1):page86_i100:dqs16n" )
			)
			( pin "J9L2.132"
				( objectStatus "@baseboard_fab2_lib.baseboard_fab2(sch_1):page86_i100:dqs16p" )
			)
			( pin "J9L2.52"
				( objectStatus "@baseboard_fab2_lib.baseboard_fab2(sch_1):page86_i100:dqs17n" )
			)
			( pin "J9L2.51"
				( objectStatus "@baseboard_fab2_lib.baseboard_fab2(sch_1):page86_i100:dqs17p" )
			)
			( pin "J9L2.283"
				( objectStatus "@baseboard_fab2_lib.baseboard_fab2(sch_1):page86_i138:vss(0)" )
			)
			( pin "J9L2.281"
				( objectStatus "@baseboard_fab2_lib.baseboard_fab2(sch_1):page86_i138:vss(1)" )
			)
			( pin "J9L2.279"
				( objectStatus "@baseboard_fab2_lib.baseboard_fab2(sch_1):page86_i138:vss(2)" )
			)
			( pin "J9L2.276"
				( objectStatus "@baseboard_fab2_lib.baseboard_fab2(sch_1):page86_i138:vss(3)" )
			)
			( pin "J9L2.274"
				( objectStatus "@baseboard_fab2_lib.baseboard_fab2(sch_1):page86_i138:vss(4)" )
			)
			( pin "J9L2.272"
				( objectStatus "@baseboard_fab2_lib.baseboard_fab2(sch_1):page86_i138:vss(5)" )
			)
			( pin "J9L2.270"
				( objectStatus "@baseboard_fab2_lib.baseboard_fab2(sch_1):page86_i138:vss(6)" )
			)
			( pin "J9L2.268"
				( objectStatus "@baseboard_fab2_lib.baseboard_fab2(sch_1):page86_i138:vss(7)" )
			)
			( pin "J9L2.265"
				( objectStatus "@baseboard_fab2_lib.baseboard_fab2(sch_1):page86_i138:vss(8)" )
			)
			( pin "J9L2.263"
				( objectStatus "@baseboard_fab2_lib.baseboard_fab2(sch_1):page86_i138:vss(9)" )
			)
			( pin "J9L2.261"
				( objectStatus "@baseboard_fab2_lib.baseboard_fab2(sch_1):page86_i138:vss(10)" )
			)
			( pin "J9L2.259"
				( objectStatus "@baseboard_fab2_lib.baseboard_fab2(sch_1):page86_i138:vss(11)" )
			)
			( pin "J9L2.257"
				( objectStatus "@baseboard_fab2_lib.baseboard_fab2(sch_1):page86_i138:vss(12)" )
			)
			( pin "J9L2.254"
				( objectStatus "@baseboard_fab2_lib.baseboard_fab2(sch_1):page86_i138:vss(13)" )
			)
			( pin "J9L2.252"
				( objectStatus "@baseboard_fab2_lib.baseboard_fab2(sch_1):page86_i138:vss(14)" )
			)
			( pin "J9L2.250"
				( objectStatus "@baseboard_fab2_lib.baseboard_fab2(sch_1):page86_i138:vss(15)" )
			)
			( pin "J9L2.248"
				( objectStatus "@baseboard_fab2_lib.baseboard_fab2(sch_1):page86_i138:vss(16)" )
			)
			( pin "J9L2.246"
				( objectStatus "@baseboard_fab2_lib.baseboard_fab2(sch_1):page86_i138:vss(17)" )
			)
			( pin "J9L2.243"
				( objectStatus "@baseboard_fab2_lib.baseboard_fab2(sch_1):page86_i138:vss(18)" )
			)
			( pin "J9L2.241"
				( objectStatus "@baseboard_fab2_lib.baseboard_fab2(sch_1):page86_i138:vss(19)" )
			)
			( pin "J9L2.239"
				( objectStatus "@baseboard_fab2_lib.baseboard_fab2(sch_1):page86_i138:vss(20)" )
			)
			( pin "J9L2.202"
				( objectStatus "@baseboard_fab2_lib.baseboard_fab2(sch_1):page86_i138:vss(21)" )
			)
			( pin "J9L2.200"
				( objectStatus "@baseboard_fab2_lib.baseboard_fab2(sch_1):page86_i138:vss(22)" )
			)
			( pin "J9L2.198"
				( objectStatus "@baseboard_fab2_lib.baseboard_fab2(sch_1):page86_i138:vss(23)" )
			)
			( pin "J9L2.195"
				( objectStatus "@baseboard_fab2_lib.baseboard_fab2(sch_1):page86_i138:vss(24)" )
			)
			( pin "J9L2.193"
				( objectStatus "@baseboard_fab2_lib.baseboard_fab2(sch_1):page86_i138:vss(25)" )
			)
			( pin "J9L2.191"
				( objectStatus "@baseboard_fab2_lib.baseboard_fab2(sch_1):page86_i138:vss(26)" )
			)
			( pin "J9L2.189"
				( objectStatus "@baseboard_fab2_lib.baseboard_fab2(sch_1):page86_i138:vss(27)" )
			)
			( pin "J9L2.187"
				( objectStatus "@baseboard_fab2_lib.baseboard_fab2(sch_1):page86_i138:vss(28)" )
			)
			( pin "J9L2.184"
				( objectStatus "@baseboard_fab2_lib.baseboard_fab2(sch_1):page86_i138:vss(29)" )
			)
			( pin "J9L2.182"
				( objectStatus "@baseboard_fab2_lib.baseboard_fab2(sch_1):page86_i138:vss(30)" )
			)
			( pin "J9L2.180"
				( objectStatus "@baseboard_fab2_lib.baseboard_fab2(sch_1):page86_i138:vss(31)" )
			)
			( pin "J9L2.178"
				( objectStatus "@baseboard_fab2_lib.baseboard_fab2(sch_1):page86_i138:vss(32)" )
			)
			( pin "J9L2.176"
				( objectStatus "@baseboard_fab2_lib.baseboard_fab2(sch_1):page86_i138:vss(33)" )
			)
			( pin "J9L2.173"
				( objectStatus "@baseboard_fab2_lib.baseboard_fab2(sch_1):page86_i138:vss(34)" )
			)
			( pin "J9L2.171"
				( objectStatus "@baseboard_fab2_lib.baseboard_fab2(sch_1):page86_i138:vss(35)" )
			)
			( pin "J9L2.169"
				( objectStatus "@baseboard_fab2_lib.baseboard_fab2(sch_1):page86_i138:vss(36)" )
			)
			( pin "J9L2.167"
				( objectStatus "@baseboard_fab2_lib.baseboard_fab2(sch_1):page86_i138:vss(37)" )
			)
			( pin "J9L2.165"
				( objectStatus "@baseboard_fab2_lib.baseboard_fab2(sch_1):page86_i138:vss(38)" )
			)
			( pin "J9L2.162"
				( objectStatus "@baseboard_fab2_lib.baseboard_fab2(sch_1):page86_i138:vss(39)" )
			)
			( pin "J9L2.160"
				( objectStatus "@baseboard_fab2_lib.baseboard_fab2(sch_1):page86_i138:vss(40)" )
			)
			( pin "J9L2.158"
				( objectStatus "@baseboard_fab2_lib.baseboard_fab2(sch_1):page86_i138:vss(41)" )
			)
			( pin "J9L2.156"
				( objectStatus "@baseboard_fab2_lib.baseboard_fab2(sch_1):page86_i138:vss(42)" )
			)
			( pin "J9L2.154"
				( objectStatus "@baseboard_fab2_lib.baseboard_fab2(sch_1):page86_i138:vss(43)" )
			)
			( pin "J9L2.151"
				( objectStatus "@baseboard_fab2_lib.baseboard_fab2(sch_1):page86_i138:vss(44)" )
			)
			( pin "J9L2.149"
				( objectStatus "@baseboard_fab2_lib.baseboard_fab2(sch_1):page86_i138:vss(45)" )
			)
			( pin "J9L2.147"
				( objectStatus "@baseboard_fab2_lib.baseboard_fab2(sch_1):page86_i138:vss(46)" )
			)
			( pin "J9L2.138"
				( objectStatus "@baseboard_fab2_lib.baseboard_fab2(sch_1):page86_i138:vss(47)" )
			)
			( pin "J9L2.136"
				( objectStatus "@baseboard_fab2_lib.baseboard_fab2(sch_1):page86_i138:vss(48)" )
			)
			( pin "J9L2.134"
				( objectStatus "@baseboard_fab2_lib.baseboard_fab2(sch_1):page86_i138:vss(49)" )
			)
			( pin "J9L2.131"
				( objectStatus "@baseboard_fab2_lib.baseboard_fab2(sch_1):page86_i138:vss(50)" )
			)
			( pin "J9L2.129"
				( objectStatus "@baseboard_fab2_lib.baseboard_fab2(sch_1):page86_i138:vss(51)" )
			)
			( pin "J9L2.127"
				( objectStatus "@baseboard_fab2_lib.baseboard_fab2(sch_1):page86_i138:vss(52)" )
			)
			( pin "J9L2.125"
				( objectStatus "@baseboard_fab2_lib.baseboard_fab2(sch_1):page86_i138:vss(53)" )
			)
			( pin "J9L2.123"
				( objectStatus "@baseboard_fab2_lib.baseboard_fab2(sch_1):page86_i138:vss(54)" )
			)
			( pin "J9L2.120"
				( objectStatus "@baseboard_fab2_lib.baseboard_fab2(sch_1):page86_i138:vss(55)" )
			)
			( pin "J9L2.118"
				( objectStatus "@baseboard_fab2_lib.baseboard_fab2(sch_1):page86_i138:vss(56)" )
			)
			( pin "J9L2.116"
				( objectStatus "@baseboard_fab2_lib.baseboard_fab2(sch_1):page86_i138:vss(57)" )
			)
			( pin "J9L2.114"
				( objectStatus "@baseboard_fab2_lib.baseboard_fab2(sch_1):page86_i138:vss(58)" )
			)
			( pin "J9L2.112"
				( objectStatus "@baseboard_fab2_lib.baseboard_fab2(sch_1):page86_i138:vss(59)" )
			)
			( pin "J9L2.109"
				( objectStatus "@baseboard_fab2_lib.baseboard_fab2(sch_1):page86_i138:vss(60)" )
			)
			( pin "J9L2.107"
				( objectStatus "@baseboard_fab2_lib.baseboard_fab2(sch_1):page86_i138:vss(61)" )
			)
			( pin "J9L2.105"
				( objectStatus "@baseboard_fab2_lib.baseboard_fab2(sch_1):page86_i138:vss(62)" )
			)
			( pin "J9L2.103"
				( objectStatus "@baseboard_fab2_lib.baseboard_fab2(sch_1):page86_i138:vss(63)" )
			)
			( pin "J9L2.101"
				( objectStatus "@baseboard_fab2_lib.baseboard_fab2(sch_1):page86_i138:vss(64)" )
			)
			( pin "J9L2.98"
				( objectStatus "@baseboard_fab2_lib.baseboard_fab2(sch_1):page86_i138:vss(65)" )
			)
			( pin "J9L2.96"
				( objectStatus "@baseboard_fab2_lib.baseboard_fab2(sch_1):page86_i138:vss(66)" )
			)
			( pin "J9L2.94"
				( objectStatus "@baseboard_fab2_lib.baseboard_fab2(sch_1):page86_i138:vss(67)" )
			)
			( pin "J9L2.57"
				( objectStatus "@baseboard_fab2_lib.baseboard_fab2(sch_1):page86_i138:vss(68)" )
			)
			( pin "J9L2.55"
				( objectStatus "@baseboard_fab2_lib.baseboard_fab2(sch_1):page86_i138:vss(69)" )
			)
			( pin "J9L2.53"
				( objectStatus "@baseboard_fab2_lib.baseboard_fab2(sch_1):page86_i138:vss(70)" )
			)
			( pin "J9L2.50"
				( objectStatus "@baseboard_fab2_lib.baseboard_fab2(sch_1):page86_i138:vss(71)" )
			)
			( pin "J9L2.48"
				( objectStatus "@baseboard_fab2_lib.baseboard_fab2(sch_1):page86_i138:vss(72)" )
			)
			( pin "J9L2.46"
				( objectStatus "@baseboard_fab2_lib.baseboard_fab2(sch_1):page86_i138:vss(73)" )
			)
			( pin "J9L2.44"
				( objectStatus "@baseboard_fab2_lib.baseboard_fab2(sch_1):page86_i138:vss(74)" )
			)
			( pin "J9L2.42"
				( objectStatus "@baseboard_fab2_lib.baseboard_fab2(sch_1):page86_i138:vss(75)" )
			)
			( pin "J9L2.39"
				( objectStatus "@baseboard_fab2_lib.baseboard_fab2(sch_1):page86_i138:vss(76)" )
			)
			( pin "J9L2.37"
				( objectStatus "@baseboard_fab2_lib.baseboard_fab2(sch_1):page86_i138:vss(77)" )
			)
			( pin "J9L2.35"
				( objectStatus "@baseboard_fab2_lib.baseboard_fab2(sch_1):page86_i138:vss(78)" )
			)
			( pin "J9L2.33"
				( objectStatus "@baseboard_fab2_lib.baseboard_fab2(sch_1):page86_i138:vss(79)" )
			)
			( pin "J9L2.31"
				( objectStatus "@baseboard_fab2_lib.baseboard_fab2(sch_1):page86_i138:vss(80)" )
			)
			( pin "J9L2.28"
				( objectStatus "@baseboard_fab2_lib.baseboard_fab2(sch_1):page86_i138:vss(81)" )
			)
			( pin "J9L2.26"
				( objectStatus "@baseboard_fab2_lib.baseboard_fab2(sch_1):page86_i138:vss(82)" )
			)
			( pin "J9L2.24"
				( objectStatus "@baseboard_fab2_lib.baseboard_fab2(sch_1):page86_i138:vss(83)" )
			)
			( pin "J9L2.22"
				( objectStatus "@baseboard_fab2_lib.baseboard_fab2(sch_1):page86_i138:vss(84)" )
			)
			( pin "J9L2.20"
				( objectStatus "@baseboard_fab2_lib.baseboard_fab2(sch_1):page86_i138:vss(85)" )
			)
			( pin "J9L2.17"
				( objectStatus "@baseboard_fab2_lib.baseboard_fab2(sch_1):page86_i138:vss(86)" )
			)
			( pin "J9L2.15"
				( objectStatus "@baseboard_fab2_lib.baseboard_fab2(sch_1):page86_i138:vss(87)" )
			)
			( pin "J9L2.13"
				( objectStatus "@baseboard_fab2_lib.baseboard_fab2(sch_1):page86_i138:vss(88)" )
			)
			( pin "J9L2.11"
				( objectStatus "@baseboard_fab2_lib.baseboard_fab2(sch_1):page86_i138:vss(89)" )
			)
			( pin "J9L2.9"
				( objectStatus "@baseboard_fab2_lib.baseboard_fab2(sch_1):page86_i138:vss(90)" )
			)
			( pin "J9L2.6"
				( objectStatus "@baseboard_fab2_lib.baseboard_fab2(sch_1):page86_i138:vss(91)" )
			)
			( pin "J9L2.4"
				( objectStatus "@baseboard_fab2_lib.baseboard_fab2(sch_1):page86_i138:vss(92)" )
			)
			( pin "J9L2.2"
				( objectStatus "@baseboard_fab2_lib.baseboard_fab2(sch_1):page86_i138:vss(93)" )
			)
			( pin "C1A17.1"
				( objectStatus "@baseboard_fab2_lib.baseboard_fab2(sch_1):page86_i182:a" )
			)
			( pin "C1A17.2"
				( objectStatus "@baseboard_fab2_lib.baseboard_fab2(sch_1):page86_i182:b" )
			)
			( pin "J1A1.145"
				( objectStatus "@baseboard_fab2_lib.baseboard_fab2(sch_1):page87_i169:\12v\(0)" )
			)
			( pin "J1A1.1"
				( objectStatus "@baseboard_fab2_lib.baseboard_fab2(sch_1):page87_i169:\12v\(1)" )
			)
			( pin "J1A1.236"
				( objectStatus "@baseboard_fab2_lib.baseboard_fab2(sch_1):page87_i169:vdd(0)" )
			)
			( pin "J1A1.233"
				( objectStatus "@baseboard_fab2_lib.baseboard_fab2(sch_1):page87_i169:vdd(1)" )
			)
			( pin "J1A1.231"
				( objectStatus "@baseboard_fab2_lib.baseboard_fab2(sch_1):page87_i169:vdd(2)" )
			)
			( pin "J1A1.229"
				( objectStatus "@baseboard_fab2_lib.baseboard_fab2(sch_1):page87_i169:vdd(3)" )
			)
			( pin "J1A1.226"
				( objectStatus "@baseboard_fab2_lib.baseboard_fab2(sch_1):page87_i169:vdd(4)" )
			)
			( pin "J1A1.223"
				( objectStatus "@baseboard_fab2_lib.baseboard_fab2(sch_1):page87_i169:vdd(5)" )
			)
			( pin "J1A1.220"
				( objectStatus "@baseboard_fab2_lib.baseboard_fab2(sch_1):page87_i169:vdd(6)" )
			)
			( pin "J1A1.217"
				( objectStatus "@baseboard_fab2_lib.baseboard_fab2(sch_1):page87_i169:vdd(7)" )
			)
			( pin "J1A1.215"
				( objectStatus "@baseboard_fab2_lib.baseboard_fab2(sch_1):page87_i169:vdd(8)" )
			)
			( pin "J1A1.212"
				( objectStatus "@baseboard_fab2_lib.baseboard_fab2(sch_1):page87_i169:vdd(9)" )
			)
			( pin "J1A1.209"
				( objectStatus "@baseboard_fab2_lib.baseboard_fab2(sch_1):page87_i169:vdd(10)" )
			)
			( pin "J1A1.206"
				( objectStatus "@baseboard_fab2_lib.baseboard_fab2(sch_1):page87_i169:vdd(11)" )
			)
			( pin "J1A1.204"
				( objectStatus "@baseboard_fab2_lib.baseboard_fab2(sch_1):page87_i169:vdd(12)" )
			)
			( pin "J1A1.92"
				( objectStatus "@baseboard_fab2_lib.baseboard_fab2(sch_1):page87_i169:vdd(13)" )
			)
			( pin "J1A1.90"
				( objectStatus "@baseboard_fab2_lib.baseboard_fab2(sch_1):page87_i169:vdd(14)" )
			)
			( pin "J1A1.88"
				( objectStatus "@baseboard_fab2_lib.baseboard_fab2(sch_1):page87_i169:vdd(15)" )
			)
			( pin "J1A1.85"
				( objectStatus "@baseboard_fab2_lib.baseboard_fab2(sch_1):page87_i169:vdd(16)" )
			)
			( pin "J1A1.83"
				( objectStatus "@baseboard_fab2_lib.baseboard_fab2(sch_1):page87_i169:vdd(17)" )
			)
			( pin "J1A1.80"
				( objectStatus "@baseboard_fab2_lib.baseboard_fab2(sch_1):page87_i169:vdd(18)" )
			)
			( pin "J1A1.76"
				( objectStatus "@baseboard_fab2_lib.baseboard_fab2(sch_1):page87_i169:vdd(19)" )
			)
			( pin "J1A1.73"
				( objectStatus "@baseboard_fab2_lib.baseboard_fab2(sch_1):page87_i169:vdd(20)" )
			)
			( pin "J1A1.70"
				( objectStatus "@baseboard_fab2_lib.baseboard_fab2(sch_1):page87_i169:vdd(21)" )
			)
			( pin "J1A1.67"
				( objectStatus "@baseboard_fab2_lib.baseboard_fab2(sch_1):page87_i169:vdd(22)" )
			)
			( pin "J1A1.64"
				( objectStatus "@baseboard_fab2_lib.baseboard_fab2(sch_1):page87_i169:vdd(23)" )
			)
			( pin "J1A1.61"
				( objectStatus "@baseboard_fab2_lib.baseboard_fab2(sch_1):page87_i169:vdd(24)" )
			)
			( pin "J1A1.59"
				( objectStatus "@baseboard_fab2_lib.baseboard_fab2(sch_1):page87_i169:vdd(25)" )
			)
			( pin "J1A1.287"
				( objectStatus "@baseboard_fab2_lib.baseboard_fab2(sch_1):page87_i169:vpp(0)" )
			)
			( pin "J1A1.286"
				( objectStatus "@baseboard_fab2_lib.baseboard_fab2(sch_1):page87_i169:vpp(1)" )
			)
			( pin "J1A1.288"
				( objectStatus "@baseboard_fab2_lib.baseboard_fab2(sch_1):page87_i169:vpp(2)" )
			)
			( pin "J1A1.143"
				( objectStatus "@baseboard_fab2_lib.baseboard_fab2(sch_1):page87_i169:vpp(3)" )
			)
			( pin "J1A1.142"
				( objectStatus "@baseboard_fab2_lib.baseboard_fab2(sch_1):page87_i169:vpp(4)" )
			)
			( pin "J1A1.221"
				( objectStatus "@baseboard_fab2_lib.baseboard_fab2(sch_1):page87_i169:vtt(0)" )
			)
			( pin "J1A1.77"
				( objectStatus "@baseboard_fab2_lib.baseboard_fab2(sch_1):page87_i169:vtt(1)" )
			)
			( pin "C1A5.1"
				( objectStatus "@baseboard_fab2_lib.baseboard_fab2(sch_1):page87_i178:a" )
			)
			( pin "C1A5.2"
				( objectStatus "@baseboard_fab2_lib.baseboard_fab2(sch_1):page87_i178:b" )
			)
			( pin "J1A1.283"
				( objectStatus "@baseboard_fab2_lib.baseboard_fab2(sch_1):page87_i185:vss(0)" )
			)
			( pin "J1A1.281"
				( objectStatus "@baseboard_fab2_lib.baseboard_fab2(sch_1):page87_i185:vss(1)" )
			)
			( pin "J1A1.279"
				( objectStatus "@baseboard_fab2_lib.baseboard_fab2(sch_1):page87_i185:vss(2)" )
			)
			( pin "J1A1.276"
				( objectStatus "@baseboard_fab2_lib.baseboard_fab2(sch_1):page87_i185:vss(3)" )
			)
			( pin "J1A1.274"
				( objectStatus "@baseboard_fab2_lib.baseboard_fab2(sch_1):page87_i185:vss(4)" )
			)
			( pin "J1A1.272"
				( objectStatus "@baseboard_fab2_lib.baseboard_fab2(sch_1):page87_i185:vss(5)" )
			)
			( pin "J1A1.270"
				( objectStatus "@baseboard_fab2_lib.baseboard_fab2(sch_1):page87_i185:vss(6)" )
			)
			( pin "J1A1.268"
				( objectStatus "@baseboard_fab2_lib.baseboard_fab2(sch_1):page87_i185:vss(7)" )
			)
			( pin "J1A1.265"
				( objectStatus "@baseboard_fab2_lib.baseboard_fab2(sch_1):page87_i185:vss(8)" )
			)
			( pin "J1A1.263"
				( objectStatus "@baseboard_fab2_lib.baseboard_fab2(sch_1):page87_i185:vss(9)" )
			)
			( pin "J1A1.261"
				( objectStatus "@baseboard_fab2_lib.baseboard_fab2(sch_1):page87_i185:vss(10)" )
			)
			( pin "J1A1.259"
				( objectStatus "@baseboard_fab2_lib.baseboard_fab2(sch_1):page87_i185:vss(11)" )
			)
			( pin "J1A1.257"
				( objectStatus "@baseboard_fab2_lib.baseboard_fab2(sch_1):page87_i185:vss(12)" )
			)
			( pin "J1A1.254"
				( objectStatus "@baseboard_fab2_lib.baseboard_fab2(sch_1):page87_i185:vss(13)" )
			)
			( pin "J1A1.252"
				( objectStatus "@baseboard_fab2_lib.baseboard_fab2(sch_1):page87_i185:vss(14)" )
			)
			( pin "J1A1.250"
				( objectStatus "@baseboard_fab2_lib.baseboard_fab2(sch_1):page87_i185:vss(15)" )
			)
			( pin "J1A1.248"
				( objectStatus "@baseboard_fab2_lib.baseboard_fab2(sch_1):page87_i185:vss(16)" )
			)
			( pin "J1A1.246"
				( objectStatus "@baseboard_fab2_lib.baseboard_fab2(sch_1):page87_i185:vss(17)" )
			)
			( pin "J1A1.243"
				( objectStatus "@baseboard_fab2_lib.baseboard_fab2(sch_1):page87_i185:vss(18)" )
			)
			( pin "J1A1.241"
				( objectStatus "@baseboard_fab2_lib.baseboard_fab2(sch_1):page87_i185:vss(19)" )
			)
			( pin "J1A1.239"
				( objectStatus "@baseboard_fab2_lib.baseboard_fab2(sch_1):page87_i185:vss(20)" )
			)
			( pin "J1A1.202"
				( objectStatus "@baseboard_fab2_lib.baseboard_fab2(sch_1):page87_i185:vss(21)" )
			)
			( pin "J1A1.200"
				( objectStatus "@baseboard_fab2_lib.baseboard_fab2(sch_1):page87_i185:vss(22)" )
			)
			( pin "J1A1.198"
				( objectStatus "@baseboard_fab2_lib.baseboard_fab2(sch_1):page87_i185:vss(23)" )
			)
			( pin "J1A1.195"
				( objectStatus "@baseboard_fab2_lib.baseboard_fab2(sch_1):page87_i185:vss(24)" )
			)
			( pin "J1A1.193"
				( objectStatus "@baseboard_fab2_lib.baseboard_fab2(sch_1):page87_i185:vss(25)" )
			)
			( pin "J1A1.191"
				( objectStatus "@baseboard_fab2_lib.baseboard_fab2(sch_1):page87_i185:vss(26)" )
			)
			( pin "J1A1.189"
				( objectStatus "@baseboard_fab2_lib.baseboard_fab2(sch_1):page87_i185:vss(27)" )
			)
			( pin "J1A1.187"
				( objectStatus "@baseboard_fab2_lib.baseboard_fab2(sch_1):page87_i185:vss(28)" )
			)
			( pin "J1A1.184"
				( objectStatus "@baseboard_fab2_lib.baseboard_fab2(sch_1):page87_i185:vss(29)" )
			)
			( pin "J1A1.182"
				( objectStatus "@baseboard_fab2_lib.baseboard_fab2(sch_1):page87_i185:vss(30)" )
			)
			( pin "J1A1.180"
				( objectStatus "@baseboard_fab2_lib.baseboard_fab2(sch_1):page87_i185:vss(31)" )
			)
			( pin "J1A1.178"
				( objectStatus "@baseboard_fab2_lib.baseboard_fab2(sch_1):page87_i185:vss(32)" )
			)
			( pin "J1A1.176"
				( objectStatus "@baseboard_fab2_lib.baseboard_fab2(sch_1):page87_i185:vss(33)" )
			)
			( pin "J1A1.173"
				( objectStatus "@baseboard_fab2_lib.baseboard_fab2(sch_1):page87_i185:vss(34)" )
			)
			( pin "J1A1.171"
				( objectStatus "@baseboard_fab2_lib.baseboard_fab2(sch_1):page87_i185:vss(35)" )
			)
			( pin "J1A1.169"
				( objectStatus "@baseboard_fab2_lib.baseboard_fab2(sch_1):page87_i185:vss(36)" )
			)
			( pin "J1A1.167"
				( objectStatus "@baseboard_fab2_lib.baseboard_fab2(sch_1):page87_i185:vss(37)" )
			)
			( pin "J1A1.165"
				( objectStatus "@baseboard_fab2_lib.baseboard_fab2(sch_1):page87_i185:vss(38)" )
			)
			( pin "J1A1.162"
				( objectStatus "@baseboard_fab2_lib.baseboard_fab2(sch_1):page87_i185:vss(39)" )
			)
			( pin "J1A1.160"
				( objectStatus "@baseboard_fab2_lib.baseboard_fab2(sch_1):page87_i185:vss(40)" )
			)
			( pin "J1A1.158"
				( objectStatus "@baseboard_fab2_lib.baseboard_fab2(sch_1):page87_i185:vss(41)" )
			)
			( pin "J1A1.156"
				( objectStatus "@baseboard_fab2_lib.baseboard_fab2(sch_1):page87_i185:vss(42)" )
			)
			( pin "J1A1.154"
				( objectStatus "@baseboard_fab2_lib.baseboard_fab2(sch_1):page87_i185:vss(43)" )
			)
			( pin "J1A1.151"
				( objectStatus "@baseboard_fab2_lib.baseboard_fab2(sch_1):page87_i185:vss(44)" )
			)
			( pin "J1A1.149"
				( objectStatus "@baseboard_fab2_lib.baseboard_fab2(sch_1):page87_i185:vss(45)" )
			)
			( pin "J1A1.147"
				( objectStatus "@baseboard_fab2_lib.baseboard_fab2(sch_1):page87_i185:vss(46)" )
			)
			( pin "J1A1.138"
				( objectStatus "@baseboard_fab2_lib.baseboard_fab2(sch_1):page87_i185:vss(47)" )
			)
			( pin "J1A1.136"
				( objectStatus "@baseboard_fab2_lib.baseboard_fab2(sch_1):page87_i185:vss(48)" )
			)
			( pin "J1A1.134"
				( objectStatus "@baseboard_fab2_lib.baseboard_fab2(sch_1):page87_i185:vss(49)" )
			)
			( pin "J1A1.131"
				( objectStatus "@baseboard_fab2_lib.baseboard_fab2(sch_1):page87_i185:vss(50)" )
			)
			( pin "J1A1.129"
				( objectStatus "@baseboard_fab2_lib.baseboard_fab2(sch_1):page87_i185:vss(51)" )
			)
			( pin "J1A1.127"
				( objectStatus "@baseboard_fab2_lib.baseboard_fab2(sch_1):page87_i185:vss(52)" )
			)
			( pin "J1A1.125"
				( objectStatus "@baseboard_fab2_lib.baseboard_fab2(sch_1):page87_i185:vss(53)" )
			)
			( pin "J1A1.123"
				( objectStatus "@baseboard_fab2_lib.baseboard_fab2(sch_1):page87_i185:vss(54)" )
			)
			( pin "J1A1.120"
				( objectStatus "@baseboard_fab2_lib.baseboard_fab2(sch_1):page87_i185:vss(55)" )
			)
			( pin "J1A1.118"
				( objectStatus "@baseboard_fab2_lib.baseboard_fab2(sch_1):page87_i185:vss(56)" )
			)
			( pin "J1A1.116"
				( objectStatus "@baseboard_fab2_lib.baseboard_fab2(sch_1):page87_i185:vss(57)" )
			)
			( pin "J1A1.114"
				( objectStatus "@baseboard_fab2_lib.baseboard_fab2(sch_1):page87_i185:vss(58)" )
			)
			( pin "J1A1.112"
				( objectStatus "@baseboard_fab2_lib.baseboard_fab2(sch_1):page87_i185:vss(59)" )
			)
			( pin "J1A1.109"
				( objectStatus "@baseboard_fab2_lib.baseboard_fab2(sch_1):page87_i185:vss(60)" )
			)
			( pin "J1A1.107"
				( objectStatus "@baseboard_fab2_lib.baseboard_fab2(sch_1):page87_i185:vss(61)" )
			)
			( pin "J1A1.105"
				( objectStatus "@baseboard_fab2_lib.baseboard_fab2(sch_1):page87_i185:vss(62)" )
			)
			( pin "J1A1.103"
				( objectStatus "@baseboard_fab2_lib.baseboard_fab2(sch_1):page87_i185:vss(63)" )
			)
			( pin "J1A1.101"
				( objectStatus "@baseboard_fab2_lib.baseboard_fab2(sch_1):page87_i185:vss(64)" )
			)
			( pin "J1A1.98"
				( objectStatus "@baseboard_fab2_lib.baseboard_fab2(sch_1):page87_i185:vss(65)" )
			)
			( pin "J1A1.96"
				( objectStatus "@baseboard_fab2_lib.baseboard_fab2(sch_1):page87_i185:vss(66)" )
			)
			( pin "J1A1.94"
				( objectStatus "@baseboard_fab2_lib.baseboard_fab2(sch_1):page87_i185:vss(67)" )
			)
			( pin "J1A1.57"
				( objectStatus "@baseboard_fab2_lib.baseboard_fab2(sch_1):page87_i185:vss(68)" )
			)
			( pin "J1A1.55"
				( objectStatus "@baseboard_fab2_lib.baseboard_fab2(sch_1):page87_i185:vss(69)" )
			)
			( pin "J1A1.53"
				( objectStatus "@baseboard_fab2_lib.baseboard_fab2(sch_1):page87_i185:vss(70)" )
			)
			( pin "J1A1.50"
				( objectStatus "@baseboard_fab2_lib.baseboard_fab2(sch_1):page87_i185:vss(71)" )
			)
			( pin "J1A1.48"
				( objectStatus "@baseboard_fab2_lib.baseboard_fab2(sch_1):page87_i185:vss(72)" )
			)
			( pin "J1A1.46"
				( objectStatus "@baseboard_fab2_lib.baseboard_fab2(sch_1):page87_i185:vss(73)" )
			)
			( pin "J1A1.44"
				( objectStatus "@baseboard_fab2_lib.baseboard_fab2(sch_1):page87_i185:vss(74)" )
			)
			( pin "J1A1.42"
				( objectStatus "@baseboard_fab2_lib.baseboard_fab2(sch_1):page87_i185:vss(75)" )
			)
			( pin "J1A1.39"
				( objectStatus "@baseboard_fab2_lib.baseboard_fab2(sch_1):page87_i185:vss(76)" )
			)
			( pin "J1A1.37"
				( objectStatus "@baseboard_fab2_lib.baseboard_fab2(sch_1):page87_i185:vss(77)" )
			)
			( pin "J1A1.35"
				( objectStatus "@baseboard_fab2_lib.baseboard_fab2(sch_1):page87_i185:vss(78)" )
			)
			( pin "J1A1.33"
				( objectStatus "@baseboard_fab2_lib.baseboard_fab2(sch_1):page87_i185:vss(79)" )
			)
			( pin "J1A1.31"
				( objectStatus "@baseboard_fab2_lib.baseboard_fab2(sch_1):page87_i185:vss(80)" )
			)
			( pin "J1A1.28"
				( objectStatus "@baseboard_fab2_lib.baseboard_fab2(sch_1):page87_i185:vss(81)" )
			)
			( pin "J1A1.26"
				( objectStatus "@baseboard_fab2_lib.baseboard_fab2(sch_1):page87_i185:vss(82)" )
			)
			( pin "J1A1.24"
				( objectStatus "@baseboard_fab2_lib.baseboard_fab2(sch_1):page87_i185:vss(83)" )
			)
			( pin "J1A1.22"
				( objectStatus "@baseboard_fab2_lib.baseboard_fab2(sch_1):page87_i185:vss(84)" )
			)
			( pin "J1A1.20"
				( objectStatus "@baseboard_fab2_lib.baseboard_fab2(sch_1):page87_i185:vss(85)" )
			)
			( pin "J1A1.17"
				( objectStatus "@baseboard_fab2_lib.baseboard_fab2(sch_1):page87_i185:vss(86)" )
			)
			( pin "J1A1.15"
				( objectStatus "@baseboard_fab2_lib.baseboard_fab2(sch_1):page87_i185:vss(87)" )
			)
			( pin "J1A1.13"
				( objectStatus "@baseboard_fab2_lib.baseboard_fab2(sch_1):page87_i185:vss(88)" )
			)
			( pin "J1A1.11"
				( objectStatus "@baseboard_fab2_lib.baseboard_fab2(sch_1):page87_i185:vss(89)" )
			)
			( pin "J1A1.9"
				( objectStatus "@baseboard_fab2_lib.baseboard_fab2(sch_1):page87_i185:vss(90)" )
			)
			( pin "J1A1.6"
				( objectStatus "@baseboard_fab2_lib.baseboard_fab2(sch_1):page87_i185:vss(91)" )
			)
			( pin "J1A1.4"
				( objectStatus "@baseboard_fab2_lib.baseboard_fab2(sch_1):page87_i185:vss(92)" )
			)
			( pin "J1A1.2"
				( objectStatus "@baseboard_fab2_lib.baseboard_fab2(sch_1):page87_i185:vss(93)" )
			)
			( pin "J1A1.79"
				( objectStatus "@baseboard_fab2_lib.baseboard_fab2(sch_1):page87_i186:a0" )
			)
			( pin "J1A1.72"
				( objectStatus "@baseboard_fab2_lib.baseboard_fab2(sch_1):page87_i186:a1" )
			)
			( pin "J1A1.216"
				( objectStatus "@baseboard_fab2_lib.baseboard_fab2(sch_1):page87_i186:a2" )
			)
			( pin "J1A1.71"
				( objectStatus "@baseboard_fab2_lib.baseboard_fab2(sch_1):page87_i186:a3" )
			)
			( pin "J1A1.214"
				( objectStatus "@baseboard_fab2_lib.baseboard_fab2(sch_1):page87_i186:a4" )
			)
			( pin "J1A1.213"
				( objectStatus "@baseboard_fab2_lib.baseboard_fab2(sch_1):page87_i186:a5" )
			)
			( pin "J1A1.69"
				( objectStatus "@baseboard_fab2_lib.baseboard_fab2(sch_1):page87_i186:a6" )
			)
			( pin "J1A1.211"
				( objectStatus "@baseboard_fab2_lib.baseboard_fab2(sch_1):page87_i186:a7" )
			)
			( pin "J1A1.68"
				( objectStatus "@baseboard_fab2_lib.baseboard_fab2(sch_1):page87_i186:a8" )
			)
			( pin "J1A1.66"
				( objectStatus "@baseboard_fab2_lib.baseboard_fab2(sch_1):page87_i186:a9" )
			)
			( pin "J1A1.225"
				( objectStatus "@baseboard_fab2_lib.baseboard_fab2(sch_1):page87_i186:a10" )
			)
			( pin "J1A1.210"
				( objectStatus "@baseboard_fab2_lib.baseboard_fab2(sch_1):page87_i186:a11" )
			)
			( pin "J1A1.65"
				( objectStatus "@baseboard_fab2_lib.baseboard_fab2(sch_1):page87_i186:a12" )
			)
			( pin "J1A1.232"
				( objectStatus "@baseboard_fab2_lib.baseboard_fab2(sch_1):page87_i186:a13" )
			)
			( pin "J1A1.228"
				( objectStatus "@baseboard_fab2_lib.baseboard_fab2(sch_1):page87_i186:a14_we_n" )
			)
			( pin "J1A1.86"
				( objectStatus "@baseboard_fab2_lib.baseboard_fab2(sch_1):page87_i186:a15_cas_n" )
			)
			( pin "J1A1.82"
				( objectStatus "@baseboard_fab2_lib.baseboard_fab2(sch_1):page87_i186:a16_ras_n" )
			)
			( pin "J1A1.234"
				( objectStatus "@baseboard_fab2_lib.baseboard_fab2(sch_1):page87_i186:a17" )
			)
			( pin "J1A1.62"
				( objectStatus "@baseboard_fab2_lib.baseboard_fab2(sch_1):page87_i186:act_n" )
			)
			( pin "J1A1.208"
				( objectStatus "@baseboard_fab2_lib.baseboard_fab2(sch_1):page87_i186:alert_n" )
			)
			( pin "J1A1.81"
				( objectStatus "@baseboard_fab2_lib.baseboard_fab2(sch_1):page87_i186:ba(0)" )
			)
			( pin "J1A1.224"
				( objectStatus "@baseboard_fab2_lib.baseboard_fab2(sch_1):page87_i186:ba(1)" )
			)
			( pin "J1A1.63"
				( objectStatus "@baseboard_fab2_lib.baseboard_fab2(sch_1):page87_i186:bg(0)" )
			)
			( pin "J1A1.207"
				( objectStatus "@baseboard_fab2_lib.baseboard_fab2(sch_1):page87_i186:bg(1)" )
			)
			( pin "J1A1.235"
				( objectStatus "@baseboard_fab2_lib.baseboard_fab2(sch_1):page87_i186:c(2)" )
			)
			( pin "J1A1.49"
				( objectStatus "@baseboard_fab2_lib.baseboard_fab2(sch_1):page87_i186:cb(0)" )
			)
			( pin "J1A1.194"
				( objectStatus "@baseboard_fab2_lib.baseboard_fab2(sch_1):page87_i186:cb(1)" )
			)
			( pin "J1A1.56"
				( objectStatus "@baseboard_fab2_lib.baseboard_fab2(sch_1):page87_i186:cb(2)" )
			)
			( pin "J1A1.201"
				( objectStatus "@baseboard_fab2_lib.baseboard_fab2(sch_1):page87_i186:cb(3)" )
			)
			( pin "J1A1.47"
				( objectStatus "@baseboard_fab2_lib.baseboard_fab2(sch_1):page87_i186:cb(4)" )
			)
			( pin "J1A1.192"
				( objectStatus "@baseboard_fab2_lib.baseboard_fab2(sch_1):page87_i186:cb(5)" )
			)
			( pin "J1A1.54"
				( objectStatus "@baseboard_fab2_lib.baseboard_fab2(sch_1):page87_i186:cb(6)" )
			)
			( pin "J1A1.199"
				( objectStatus "@baseboard_fab2_lib.baseboard_fab2(sch_1):page87_i186:cb(7)" )
			)
			( pin "J1A1.75"
				( objectStatus "@baseboard_fab2_lib.baseboard_fab2(sch_1):page87_i186:ck0n" )
			)
			( pin "J1A1.74"
				( objectStatus "@baseboard_fab2_lib.baseboard_fab2(sch_1):page87_i186:ck0p" )
			)
			( pin "J1A1.219"
				( objectStatus "@baseboard_fab2_lib.baseboard_fab2(sch_1):page87_i186:ck1n" )
			)
			( pin "J1A1.218"
				( objectStatus "@baseboard_fab2_lib.baseboard_fab2(sch_1):page87_i186:ck1p" )
			)
			( pin "J1A1.60"
				( objectStatus "@baseboard_fab2_lib.baseboard_fab2(sch_1):page87_i186:cke(0)" )
			)
			( pin "J1A1.203"
				( objectStatus "@baseboard_fab2_lib.baseboard_fab2(sch_1):page87_i186:cke(1)" )
			)
			( pin "J1A1.5"
				( objectStatus "@baseboard_fab2_lib.baseboard_fab2(sch_1):page87_i186:dq(0)" )
			)
			( pin "J1A1.150"
				( objectStatus "@baseboard_fab2_lib.baseboard_fab2(sch_1):page87_i186:dq(1)" )
			)
			( pin "J1A1.12"
				( objectStatus "@baseboard_fab2_lib.baseboard_fab2(sch_1):page87_i186:dq(2)" )
			)
			( pin "J1A1.157"
				( objectStatus "@baseboard_fab2_lib.baseboard_fab2(sch_1):page87_i186:dq(3)" )
			)
			( pin "J1A1.3"
				( objectStatus "@baseboard_fab2_lib.baseboard_fab2(sch_1):page87_i186:dq(4)" )
			)
			( pin "J1A1.148"
				( objectStatus "@baseboard_fab2_lib.baseboard_fab2(sch_1):page87_i186:dq(5)" )
			)
			( pin "J1A1.10"
				( objectStatus "@baseboard_fab2_lib.baseboard_fab2(sch_1):page87_i186:dq(6)" )
			)
			( pin "J1A1.155"
				( objectStatus "@baseboard_fab2_lib.baseboard_fab2(sch_1):page87_i186:dq(7)" )
			)
			( pin "J1A1.16"
				( objectStatus "@baseboard_fab2_lib.baseboard_fab2(sch_1):page87_i186:dq(8)" )
			)
			( pin "J1A1.161"
				( objectStatus "@baseboard_fab2_lib.baseboard_fab2(sch_1):page87_i186:dq(9)" )
			)
			( pin "J1A1.23"
				( objectStatus "@baseboard_fab2_lib.baseboard_fab2(sch_1):page87_i186:dq(10)" )
			)
			( pin "J1A1.168"
				( objectStatus "@baseboard_fab2_lib.baseboard_fab2(sch_1):page87_i186:dq(11)" )
			)
			( pin "J1A1.14"
				( objectStatus "@baseboard_fab2_lib.baseboard_fab2(sch_1):page87_i186:dq(12)" )
			)
			( pin "J1A1.159"
				( objectStatus "@baseboard_fab2_lib.baseboard_fab2(sch_1):page87_i186:dq(13)" )
			)
			( pin "J1A1.21"
				( objectStatus "@baseboard_fab2_lib.baseboard_fab2(sch_1):page87_i186:dq(14)" )
			)
			( pin "J1A1.166"
				( objectStatus "@baseboard_fab2_lib.baseboard_fab2(sch_1):page87_i186:dq(15)" )
			)
			( pin "J1A1.27"
				( objectStatus "@baseboard_fab2_lib.baseboard_fab2(sch_1):page87_i186:dq(16)" )
			)
			( pin "J1A1.172"
				( objectStatus "@baseboard_fab2_lib.baseboard_fab2(sch_1):page87_i186:dq(17)" )
			)
			( pin "J1A1.34"
				( objectStatus "@baseboard_fab2_lib.baseboard_fab2(sch_1):page87_i186:dq(18)" )
			)
			( pin "J1A1.179"
				( objectStatus "@baseboard_fab2_lib.baseboard_fab2(sch_1):page87_i186:dq(19)" )
			)
			( pin "J1A1.25"
				( objectStatus "@baseboard_fab2_lib.baseboard_fab2(sch_1):page87_i186:dq(20)" )
			)
			( pin "J1A1.170"
				( objectStatus "@baseboard_fab2_lib.baseboard_fab2(sch_1):page87_i186:dq(21)" )
			)
			( pin "J1A1.32"
				( objectStatus "@baseboard_fab2_lib.baseboard_fab2(sch_1):page87_i186:dq(22)" )
			)
			( pin "J1A1.177"
				( objectStatus "@baseboard_fab2_lib.baseboard_fab2(sch_1):page87_i186:dq(23)" )
			)
			( pin "J1A1.38"
				( objectStatus "@baseboard_fab2_lib.baseboard_fab2(sch_1):page87_i186:dq(24)" )
			)
			( pin "J1A1.183"
				( objectStatus "@baseboard_fab2_lib.baseboard_fab2(sch_1):page87_i186:dq(25)" )
			)
			( pin "J1A1.45"
				( objectStatus "@baseboard_fab2_lib.baseboard_fab2(sch_1):page87_i186:dq(26)" )
			)
			( pin "J1A1.190"
				( objectStatus "@baseboard_fab2_lib.baseboard_fab2(sch_1):page87_i186:dq(27)" )
			)
			( pin "J1A1.36"
				( objectStatus "@baseboard_fab2_lib.baseboard_fab2(sch_1):page87_i186:dq(28)" )
			)
			( pin "J1A1.181"
				( objectStatus "@baseboard_fab2_lib.baseboard_fab2(sch_1):page87_i186:dq(29)" )
			)
			( pin "J1A1.43"
				( objectStatus "@baseboard_fab2_lib.baseboard_fab2(sch_1):page87_i186:dq(30)" )
			)
			( pin "J1A1.188"
				( objectStatus "@baseboard_fab2_lib.baseboard_fab2(sch_1):page87_i186:dq(31)" )
			)
			( pin "J1A1.97"
				( objectStatus "@baseboard_fab2_lib.baseboard_fab2(sch_1):page87_i186:dq(32)" )
			)
			( pin "J1A1.242"
				( objectStatus "@baseboard_fab2_lib.baseboard_fab2(sch_1):page87_i186:dq(33)" )
			)
			( pin "J1A1.104"
				( objectStatus "@baseboard_fab2_lib.baseboard_fab2(sch_1):page87_i186:dq(34)" )
			)
			( pin "J1A1.249"
				( objectStatus "@baseboard_fab2_lib.baseboard_fab2(sch_1):page87_i186:dq(35)" )
			)
			( pin "J1A1.95"
				( objectStatus "@baseboard_fab2_lib.baseboard_fab2(sch_1):page87_i186:dq(36)" )
			)
			( pin "J1A1.240"
				( objectStatus "@baseboard_fab2_lib.baseboard_fab2(sch_1):page87_i186:dq(37)" )
			)
			( pin "J1A1.102"
				( objectStatus "@baseboard_fab2_lib.baseboard_fab2(sch_1):page87_i186:dq(38)" )
			)
			( pin "J1A1.247"
				( objectStatus "@baseboard_fab2_lib.baseboard_fab2(sch_1):page87_i186:dq(39)" )
			)
			( pin "J1A1.108"
				( objectStatus "@baseboard_fab2_lib.baseboard_fab2(sch_1):page87_i186:dq(40)" )
			)
			( pin "J1A1.253"
				( objectStatus "@baseboard_fab2_lib.baseboard_fab2(sch_1):page87_i186:dq(41)" )
			)
			( pin "J1A1.115"
				( objectStatus "@baseboard_fab2_lib.baseboard_fab2(sch_1):page87_i186:dq(42)" )
			)
			( pin "J1A1.260"
				( objectStatus "@baseboard_fab2_lib.baseboard_fab2(sch_1):page87_i186:dq(43)" )
			)
			( pin "J1A1.106"
				( objectStatus "@baseboard_fab2_lib.baseboard_fab2(sch_1):page87_i186:dq(44)" )
			)
			( pin "J1A1.251"
				( objectStatus "@baseboard_fab2_lib.baseboard_fab2(sch_1):page87_i186:dq(45)" )
			)
			( pin "J1A1.113"
				( objectStatus "@baseboard_fab2_lib.baseboard_fab2(sch_1):page87_i186:dq(46)" )
			)
			( pin "J1A1.258"
				( objectStatus "@baseboard_fab2_lib.baseboard_fab2(sch_1):page87_i186:dq(47)" )
			)
			( pin "J1A1.119"
				( objectStatus "@baseboard_fab2_lib.baseboard_fab2(sch_1):page87_i186:dq(48)" )
			)
			( pin "J1A1.264"
				( objectStatus "@baseboard_fab2_lib.baseboard_fab2(sch_1):page87_i186:dq(49)" )
			)
			( pin "J1A1.126"
				( objectStatus "@baseboard_fab2_lib.baseboard_fab2(sch_1):page87_i186:dq(50)" )
			)
			( pin "J1A1.271"
				( objectStatus "@baseboard_fab2_lib.baseboard_fab2(sch_1):page87_i186:dq(51)" )
			)
			( pin "J1A1.117"
				( objectStatus "@baseboard_fab2_lib.baseboard_fab2(sch_1):page87_i186:dq(52)" )
			)
			( pin "J1A1.262"
				( objectStatus "@baseboard_fab2_lib.baseboard_fab2(sch_1):page87_i186:dq(53)" )
			)
			( pin "J1A1.124"
				( objectStatus "@baseboard_fab2_lib.baseboard_fab2(sch_1):page87_i186:dq(54)" )
			)
			( pin "J1A1.269"
				( objectStatus "@baseboard_fab2_lib.baseboard_fab2(sch_1):page87_i186:dq(55)" )
			)
			( pin "J1A1.130"
				( objectStatus "@baseboard_fab2_lib.baseboard_fab2(sch_1):page87_i186:dq(56)" )
			)
			( pin "J1A1.275"
				( objectStatus "@baseboard_fab2_lib.baseboard_fab2(sch_1):page87_i186:dq(57)" )
			)
			( pin "J1A1.137"
				( objectStatus "@baseboard_fab2_lib.baseboard_fab2(sch_1):page87_i186:dq(58)" )
			)
			( pin "J1A1.282"
				( objectStatus "@baseboard_fab2_lib.baseboard_fab2(sch_1):page87_i186:dq(59)" )
			)
			( pin "J1A1.128"
				( objectStatus "@baseboard_fab2_lib.baseboard_fab2(sch_1):page87_i186:dq(60)" )
			)
			( pin "J1A1.273"
				( objectStatus "@baseboard_fab2_lib.baseboard_fab2(sch_1):page87_i186:dq(61)" )
			)
			( pin "J1A1.135"
				( objectStatus "@baseboard_fab2_lib.baseboard_fab2(sch_1):page87_i186:dq(62)" )
			)
			( pin "J1A1.280"
				( objectStatus "@baseboard_fab2_lib.baseboard_fab2(sch_1):page87_i186:dq(63)" )
			)
			( pin "J1A1.78"
				( objectStatus "@baseboard_fab2_lib.baseboard_fab2(sch_1):page87_i186:event_n" )
			)
			( pin "J1A1.87"
				( objectStatus "@baseboard_fab2_lib.baseboard_fab2(sch_1):page87_i186:odt(0)" )
			)
			( pin "J1A1.91"
				( objectStatus "@baseboard_fab2_lib.baseboard_fab2(sch_1):page87_i186:odt(1)" )
			)
			( pin "J1A1.222"
				( objectStatus "@baseboard_fab2_lib.baseboard_fab2(sch_1):page87_i186:par" )
			)
			( pin "J1A1.58"
				( objectStatus "@baseboard_fab2_lib.baseboard_fab2(sch_1):page87_i186:reset_n" )
			)
			( pin "J1A1.205"
				( objectStatus "@baseboard_fab2_lib.baseboard_fab2(sch_1):page87_i186:rfu(0)" )
			)
			( pin "J1A1.227"
				( objectStatus "@baseboard_fab2_lib.baseboard_fab2(sch_1):page87_i186:rfu(1)" )
			)
			( pin "J1A1.144"
				( objectStatus "@baseboard_fab2_lib.baseboard_fab2(sch_1):page87_i186:rfu(2)" )
			)
			( pin "J1A1.84"
				( objectStatus "@baseboard_fab2_lib.baseboard_fab2(sch_1):page87_i186:s0_n" )
			)
			( pin "J1A1.89"
				( objectStatus "@baseboard_fab2_lib.baseboard_fab2(sch_1):page87_i186:s1_n" )
			)
			( pin "J1A1.93"
				( objectStatus "@baseboard_fab2_lib.baseboard_fab2(sch_1):page87_i186:s2_n_c(0)" )
			)
			( pin "J1A1.237"
				( objectStatus "@baseboard_fab2_lib.baseboard_fab2(sch_1):page87_i186:s3_n_c(1)" )
			)
			( pin "J1A1.139"
				( objectStatus "@baseboard_fab2_lib.baseboard_fab2(sch_1):page87_i186:sa(0)" )
			)
			( pin "J1A1.140"
				( objectStatus "@baseboard_fab2_lib.baseboard_fab2(sch_1):page87_i186:sa(1)" )
			)
			( pin "J1A1.238"
				( objectStatus "@baseboard_fab2_lib.baseboard_fab2(sch_1):page87_i186:sa(2)" )
			)
			( pin "J1A1.230"
				( objectStatus "@baseboard_fab2_lib.baseboard_fab2(sch_1):page87_i186:save_n_nc" )
			)
			( pin "J1A1.141"
				( objectStatus "@baseboard_fab2_lib.baseboard_fab2(sch_1):page87_i186:scl" )
			)
			( pin "J1A1.285"
				( objectStatus "@baseboard_fab2_lib.baseboard_fab2(sch_1):page87_i186:sda" )
			)
			( pin "J1A1.284"
				( objectStatus "@baseboard_fab2_lib.baseboard_fab2(sch_1):page87_i186:vddspd" )
			)
			( pin "J1A1.146"
				( objectStatus "@baseboard_fab2_lib.baseboard_fab2(sch_1):page87_i186:vrefca" )
			)
			( pin "J1A1.152"
				( objectStatus "@baseboard_fab2_lib.baseboard_fab2(sch_1):page87_i187:dqs0n" )
			)
			( pin "J1A1.153"
				( objectStatus "@baseboard_fab2_lib.baseboard_fab2(sch_1):page87_i187:dqs0p" )
			)
			( pin "J1A1.163"
				( objectStatus "@baseboard_fab2_lib.baseboard_fab2(sch_1):page87_i187:dqs1n" )
			)
			( pin "J1A1.164"
				( objectStatus "@baseboard_fab2_lib.baseboard_fab2(sch_1):page87_i187:dqs1p" )
			)
			( pin "J1A1.174"
				( objectStatus "@baseboard_fab2_lib.baseboard_fab2(sch_1):page87_i187:dqs2n" )
			)
			( pin "J1A1.175"
				( objectStatus "@baseboard_fab2_lib.baseboard_fab2(sch_1):page87_i187:dqs2p" )
			)
			( pin "J1A1.185"
				( objectStatus "@baseboard_fab2_lib.baseboard_fab2(sch_1):page87_i187:dqs3n" )
			)
			( pin "J1A1.186"
				( objectStatus "@baseboard_fab2_lib.baseboard_fab2(sch_1):page87_i187:dqs3p" )
			)
			( pin "J1A1.244"
				( objectStatus "@baseboard_fab2_lib.baseboard_fab2(sch_1):page87_i187:dqs4n" )
			)
			( pin "J1A1.245"
				( objectStatus "@baseboard_fab2_lib.baseboard_fab2(sch_1):page87_i187:dqs4p" )
			)
			( pin "J1A1.255"
				( objectStatus "@baseboard_fab2_lib.baseboard_fab2(sch_1):page87_i187:dqs5n" )
			)
			( pin "J1A1.256"
				( objectStatus "@baseboard_fab2_lib.baseboard_fab2(sch_1):page87_i187:dqs5p" )
			)
			( pin "J1A1.266"
				( objectStatus "@baseboard_fab2_lib.baseboard_fab2(sch_1):page87_i187:dqs6n" )
			)
			( pin "J1A1.267"
				( objectStatus "@baseboard_fab2_lib.baseboard_fab2(sch_1):page87_i187:dqs6p" )
			)
			( pin "J1A1.277"
				( objectStatus "@baseboard_fab2_lib.baseboard_fab2(sch_1):page87_i187:dqs7n" )
			)
			( pin "J1A1.278"
				( objectStatus "@baseboard_fab2_lib.baseboard_fab2(sch_1):page87_i187:dqs7p" )
			)
			( pin "J1A1.196"
				( objectStatus "@baseboard_fab2_lib.baseboard_fab2(sch_1):page87_i187:dqs8n" )
			)
			( pin "J1A1.197"
				( objectStatus "@baseboard_fab2_lib.baseboard_fab2(sch_1):page87_i187:dqs8p" )
			)
			( pin "J1A1.8"
				( objectStatus "@baseboard_fab2_lib.baseboard_fab2(sch_1):page87_i187:dqs9n" )
			)
			( pin "J1A1.7"
				( objectStatus "@baseboard_fab2_lib.baseboard_fab2(sch_1):page87_i187:dqs9p" )
			)
			( pin "J1A1.19"
				( objectStatus "@baseboard_fab2_lib.baseboard_fab2(sch_1):page87_i187:dqs10n" )
			)
			( pin "J1A1.18"
				( objectStatus "@baseboard_fab2_lib.baseboard_fab2(sch_1):page87_i187:dqs10p" )
			)
			( pin "J1A1.30"
				( objectStatus "@baseboard_fab2_lib.baseboard_fab2(sch_1):page87_i187:dqs11n" )
			)
			( pin "J1A1.29"
				( objectStatus "@baseboard_fab2_lib.baseboard_fab2(sch_1):page87_i187:dqs11p" )
			)
			( pin "J1A1.41"
				( objectStatus "@baseboard_fab2_lib.baseboard_fab2(sch_1):page87_i187:dqs12n" )
			)
			( pin "J1A1.40"
				( objectStatus "@baseboard_fab2_lib.baseboard_fab2(sch_1):page87_i187:dqs12p" )
			)
			( pin "J1A1.100"
				( objectStatus "@baseboard_fab2_lib.baseboard_fab2(sch_1):page87_i187:dqs13n" )
			)
			( pin "J1A1.99"
				( objectStatus "@baseboard_fab2_lib.baseboard_fab2(sch_1):page87_i187:dqs13p" )
			)
			( pin "J1A1.111"
				( objectStatus "@baseboard_fab2_lib.baseboard_fab2(sch_1):page87_i187:dqs14n" )
			)
			( pin "J1A1.110"
				( objectStatus "@baseboard_fab2_lib.baseboard_fab2(sch_1):page87_i187:dqs14p" )
			)
			( pin "J1A1.122"
				( objectStatus "@baseboard_fab2_lib.baseboard_fab2(sch_1):page87_i187:dqs15n" )
			)
			( pin "J1A1.121"
				( objectStatus "@baseboard_fab2_lib.baseboard_fab2(sch_1):page87_i187:dqs15p" )
			)
			( pin "J1A1.133"
				( objectStatus "@baseboard_fab2_lib.baseboard_fab2(sch_1):page87_i187:dqs16n" )
			)
			( pin "J1A1.132"
				( objectStatus "@baseboard_fab2_lib.baseboard_fab2(sch_1):page87_i187:dqs16p" )
			)
			( pin "J1A1.52"
				( objectStatus "@baseboard_fab2_lib.baseboard_fab2(sch_1):page87_i187:dqs17n" )
			)
			( pin "J1A1.51"
				( objectStatus "@baseboard_fab2_lib.baseboard_fab2(sch_1):page87_i187:dqs17p" )
			)
			( pin "J9L1.283"
				( objectStatus "@baseboard_fab2_lib.baseboard_fab2(sch_1):page88_i25:vss(0)" )
			)
			( pin "J9L1.281"
				( objectStatus "@baseboard_fab2_lib.baseboard_fab2(sch_1):page88_i25:vss(1)" )
			)
			( pin "J9L1.279"
				( objectStatus "@baseboard_fab2_lib.baseboard_fab2(sch_1):page88_i25:vss(2)" )
			)
			( pin "J9L1.276"
				( objectStatus "@baseboard_fab2_lib.baseboard_fab2(sch_1):page88_i25:vss(3)" )
			)
			( pin "J9L1.274"
				( objectStatus "@baseboard_fab2_lib.baseboard_fab2(sch_1):page88_i25:vss(4)" )
			)
			( pin "J9L1.272"
				( objectStatus "@baseboard_fab2_lib.baseboard_fab2(sch_1):page88_i25:vss(5)" )
			)
			( pin "J9L1.270"
				( objectStatus "@baseboard_fab2_lib.baseboard_fab2(sch_1):page88_i25:vss(6)" )
			)
			( pin "J9L1.268"
				( objectStatus "@baseboard_fab2_lib.baseboard_fab2(sch_1):page88_i25:vss(7)" )
			)
			( pin "J9L1.265"
				( objectStatus "@baseboard_fab2_lib.baseboard_fab2(sch_1):page88_i25:vss(8)" )
			)
			( pin "J9L1.263"
				( objectStatus "@baseboard_fab2_lib.baseboard_fab2(sch_1):page88_i25:vss(9)" )
			)
			( pin "J9L1.261"
				( objectStatus "@baseboard_fab2_lib.baseboard_fab2(sch_1):page88_i25:vss(10)" )
			)
			( pin "J9L1.259"
				( objectStatus "@baseboard_fab2_lib.baseboard_fab2(sch_1):page88_i25:vss(11)" )
			)
			( pin "J9L1.257"
				( objectStatus "@baseboard_fab2_lib.baseboard_fab2(sch_1):page88_i25:vss(12)" )
			)
			( pin "J9L1.254"
				( objectStatus "@baseboard_fab2_lib.baseboard_fab2(sch_1):page88_i25:vss(13)" )
			)
			( pin "J9L1.252"
				( objectStatus "@baseboard_fab2_lib.baseboard_fab2(sch_1):page88_i25:vss(14)" )
			)
			( pin "J9L1.250"
				( objectStatus "@baseboard_fab2_lib.baseboard_fab2(sch_1):page88_i25:vss(15)" )
			)
			( pin "J9L1.248"
				( objectStatus "@baseboard_fab2_lib.baseboard_fab2(sch_1):page88_i25:vss(16)" )
			)
			( pin "J9L1.246"
				( objectStatus "@baseboard_fab2_lib.baseboard_fab2(sch_1):page88_i25:vss(17)" )
			)
			( pin "J9L1.243"
				( objectStatus "@baseboard_fab2_lib.baseboard_fab2(sch_1):page88_i25:vss(18)" )
			)
			( pin "J9L1.241"
				( objectStatus "@baseboard_fab2_lib.baseboard_fab2(sch_1):page88_i25:vss(19)" )
			)
			( pin "J9L1.239"
				( objectStatus "@baseboard_fab2_lib.baseboard_fab2(sch_1):page88_i25:vss(20)" )
			)
			( pin "J9L1.202"
				( objectStatus "@baseboard_fab2_lib.baseboard_fab2(sch_1):page88_i25:vss(21)" )
			)
			( pin "J9L1.200"
				( objectStatus "@baseboard_fab2_lib.baseboard_fab2(sch_1):page88_i25:vss(22)" )
			)
			( pin "J9L1.198"
				( objectStatus "@baseboard_fab2_lib.baseboard_fab2(sch_1):page88_i25:vss(23)" )
			)
			( pin "J9L1.195"
				( objectStatus "@baseboard_fab2_lib.baseboard_fab2(sch_1):page88_i25:vss(24)" )
			)
			( pin "J9L1.193"
				( objectStatus "@baseboard_fab2_lib.baseboard_fab2(sch_1):page88_i25:vss(25)" )
			)
			( pin "J9L1.191"
				( objectStatus "@baseboard_fab2_lib.baseboard_fab2(sch_1):page88_i25:vss(26)" )
			)
			( pin "J9L1.189"
				( objectStatus "@baseboard_fab2_lib.baseboard_fab2(sch_1):page88_i25:vss(27)" )
			)
			( pin "J9L1.187"
				( objectStatus "@baseboard_fab2_lib.baseboard_fab2(sch_1):page88_i25:vss(28)" )
			)
			( pin "J9L1.184"
				( objectStatus "@baseboard_fab2_lib.baseboard_fab2(sch_1):page88_i25:vss(29)" )
			)
			( pin "J9L1.182"
				( objectStatus "@baseboard_fab2_lib.baseboard_fab2(sch_1):page88_i25:vss(30)" )
			)
			( pin "J9L1.180"
				( objectStatus "@baseboard_fab2_lib.baseboard_fab2(sch_1):page88_i25:vss(31)" )
			)
			( pin "J9L1.178"
				( objectStatus "@baseboard_fab2_lib.baseboard_fab2(sch_1):page88_i25:vss(32)" )
			)
			( pin "J9L1.176"
				( objectStatus "@baseboard_fab2_lib.baseboard_fab2(sch_1):page88_i25:vss(33)" )
			)
			( pin "J9L1.173"
				( objectStatus "@baseboard_fab2_lib.baseboard_fab2(sch_1):page88_i25:vss(34)" )
			)
			( pin "J9L1.171"
				( objectStatus "@baseboard_fab2_lib.baseboard_fab2(sch_1):page88_i25:vss(35)" )
			)
			( pin "J9L1.169"
				( objectStatus "@baseboard_fab2_lib.baseboard_fab2(sch_1):page88_i25:vss(36)" )
			)
			( pin "J9L1.167"
				( objectStatus "@baseboard_fab2_lib.baseboard_fab2(sch_1):page88_i25:vss(37)" )
			)
			( pin "J9L1.165"
				( objectStatus "@baseboard_fab2_lib.baseboard_fab2(sch_1):page88_i25:vss(38)" )
			)
			( pin "J9L1.162"
				( objectStatus "@baseboard_fab2_lib.baseboard_fab2(sch_1):page88_i25:vss(39)" )
			)
			( pin "J9L1.160"
				( objectStatus "@baseboard_fab2_lib.baseboard_fab2(sch_1):page88_i25:vss(40)" )
			)
			( pin "J9L1.158"
				( objectStatus "@baseboard_fab2_lib.baseboard_fab2(sch_1):page88_i25:vss(41)" )
			)
			( pin "J9L1.156"
				( objectStatus "@baseboard_fab2_lib.baseboard_fab2(sch_1):page88_i25:vss(42)" )
			)
			( pin "J9L1.154"
				( objectStatus "@baseboard_fab2_lib.baseboard_fab2(sch_1):page88_i25:vss(43)" )
			)
			( pin "J9L1.151"
				( objectStatus "@baseboard_fab2_lib.baseboard_fab2(sch_1):page88_i25:vss(44)" )
			)
			( pin "J9L1.149"
				( objectStatus "@baseboard_fab2_lib.baseboard_fab2(sch_1):page88_i25:vss(45)" )
			)
			( pin "J9L1.147"
				( objectStatus "@baseboard_fab2_lib.baseboard_fab2(sch_1):page88_i25:vss(46)" )
			)
			( pin "J9L1.138"
				( objectStatus "@baseboard_fab2_lib.baseboard_fab2(sch_1):page88_i25:vss(47)" )
			)
			( pin "J9L1.136"
				( objectStatus "@baseboard_fab2_lib.baseboard_fab2(sch_1):page88_i25:vss(48)" )
			)
			( pin "J9L1.134"
				( objectStatus "@baseboard_fab2_lib.baseboard_fab2(sch_1):page88_i25:vss(49)" )
			)
			( pin "J9L1.131"
				( objectStatus "@baseboard_fab2_lib.baseboard_fab2(sch_1):page88_i25:vss(50)" )
			)
			( pin "J9L1.129"
				( objectStatus "@baseboard_fab2_lib.baseboard_fab2(sch_1):page88_i25:vss(51)" )
			)
			( pin "J9L1.127"
				( objectStatus "@baseboard_fab2_lib.baseboard_fab2(sch_1):page88_i25:vss(52)" )
			)
			( pin "J9L1.125"
				( objectStatus "@baseboard_fab2_lib.baseboard_fab2(sch_1):page88_i25:vss(53)" )
			)
			( pin "J9L1.123"
				( objectStatus "@baseboard_fab2_lib.baseboard_fab2(sch_1):page88_i25:vss(54)" )
			)
			( pin "J9L1.120"
				( objectStatus "@baseboard_fab2_lib.baseboard_fab2(sch_1):page88_i25:vss(55)" )
			)
			( pin "J9L1.118"
				( objectStatus "@baseboard_fab2_lib.baseboard_fab2(sch_1):page88_i25:vss(56)" )
			)
			( pin "J9L1.116"
				( objectStatus "@baseboard_fab2_lib.baseboard_fab2(sch_1):page88_i25:vss(57)" )
			)
			( pin "J9L1.114"
				( objectStatus "@baseboard_fab2_lib.baseboard_fab2(sch_1):page88_i25:vss(58)" )
			)
			( pin "J9L1.112"
				( objectStatus "@baseboard_fab2_lib.baseboard_fab2(sch_1):page88_i25:vss(59)" )
			)
			( pin "J9L1.109"
				( objectStatus "@baseboard_fab2_lib.baseboard_fab2(sch_1):page88_i25:vss(60)" )
			)
			( pin "J9L1.107"
				( objectStatus "@baseboard_fab2_lib.baseboard_fab2(sch_1):page88_i25:vss(61)" )
			)
			( pin "J9L1.105"
				( objectStatus "@baseboard_fab2_lib.baseboard_fab2(sch_1):page88_i25:vss(62)" )
			)
			( pin "J9L1.103"
				( objectStatus "@baseboard_fab2_lib.baseboard_fab2(sch_1):page88_i25:vss(63)" )
			)
			( pin "J9L1.101"
				( objectStatus "@baseboard_fab2_lib.baseboard_fab2(sch_1):page88_i25:vss(64)" )
			)
			( pin "J9L1.98"
				( objectStatus "@baseboard_fab2_lib.baseboard_fab2(sch_1):page88_i25:vss(65)" )
			)
			( pin "J9L1.96"
				( objectStatus "@baseboard_fab2_lib.baseboard_fab2(sch_1):page88_i25:vss(66)" )
			)
			( pin "J9L1.94"
				( objectStatus "@baseboard_fab2_lib.baseboard_fab2(sch_1):page88_i25:vss(67)" )
			)
			( pin "J9L1.57"
				( objectStatus "@baseboard_fab2_lib.baseboard_fab2(sch_1):page88_i25:vss(68)" )
			)
			( pin "J9L1.55"
				( objectStatus "@baseboard_fab2_lib.baseboard_fab2(sch_1):page88_i25:vss(69)" )
			)
			( pin "J9L1.53"
				( objectStatus "@baseboard_fab2_lib.baseboard_fab2(sch_1):page88_i25:vss(70)" )
			)
			( pin "J9L1.50"
				( objectStatus "@baseboard_fab2_lib.baseboard_fab2(sch_1):page88_i25:vss(71)" )
			)
			( pin "J9L1.48"
				( objectStatus "@baseboard_fab2_lib.baseboard_fab2(sch_1):page88_i25:vss(72)" )
			)
			( pin "J9L1.46"
				( objectStatus "@baseboard_fab2_lib.baseboard_fab2(sch_1):page88_i25:vss(73)" )
			)
			( pin "J9L1.44"
				( objectStatus "@baseboard_fab2_lib.baseboard_fab2(sch_1):page88_i25:vss(74)" )
			)
			( pin "J9L1.42"
				( objectStatus "@baseboard_fab2_lib.baseboard_fab2(sch_1):page88_i25:vss(75)" )
			)
			( pin "J9L1.39"
				( objectStatus "@baseboard_fab2_lib.baseboard_fab2(sch_1):page88_i25:vss(76)" )
			)
			( pin "J9L1.37"
				( objectStatus "@baseboard_fab2_lib.baseboard_fab2(sch_1):page88_i25:vss(77)" )
			)
			( pin "J9L1.35"
				( objectStatus "@baseboard_fab2_lib.baseboard_fab2(sch_1):page88_i25:vss(78)" )
			)
			( pin "J9L1.33"
				( objectStatus "@baseboard_fab2_lib.baseboard_fab2(sch_1):page88_i25:vss(79)" )
			)
			( pin "J9L1.31"
				( objectStatus "@baseboard_fab2_lib.baseboard_fab2(sch_1):page88_i25:vss(80)" )
			)
			( pin "J9L1.28"
				( objectStatus "@baseboard_fab2_lib.baseboard_fab2(sch_1):page88_i25:vss(81)" )
			)
			( pin "J9L1.26"
				( objectStatus "@baseboard_fab2_lib.baseboard_fab2(sch_1):page88_i25:vss(82)" )
			)
			( pin "J9L1.24"
				( objectStatus "@baseboard_fab2_lib.baseboard_fab2(sch_1):page88_i25:vss(83)" )
			)
			( pin "J9L1.22"
				( objectStatus "@baseboard_fab2_lib.baseboard_fab2(sch_1):page88_i25:vss(84)" )
			)
			( pin "J9L1.20"
				( objectStatus "@baseboard_fab2_lib.baseboard_fab2(sch_1):page88_i25:vss(85)" )
			)
			( pin "J9L1.17"
				( objectStatus "@baseboard_fab2_lib.baseboard_fab2(sch_1):page88_i25:vss(86)" )
			)
			( pin "J9L1.15"
				( objectStatus "@baseboard_fab2_lib.baseboard_fab2(sch_1):page88_i25:vss(87)" )
			)
			( pin "J9L1.13"
				( objectStatus "@baseboard_fab2_lib.baseboard_fab2(sch_1):page88_i25:vss(88)" )
			)
			( pin "J9L1.11"
				( objectStatus "@baseboard_fab2_lib.baseboard_fab2(sch_1):page88_i25:vss(89)" )
			)
			( pin "J9L1.9"
				( objectStatus "@baseboard_fab2_lib.baseboard_fab2(sch_1):page88_i25:vss(90)" )
			)
			( pin "J9L1.6"
				( objectStatus "@baseboard_fab2_lib.baseboard_fab2(sch_1):page88_i25:vss(91)" )
			)
			( pin "J9L1.4"
				( objectStatus "@baseboard_fab2_lib.baseboard_fab2(sch_1):page88_i25:vss(92)" )
			)
			( pin "J9L1.2"
				( objectStatus "@baseboard_fab2_lib.baseboard_fab2(sch_1):page88_i25:vss(93)" )
			)
			( pin "J9L1.152"
				( objectStatus "@baseboard_fab2_lib.baseboard_fab2(sch_1):page88_i87:dqs0n" )
			)
			( pin "J9L1.153"
				( objectStatus "@baseboard_fab2_lib.baseboard_fab2(sch_1):page88_i87:dqs0p" )
			)
			( pin "J9L1.163"
				( objectStatus "@baseboard_fab2_lib.baseboard_fab2(sch_1):page88_i87:dqs1n" )
			)
			( pin "J9L1.164"
				( objectStatus "@baseboard_fab2_lib.baseboard_fab2(sch_1):page88_i87:dqs1p" )
			)
			( pin "J9L1.174"
				( objectStatus "@baseboard_fab2_lib.baseboard_fab2(sch_1):page88_i87:dqs2n" )
			)
			( pin "J9L1.175"
				( objectStatus "@baseboard_fab2_lib.baseboard_fab2(sch_1):page88_i87:dqs2p" )
			)
			( pin "J9L1.185"
				( objectStatus "@baseboard_fab2_lib.baseboard_fab2(sch_1):page88_i87:dqs3n" )
			)
			( pin "J9L1.186"
				( objectStatus "@baseboard_fab2_lib.baseboard_fab2(sch_1):page88_i87:dqs3p" )
			)
			( pin "J9L1.244"
				( objectStatus "@baseboard_fab2_lib.baseboard_fab2(sch_1):page88_i87:dqs4n" )
			)
			( pin "J9L1.245"
				( objectStatus "@baseboard_fab2_lib.baseboard_fab2(sch_1):page88_i87:dqs4p" )
			)
			( pin "J9L1.255"
				( objectStatus "@baseboard_fab2_lib.baseboard_fab2(sch_1):page88_i87:dqs5n" )
			)
			( pin "J9L1.256"
				( objectStatus "@baseboard_fab2_lib.baseboard_fab2(sch_1):page88_i87:dqs5p" )
			)
			( pin "J9L1.266"
				( objectStatus "@baseboard_fab2_lib.baseboard_fab2(sch_1):page88_i87:dqs6n" )
			)
			( pin "J9L1.267"
				( objectStatus "@baseboard_fab2_lib.baseboard_fab2(sch_1):page88_i87:dqs6p" )
			)
			( pin "J9L1.277"
				( objectStatus "@baseboard_fab2_lib.baseboard_fab2(sch_1):page88_i87:dqs7n" )
			)
			( pin "J9L1.278"
				( objectStatus "@baseboard_fab2_lib.baseboard_fab2(sch_1):page88_i87:dqs7p" )
			)
			( pin "J9L1.196"
				( objectStatus "@baseboard_fab2_lib.baseboard_fab2(sch_1):page88_i87:dqs8n" )
			)
			( pin "J9L1.197"
				( objectStatus "@baseboard_fab2_lib.baseboard_fab2(sch_1):page88_i87:dqs8p" )
			)
			( pin "J9L1.8"
				( objectStatus "@baseboard_fab2_lib.baseboard_fab2(sch_1):page88_i87:dqs9n" )
			)
			( pin "J9L1.7"
				( objectStatus "@baseboard_fab2_lib.baseboard_fab2(sch_1):page88_i87:dqs9p" )
			)
			( pin "J9L1.19"
				( objectStatus "@baseboard_fab2_lib.baseboard_fab2(sch_1):page88_i87:dqs10n" )
			)
			( pin "J9L1.18"
				( objectStatus "@baseboard_fab2_lib.baseboard_fab2(sch_1):page88_i87:dqs10p" )
			)
			( pin "J9L1.30"
				( objectStatus "@baseboard_fab2_lib.baseboard_fab2(sch_1):page88_i87:dqs11n" )
			)
			( pin "J9L1.29"
				( objectStatus "@baseboard_fab2_lib.baseboard_fab2(sch_1):page88_i87:dqs11p" )
			)
			( pin "J9L1.41"
				( objectStatus "@baseboard_fab2_lib.baseboard_fab2(sch_1):page88_i87:dqs12n" )
			)
			( pin "J9L1.40"
				( objectStatus "@baseboard_fab2_lib.baseboard_fab2(sch_1):page88_i87:dqs12p" )
			)
			( pin "J9L1.100"
				( objectStatus "@baseboard_fab2_lib.baseboard_fab2(sch_1):page88_i87:dqs13n" )
			)
			( pin "J9L1.99"
				( objectStatus "@baseboard_fab2_lib.baseboard_fab2(sch_1):page88_i87:dqs13p" )
			)
			( pin "J9L1.111"
				( objectStatus "@baseboard_fab2_lib.baseboard_fab2(sch_1):page88_i87:dqs14n" )
			)
			( pin "J9L1.110"
				( objectStatus "@baseboard_fab2_lib.baseboard_fab2(sch_1):page88_i87:dqs14p" )
			)
			( pin "J9L1.122"
				( objectStatus "@baseboard_fab2_lib.baseboard_fab2(sch_1):page88_i87:dqs15n" )
			)
			( pin "J9L1.121"
				( objectStatus "@baseboard_fab2_lib.baseboard_fab2(sch_1):page88_i87:dqs15p" )
			)
			( pin "J9L1.133"
				( objectStatus "@baseboard_fab2_lib.baseboard_fab2(sch_1):page88_i87:dqs16n" )
			)
			( pin "J9L1.132"
				( objectStatus "@baseboard_fab2_lib.baseboard_fab2(sch_1):page88_i87:dqs16p" )
			)
			( pin "J9L1.52"
				( objectStatus "@baseboard_fab2_lib.baseboard_fab2(sch_1):page88_i87:dqs17n" )
			)
			( pin "J9L1.51"
				( objectStatus "@baseboard_fab2_lib.baseboard_fab2(sch_1):page88_i87:dqs17p" )
			)
			( pin "J9L1.79"
				( objectStatus "@baseboard_fab2_lib.baseboard_fab2(sch_1):page88_i111:a0" )
			)
			( pin "J9L1.72"
				( objectStatus "@baseboard_fab2_lib.baseboard_fab2(sch_1):page88_i111:a1" )
			)
			( pin "J9L1.216"
				( objectStatus "@baseboard_fab2_lib.baseboard_fab2(sch_1):page88_i111:a2" )
			)
			( pin "J9L1.71"
				( objectStatus "@baseboard_fab2_lib.baseboard_fab2(sch_1):page88_i111:a3" )
			)
			( pin "J9L1.214"
				( objectStatus "@baseboard_fab2_lib.baseboard_fab2(sch_1):page88_i111:a4" )
			)
			( pin "J9L1.213"
				( objectStatus "@baseboard_fab2_lib.baseboard_fab2(sch_1):page88_i111:a5" )
			)
			( pin "J9L1.69"
				( objectStatus "@baseboard_fab2_lib.baseboard_fab2(sch_1):page88_i111:a6" )
			)
			( pin "J9L1.211"
				( objectStatus "@baseboard_fab2_lib.baseboard_fab2(sch_1):page88_i111:a7" )
			)
			( pin "J9L1.68"
				( objectStatus "@baseboard_fab2_lib.baseboard_fab2(sch_1):page88_i111:a8" )
			)
			( pin "J9L1.66"
				( objectStatus "@baseboard_fab2_lib.baseboard_fab2(sch_1):page88_i111:a9" )
			)
			( pin "J9L1.225"
				( objectStatus "@baseboard_fab2_lib.baseboard_fab2(sch_1):page88_i111:a10" )
			)
			( pin "J9L1.210"
				( objectStatus "@baseboard_fab2_lib.baseboard_fab2(sch_1):page88_i111:a11" )
			)
			( pin "J9L1.65"
				( objectStatus "@baseboard_fab2_lib.baseboard_fab2(sch_1):page88_i111:a12" )
			)
			( pin "J9L1.232"
				( objectStatus "@baseboard_fab2_lib.baseboard_fab2(sch_1):page88_i111:a13" )
			)
			( pin "J9L1.228"
				( objectStatus "@baseboard_fab2_lib.baseboard_fab2(sch_1):page88_i111:a14_we_n" )
			)
			( pin "J9L1.86"
				( objectStatus "@baseboard_fab2_lib.baseboard_fab2(sch_1):page88_i111:a15_cas_n" )
			)
			( pin "J9L1.82"
				( objectStatus "@baseboard_fab2_lib.baseboard_fab2(sch_1):page88_i111:a16_ras_n" )
			)
			( pin "J9L1.234"
				( objectStatus "@baseboard_fab2_lib.baseboard_fab2(sch_1):page88_i111:a17" )
			)
			( pin "J9L1.62"
				( objectStatus "@baseboard_fab2_lib.baseboard_fab2(sch_1):page88_i111:act_n" )
			)
			( pin "J9L1.208"
				( objectStatus "@baseboard_fab2_lib.baseboard_fab2(sch_1):page88_i111:alert_n" )
			)
			( pin "J9L1.81"
				( objectStatus "@baseboard_fab2_lib.baseboard_fab2(sch_1):page88_i111:ba(0)" )
			)
			( pin "J9L1.224"
				( objectStatus "@baseboard_fab2_lib.baseboard_fab2(sch_1):page88_i111:ba(1)" )
			)
			( pin "J9L1.63"
				( objectStatus "@baseboard_fab2_lib.baseboard_fab2(sch_1):page88_i111:bg(0)" )
			)
			( pin "J9L1.207"
				( objectStatus "@baseboard_fab2_lib.baseboard_fab2(sch_1):page88_i111:bg(1)" )
			)
			( pin "J9L1.235"
				( objectStatus "@baseboard_fab2_lib.baseboard_fab2(sch_1):page88_i111:c(2)" )
			)
			( pin "J9L1.49"
				( objectStatus "@baseboard_fab2_lib.baseboard_fab2(sch_1):page88_i111:cb(0)" )
			)
			( pin "J9L1.194"
				( objectStatus "@baseboard_fab2_lib.baseboard_fab2(sch_1):page88_i111:cb(1)" )
			)
			( pin "J9L1.56"
				( objectStatus "@baseboard_fab2_lib.baseboard_fab2(sch_1):page88_i111:cb(2)" )
			)
			( pin "J9L1.201"
				( objectStatus "@baseboard_fab2_lib.baseboard_fab2(sch_1):page88_i111:cb(3)" )
			)
			( pin "J9L1.47"
				( objectStatus "@baseboard_fab2_lib.baseboard_fab2(sch_1):page88_i111:cb(4)" )
			)
			( pin "J9L1.192"
				( objectStatus "@baseboard_fab2_lib.baseboard_fab2(sch_1):page88_i111:cb(5)" )
			)
			( pin "J9L1.54"
				( objectStatus "@baseboard_fab2_lib.baseboard_fab2(sch_1):page88_i111:cb(6)" )
			)
			( pin "J9L1.199"
				( objectStatus "@baseboard_fab2_lib.baseboard_fab2(sch_1):page88_i111:cb(7)" )
			)
			( pin "J9L1.75"
				( objectStatus "@baseboard_fab2_lib.baseboard_fab2(sch_1):page88_i111:ck0n" )
			)
			( pin "J9L1.74"
				( objectStatus "@baseboard_fab2_lib.baseboard_fab2(sch_1):page88_i111:ck0p" )
			)
			( pin "J9L1.219"
				( objectStatus "@baseboard_fab2_lib.baseboard_fab2(sch_1):page88_i111:ck1n" )
			)
			( pin "J9L1.218"
				( objectStatus "@baseboard_fab2_lib.baseboard_fab2(sch_1):page88_i111:ck1p" )
			)
			( pin "J9L1.60"
				( objectStatus "@baseboard_fab2_lib.baseboard_fab2(sch_1):page88_i111:cke(0)" )
			)
			( pin "J9L1.203"
				( objectStatus "@baseboard_fab2_lib.baseboard_fab2(sch_1):page88_i111:cke(1)" )
			)
			( pin "J9L1.5"
				( objectStatus "@baseboard_fab2_lib.baseboard_fab2(sch_1):page88_i111:dq(0)" )
			)
			( pin "J9L1.150"
				( objectStatus "@baseboard_fab2_lib.baseboard_fab2(sch_1):page88_i111:dq(1)" )
			)
			( pin "J9L1.12"
				( objectStatus "@baseboard_fab2_lib.baseboard_fab2(sch_1):page88_i111:dq(2)" )
			)
			( pin "J9L1.157"
				( objectStatus "@baseboard_fab2_lib.baseboard_fab2(sch_1):page88_i111:dq(3)" )
			)
			( pin "J9L1.3"
				( objectStatus "@baseboard_fab2_lib.baseboard_fab2(sch_1):page88_i111:dq(4)" )
			)
			( pin "J9L1.148"
				( objectStatus "@baseboard_fab2_lib.baseboard_fab2(sch_1):page88_i111:dq(5)" )
			)
			( pin "J9L1.10"
				( objectStatus "@baseboard_fab2_lib.baseboard_fab2(sch_1):page88_i111:dq(6)" )
			)
			( pin "J9L1.155"
				( objectStatus "@baseboard_fab2_lib.baseboard_fab2(sch_1):page88_i111:dq(7)" )
			)
			( pin "J9L1.16"
				( objectStatus "@baseboard_fab2_lib.baseboard_fab2(sch_1):page88_i111:dq(8)" )
			)
			( pin "J9L1.161"
				( objectStatus "@baseboard_fab2_lib.baseboard_fab2(sch_1):page88_i111:dq(9)" )
			)
			( pin "J9L1.23"
				( objectStatus "@baseboard_fab2_lib.baseboard_fab2(sch_1):page88_i111:dq(10)" )
			)
			( pin "J9L1.168"
				( objectStatus "@baseboard_fab2_lib.baseboard_fab2(sch_1):page88_i111:dq(11)" )
			)
			( pin "J9L1.14"
				( objectStatus "@baseboard_fab2_lib.baseboard_fab2(sch_1):page88_i111:dq(12)" )
			)
			( pin "J9L1.159"
				( objectStatus "@baseboard_fab2_lib.baseboard_fab2(sch_1):page88_i111:dq(13)" )
			)
			( pin "J9L1.21"
				( objectStatus "@baseboard_fab2_lib.baseboard_fab2(sch_1):page88_i111:dq(14)" )
			)
			( pin "J9L1.166"
				( objectStatus "@baseboard_fab2_lib.baseboard_fab2(sch_1):page88_i111:dq(15)" )
			)
			( pin "J9L1.27"
				( objectStatus "@baseboard_fab2_lib.baseboard_fab2(sch_1):page88_i111:dq(16)" )
			)
			( pin "J9L1.172"
				( objectStatus "@baseboard_fab2_lib.baseboard_fab2(sch_1):page88_i111:dq(17)" )
			)
			( pin "J9L1.34"
				( objectStatus "@baseboard_fab2_lib.baseboard_fab2(sch_1):page88_i111:dq(18)" )
			)
			( pin "J9L1.179"
				( objectStatus "@baseboard_fab2_lib.baseboard_fab2(sch_1):page88_i111:dq(19)" )
			)
			( pin "J9L1.25"
				( objectStatus "@baseboard_fab2_lib.baseboard_fab2(sch_1):page88_i111:dq(20)" )
			)
			( pin "J9L1.170"
				( objectStatus "@baseboard_fab2_lib.baseboard_fab2(sch_1):page88_i111:dq(21)" )
			)
			( pin "J9L1.32"
				( objectStatus "@baseboard_fab2_lib.baseboard_fab2(sch_1):page88_i111:dq(22)" )
			)
			( pin "J9L1.177"
				( objectStatus "@baseboard_fab2_lib.baseboard_fab2(sch_1):page88_i111:dq(23)" )
			)
			( pin "J9L1.38"
				( objectStatus "@baseboard_fab2_lib.baseboard_fab2(sch_1):page88_i111:dq(24)" )
			)
			( pin "J9L1.183"
				( objectStatus "@baseboard_fab2_lib.baseboard_fab2(sch_1):page88_i111:dq(25)" )
			)
			( pin "J9L1.45"
				( objectStatus "@baseboard_fab2_lib.baseboard_fab2(sch_1):page88_i111:dq(26)" )
			)
			( pin "J9L1.190"
				( objectStatus "@baseboard_fab2_lib.baseboard_fab2(sch_1):page88_i111:dq(27)" )
			)
			( pin "J9L1.36"
				( objectStatus "@baseboard_fab2_lib.baseboard_fab2(sch_1):page88_i111:dq(28)" )
			)
			( pin "J9L1.181"
				( objectStatus "@baseboard_fab2_lib.baseboard_fab2(sch_1):page88_i111:dq(29)" )
			)
			( pin "J9L1.43"
				( objectStatus "@baseboard_fab2_lib.baseboard_fab2(sch_1):page88_i111:dq(30)" )
			)
			( pin "J9L1.188"
				( objectStatus "@baseboard_fab2_lib.baseboard_fab2(sch_1):page88_i111:dq(31)" )
			)
			( pin "J9L1.97"
				( objectStatus "@baseboard_fab2_lib.baseboard_fab2(sch_1):page88_i111:dq(32)" )
			)
			( pin "J9L1.242"
				( objectStatus "@baseboard_fab2_lib.baseboard_fab2(sch_1):page88_i111:dq(33)" )
			)
			( pin "J9L1.104"
				( objectStatus "@baseboard_fab2_lib.baseboard_fab2(sch_1):page88_i111:dq(34)" )
			)
			( pin "J9L1.249"
				( objectStatus "@baseboard_fab2_lib.baseboard_fab2(sch_1):page88_i111:dq(35)" )
			)
			( pin "J9L1.95"
				( objectStatus "@baseboard_fab2_lib.baseboard_fab2(sch_1):page88_i111:dq(36)" )
			)
			( pin "J9L1.240"
				( objectStatus "@baseboard_fab2_lib.baseboard_fab2(sch_1):page88_i111:dq(37)" )
			)
			( pin "J9L1.102"
				( objectStatus "@baseboard_fab2_lib.baseboard_fab2(sch_1):page88_i111:dq(38)" )
			)
			( pin "J9L1.247"
				( objectStatus "@baseboard_fab2_lib.baseboard_fab2(sch_1):page88_i111:dq(39)" )
			)
			( pin "J9L1.108"
				( objectStatus "@baseboard_fab2_lib.baseboard_fab2(sch_1):page88_i111:dq(40)" )
			)
			( pin "J9L1.253"
				( objectStatus "@baseboard_fab2_lib.baseboard_fab2(sch_1):page88_i111:dq(41)" )
			)
			( pin "J9L1.115"
				( objectStatus "@baseboard_fab2_lib.baseboard_fab2(sch_1):page88_i111:dq(42)" )
			)
			( pin "J9L1.260"
				( objectStatus "@baseboard_fab2_lib.baseboard_fab2(sch_1):page88_i111:dq(43)" )
			)
			( pin "J9L1.106"
				( objectStatus "@baseboard_fab2_lib.baseboard_fab2(sch_1):page88_i111:dq(44)" )
			)
			( pin "J9L1.251"
				( objectStatus "@baseboard_fab2_lib.baseboard_fab2(sch_1):page88_i111:dq(45)" )
			)
			( pin "J9L1.113"
				( objectStatus "@baseboard_fab2_lib.baseboard_fab2(sch_1):page88_i111:dq(46)" )
			)
			( pin "J9L1.258"
				( objectStatus "@baseboard_fab2_lib.baseboard_fab2(sch_1):page88_i111:dq(47)" )
			)
			( pin "J9L1.119"
				( objectStatus "@baseboard_fab2_lib.baseboard_fab2(sch_1):page88_i111:dq(48)" )
			)
			( pin "J9L1.264"
				( objectStatus "@baseboard_fab2_lib.baseboard_fab2(sch_1):page88_i111:dq(49)" )
			)
			( pin "J9L1.126"
				( objectStatus "@baseboard_fab2_lib.baseboard_fab2(sch_1):page88_i111:dq(50)" )
			)
			( pin "J9L1.271"
				( objectStatus "@baseboard_fab2_lib.baseboard_fab2(sch_1):page88_i111:dq(51)" )
			)
			( pin "J9L1.117"
				( objectStatus "@baseboard_fab2_lib.baseboard_fab2(sch_1):page88_i111:dq(52)" )
			)
			( pin "J9L1.262"
				( objectStatus "@baseboard_fab2_lib.baseboard_fab2(sch_1):page88_i111:dq(53)" )
			)
			( pin "J9L1.124"
				( objectStatus "@baseboard_fab2_lib.baseboard_fab2(sch_1):page88_i111:dq(54)" )
			)
			( pin "J9L1.269"
				( objectStatus "@baseboard_fab2_lib.baseboard_fab2(sch_1):page88_i111:dq(55)" )
			)
			( pin "J9L1.130"
				( objectStatus "@baseboard_fab2_lib.baseboard_fab2(sch_1):page88_i111:dq(56)" )
			)
			( pin "J9L1.275"
				( objectStatus "@baseboard_fab2_lib.baseboard_fab2(sch_1):page88_i111:dq(57)" )
			)
			( pin "J9L1.137"
				( objectStatus "@baseboard_fab2_lib.baseboard_fab2(sch_1):page88_i111:dq(58)" )
			)
			( pin "J9L1.282"
				( objectStatus "@baseboard_fab2_lib.baseboard_fab2(sch_1):page88_i111:dq(59)" )
			)
			( pin "J9L1.128"
				( objectStatus "@baseboard_fab2_lib.baseboard_fab2(sch_1):page88_i111:dq(60)" )
			)
			( pin "J9L1.273"
				( objectStatus "@baseboard_fab2_lib.baseboard_fab2(sch_1):page88_i111:dq(61)" )
			)
			( pin "J9L1.135"
				( objectStatus "@baseboard_fab2_lib.baseboard_fab2(sch_1):page88_i111:dq(62)" )
			)
			( pin "J9L1.280"
				( objectStatus "@baseboard_fab2_lib.baseboard_fab2(sch_1):page88_i111:dq(63)" )
			)
			( pin "J9L1.78"
				( objectStatus "@baseboard_fab2_lib.baseboard_fab2(sch_1):page88_i111:event_n" )
			)
			( pin "J9L1.87"
				( objectStatus "@baseboard_fab2_lib.baseboard_fab2(sch_1):page88_i111:odt(0)" )
			)
			( pin "J9L1.91"
				( objectStatus "@baseboard_fab2_lib.baseboard_fab2(sch_1):page88_i111:odt(1)" )
			)
			( pin "J9L1.222"
				( objectStatus "@baseboard_fab2_lib.baseboard_fab2(sch_1):page88_i111:par" )
			)
			( pin "J9L1.58"
				( objectStatus "@baseboard_fab2_lib.baseboard_fab2(sch_1):page88_i111:reset_n" )
			)
			( pin "J9L1.205"
				( objectStatus "@baseboard_fab2_lib.baseboard_fab2(sch_1):page88_i111:rfu(0)" )
			)
			( pin "J9L1.227"
				( objectStatus "@baseboard_fab2_lib.baseboard_fab2(sch_1):page88_i111:rfu(1)" )
			)
			( pin "J9L1.144"
				( objectStatus "@baseboard_fab2_lib.baseboard_fab2(sch_1):page88_i111:rfu(2)" )
			)
			( pin "J9L1.84"
				( objectStatus "@baseboard_fab2_lib.baseboard_fab2(sch_1):page88_i111:s0_n" )
			)
			( pin "J9L1.89"
				( objectStatus "@baseboard_fab2_lib.baseboard_fab2(sch_1):page88_i111:s1_n" )
			)
			( pin "J9L1.93"
				( objectStatus "@baseboard_fab2_lib.baseboard_fab2(sch_1):page88_i111:s2_n_c(0)" )
			)
			( pin "J9L1.237"
				( objectStatus "@baseboard_fab2_lib.baseboard_fab2(sch_1):page88_i111:s3_n_c(1)" )
			)
			( pin "J9L1.139"
				( objectStatus "@baseboard_fab2_lib.baseboard_fab2(sch_1):page88_i111:sa(0)" )
			)
			( pin "J9L1.140"
				( objectStatus "@baseboard_fab2_lib.baseboard_fab2(sch_1):page88_i111:sa(1)" )
			)
			( pin "J9L1.238"
				( objectStatus "@baseboard_fab2_lib.baseboard_fab2(sch_1):page88_i111:sa(2)" )
			)
			( pin "J9L1.230"
				( objectStatus "@baseboard_fab2_lib.baseboard_fab2(sch_1):page88_i111:save_n_nc" )
			)
			( pin "J9L1.141"
				( objectStatus "@baseboard_fab2_lib.baseboard_fab2(sch_1):page88_i111:scl" )
			)
			( pin "J9L1.285"
				( objectStatus "@baseboard_fab2_lib.baseboard_fab2(sch_1):page88_i111:sda" )
			)
			( pin "J9L1.284"
				( objectStatus "@baseboard_fab2_lib.baseboard_fab2(sch_1):page88_i111:vddspd" )
			)
			( pin "J9L1.146"
				( objectStatus "@baseboard_fab2_lib.baseboard_fab2(sch_1):page88_i111:vrefca" )
			)
			( pin "J9L1.145"
				( objectStatus "@baseboard_fab2_lib.baseboard_fab2(sch_1):page88_i168:\12v\(0)" )
			)
			( pin "J9L1.1"
				( objectStatus "@baseboard_fab2_lib.baseboard_fab2(sch_1):page88_i168:\12v\(1)" )
			)
			( pin "J9L1.236"
				( objectStatus "@baseboard_fab2_lib.baseboard_fab2(sch_1):page88_i168:vdd(0)" )
			)
			( pin "J9L1.233"
				( objectStatus "@baseboard_fab2_lib.baseboard_fab2(sch_1):page88_i168:vdd(1)" )
			)
			( pin "J9L1.231"
				( objectStatus "@baseboard_fab2_lib.baseboard_fab2(sch_1):page88_i168:vdd(2)" )
			)
			( pin "J9L1.229"
				( objectStatus "@baseboard_fab2_lib.baseboard_fab2(sch_1):page88_i168:vdd(3)" )
			)
			( pin "J9L1.226"
				( objectStatus "@baseboard_fab2_lib.baseboard_fab2(sch_1):page88_i168:vdd(4)" )
			)
			( pin "J9L1.223"
				( objectStatus "@baseboard_fab2_lib.baseboard_fab2(sch_1):page88_i168:vdd(5)" )
			)
			( pin "J9L1.220"
				( objectStatus "@baseboard_fab2_lib.baseboard_fab2(sch_1):page88_i168:vdd(6)" )
			)
			( pin "J9L1.217"
				( objectStatus "@baseboard_fab2_lib.baseboard_fab2(sch_1):page88_i168:vdd(7)" )
			)
			( pin "J9L1.215"
				( objectStatus "@baseboard_fab2_lib.baseboard_fab2(sch_1):page88_i168:vdd(8)" )
			)
			( pin "J9L1.212"
				( objectStatus "@baseboard_fab2_lib.baseboard_fab2(sch_1):page88_i168:vdd(9)" )
			)
			( pin "J9L1.209"
				( objectStatus "@baseboard_fab2_lib.baseboard_fab2(sch_1):page88_i168:vdd(10)" )
			)
			( pin "J9L1.206"
				( objectStatus "@baseboard_fab2_lib.baseboard_fab2(sch_1):page88_i168:vdd(11)" )
			)
			( pin "J9L1.204"
				( objectStatus "@baseboard_fab2_lib.baseboard_fab2(sch_1):page88_i168:vdd(12)" )
			)
			( pin "J9L1.92"
				( objectStatus "@baseboard_fab2_lib.baseboard_fab2(sch_1):page88_i168:vdd(13)" )
			)
			( pin "J9L1.90"
				( objectStatus "@baseboard_fab2_lib.baseboard_fab2(sch_1):page88_i168:vdd(14)" )
			)
			( pin "J9L1.88"
				( objectStatus "@baseboard_fab2_lib.baseboard_fab2(sch_1):page88_i168:vdd(15)" )
			)
			( pin "J9L1.85"
				( objectStatus "@baseboard_fab2_lib.baseboard_fab2(sch_1):page88_i168:vdd(16)" )
			)
			( pin "J9L1.83"
				( objectStatus "@baseboard_fab2_lib.baseboard_fab2(sch_1):page88_i168:vdd(17)" )
			)
			( pin "J9L1.80"
				( objectStatus "@baseboard_fab2_lib.baseboard_fab2(sch_1):page88_i168:vdd(18)" )
			)
			( pin "J9L1.76"
				( objectStatus "@baseboard_fab2_lib.baseboard_fab2(sch_1):page88_i168:vdd(19)" )
			)
			( pin "J9L1.73"
				( objectStatus "@baseboard_fab2_lib.baseboard_fab2(sch_1):page88_i168:vdd(20)" )
			)
			( pin "J9L1.70"
				( objectStatus "@baseboard_fab2_lib.baseboard_fab2(sch_1):page88_i168:vdd(21)" )
			)
			( pin "J9L1.67"
				( objectStatus "@baseboard_fab2_lib.baseboard_fab2(sch_1):page88_i168:vdd(22)" )
			)
			( pin "J9L1.64"
				( objectStatus "@baseboard_fab2_lib.baseboard_fab2(sch_1):page88_i168:vdd(23)" )
			)
			( pin "J9L1.61"
				( objectStatus "@baseboard_fab2_lib.baseboard_fab2(sch_1):page88_i168:vdd(24)" )
			)
			( pin "J9L1.59"
				( objectStatus "@baseboard_fab2_lib.baseboard_fab2(sch_1):page88_i168:vdd(25)" )
			)
			( pin "J9L1.287"
				( objectStatus "@baseboard_fab2_lib.baseboard_fab2(sch_1):page88_i168:vpp(0)" )
			)
			( pin "J9L1.286"
				( objectStatus "@baseboard_fab2_lib.baseboard_fab2(sch_1):page88_i168:vpp(1)" )
			)
			( pin "J9L1.288"
				( objectStatus "@baseboard_fab2_lib.baseboard_fab2(sch_1):page88_i168:vpp(2)" )
			)
			( pin "J9L1.143"
				( objectStatus "@baseboard_fab2_lib.baseboard_fab2(sch_1):page88_i168:vpp(3)" )
			)
			( pin "J9L1.142"
				( objectStatus "@baseboard_fab2_lib.baseboard_fab2(sch_1):page88_i168:vpp(4)" )
			)
			( pin "J9L1.221"
				( objectStatus "@baseboard_fab2_lib.baseboard_fab2(sch_1):page88_i168:vtt(0)" )
			)
			( pin "J9L1.77"
				( objectStatus "@baseboard_fab2_lib.baseboard_fab2(sch_1):page88_i168:vtt(1)" )
			)
			( pin "C9L1.1"
				( objectStatus "@baseboard_fab2_lib.baseboard_fab2(sch_1):page88_i177:a" )
			)
			( pin "C9L1.2"
				( objectStatus "@baseboard_fab2_lib.baseboard_fab2(sch_1):page88_i177:b" )
			)
			( pin "R4T2.1"
				( objectStatus "@baseboard_fab2_lib.baseboard_fab2(sch_1):page89_i1:a" )
			)
			( pin "R4T2.2"
				( objectStatus "@baseboard_fab2_lib.baseboard_fab2(sch_1):page89_i1:b" )
			)
			( pin "R4T1.1"
				( objectStatus "@baseboard_fab2_lib.baseboard_fab2(sch_1):page89_i2:a" )
			)
			( pin "R4T1.2"
				( objectStatus "@baseboard_fab2_lib.baseboard_fab2(sch_1):page89_i2:b" )
			)
			( pin "R6F4.1"
				( objectStatus "@baseboard_fab2_lib.baseboard_fab2(sch_1):page89_i3:a" )
			)
			( pin "R6F4.2"
				( objectStatus "@baseboard_fab2_lib.baseboard_fab2(sch_1):page89_i3:b" )
			)
			( pin "R6F1.1"
				( objectStatus "@baseboard_fab2_lib.baseboard_fab2(sch_1):page89_i4:a" )
			)
			( pin "R6F1.2"
				( objectStatus "@baseboard_fab2_lib.baseboard_fab2(sch_1):page89_i4:b" )
			)
			( pin "R6F5.1"
				( objectStatus "@baseboard_fab2_lib.baseboard_fab2(sch_1):page89_i5:a" )
			)
			( pin "R6F5.2"
				( objectStatus "@baseboard_fab2_lib.baseboard_fab2(sch_1):page89_i5:b" )
			)
			( pin "R6F2.1"
				( objectStatus "@baseboard_fab2_lib.baseboard_fab2(sch_1):page89_i6:a" )
			)
			( pin "R6F2.2"
				( objectStatus "@baseboard_fab2_lib.baseboard_fab2(sch_1):page89_i6:b" )
			)
			( pin "R6F3.1"
				( objectStatus "@baseboard_fab2_lib.baseboard_fab2(sch_1):page89_i7:a" )
			)
			( pin "R6F3.2"
				( objectStatus "@baseboard_fab2_lib.baseboard_fab2(sch_1):page89_i7:b" )
			)
			( pin "Q1P2.3"
				( objectStatus "@baseboard_fab2_lib.baseboard_fab2(sch_1):page196_i129:drn" )
			)
			( pin "Q1P2.1"
				( objectStatus "@baseboard_fab2_lib.baseboard_fab2(sch_1):page196_i129:gate" )
			)
			( pin "Q1P2.2"
				( objectStatus "@baseboard_fab2_lib.baseboard_fab2(sch_1):page196_i129:src" )
			)
			( pin "R2P12.1"
				( objectStatus "@baseboard_fab2_lib.baseboard_fab2(sch_1):page89_i23:a" )
			)
			( pin "R2P12.2"
				( objectStatus "@baseboard_fab2_lib.baseboard_fab2(sch_1):page89_i23:b" )
			)
			( pin "R8D29.1"
				( objectStatus "@baseboard_fab2_lib.baseboard_fab2(sch_1):page89_i26:a" )
			)
			( pin "R8D29.2"
				( objectStatus "@baseboard_fab2_lib.baseboard_fab2(sch_1):page89_i26:b" )
			)
			( pin "R8D31.1"
				( objectStatus "@baseboard_fab2_lib.baseboard_fab2(sch_1):page89_i27:a" )
			)
			( pin "R8D31.2"
				( objectStatus "@baseboard_fab2_lib.baseboard_fab2(sch_1):page89_i27:b" )
			)
			( pin "R8D30.1"
				( objectStatus "@baseboard_fab2_lib.baseboard_fab2(sch_1):page89_i34:a" )
			)
			( pin "R8D30.2"
				( objectStatus "@baseboard_fab2_lib.baseboard_fab2(sch_1):page89_i34:b" )
			)
			( pin "Q8D1.5"
				( objectStatus "@baseboard_fab2_lib.baseboard_fab2(sch_1):page89_i35:b(0)" )
			)
			( pin "Q8D1.3"
				( objectStatus "@baseboard_fab2_lib.baseboard_fab2(sch_1):page89_i35:c(0)" )
			)
			( pin "Q8D1.4"
				( objectStatus "@baseboard_fab2_lib.baseboard_fab2(sch_1):page89_i35:e(0)" )
			)
			( pin "R3D22.1"
				( objectStatus "@baseboard_fab2_lib.baseboard_fab2(sch_1):page90_i17:a" )
			)
			( pin "R3D22.2"
				( objectStatus "@baseboard_fab2_lib.baseboard_fab2(sch_1):page90_i17:b" )
			)
			( pin "R3D16.1"
				( objectStatus "@baseboard_fab2_lib.baseboard_fab2(sch_1):page90_i24:a" )
			)
			( pin "R3D16.2"
				( objectStatus "@baseboard_fab2_lib.baseboard_fab2(sch_1):page90_i24:b" )
			)
			( pin "R3D23.1"
				( objectStatus "@baseboard_fab2_lib.baseboard_fab2(sch_1):page90_i25:a" )
			)
			( pin "R3D23.2"
				( objectStatus "@baseboard_fab2_lib.baseboard_fab2(sch_1):page90_i25:b" )
			)
			( pin "R3D26.1"
				( objectStatus "@baseboard_fab2_lib.baseboard_fab2(sch_1):page90_i28:a" )
			)
			( pin "R3D26.2"
				( objectStatus "@baseboard_fab2_lib.baseboard_fab2(sch_1):page90_i28:b" )
			)
			( pin "R5D3.1"
				( objectStatus "@baseboard_fab2_lib.baseboard_fab2(sch_1):page90_i29:a" )
			)
			( pin "R5D3.2"
				( objectStatus "@baseboard_fab2_lib.baseboard_fab2(sch_1):page90_i29:b" )
			)
			( pin "R6D7.1"
				( objectStatus "@baseboard_fab2_lib.baseboard_fab2(sch_1):page90_i31:a" )
			)
			( pin "R6D7.2"
				( objectStatus "@baseboard_fab2_lib.baseboard_fab2(sch_1):page90_i31:b" )
			)
			( pin "R6D13.1"
				( objectStatus "@baseboard_fab2_lib.baseboard_fab2(sch_1):page90_i33:a" )
			)
			( pin "R6D13.2"
				( objectStatus "@baseboard_fab2_lib.baseboard_fab2(sch_1):page90_i33:b" )
			)
			( pin "R6D15.1"
				( objectStatus "@baseboard_fab2_lib.baseboard_fab2(sch_1):page90_i48:a" )
			)
			( pin "R6D15.2"
				( objectStatus "@baseboard_fab2_lib.baseboard_fab2(sch_1):page90_i48:b" )
			)
			( pin "R6D10.1"
				( objectStatus "@baseboard_fab2_lib.baseboard_fab2(sch_1):page90_i49:a" )
			)
			( pin "R6D10.2"
				( objectStatus "@baseboard_fab2_lib.baseboard_fab2(sch_1):page90_i49:b" )
			)
			( pin "R6D14.1"
				( objectStatus "@baseboard_fab2_lib.baseboard_fab2(sch_1):page90_i52:a" )
			)
			( pin "R6D14.2"
				( objectStatus "@baseboard_fab2_lib.baseboard_fab2(sch_1):page90_i52:b" )
			)
			( pin "R4P14.1"
				( objectStatus "@baseboard_fab2_lib.baseboard_fab2(sch_1):page90_i53:a" )
			)
			( pin "R4P14.2"
				( objectStatus "@baseboard_fab2_lib.baseboard_fab2(sch_1):page90_i53:b" )
			)
			( pin "R3D24.1"
				( objectStatus "@baseboard_fab2_lib.baseboard_fab2(sch_1):page90_i59:a" )
			)
			( pin "R3D24.2"
				( objectStatus "@baseboard_fab2_lib.baseboard_fab2(sch_1):page90_i59:b" )
			)
			( pin "R3D17.1"
				( objectStatus "@baseboard_fab2_lib.baseboard_fab2(sch_1):page90_i60:a" )
			)
			( pin "R3D17.2"
				( objectStatus "@baseboard_fab2_lib.baseboard_fab2(sch_1):page90_i60:b" )
			)
			( pin "R3D25.1"
				( objectStatus "@baseboard_fab2_lib.baseboard_fab2(sch_1):page90_i66:a" )
			)
			( pin "R3D25.2"
				( objectStatus "@baseboard_fab2_lib.baseboard_fab2(sch_1):page90_i66:b" )
			)
			( pin "R4P6.1"
				( objectStatus "@baseboard_fab2_lib.baseboard_fab2(sch_1):page90_i68:a" )
			)
			( pin "R4P6.2"
				( objectStatus "@baseboard_fab2_lib.baseboard_fab2(sch_1):page90_i68:b" )
			)
			( pin "R2U30.1"
				( objectStatus "@baseboard_fab2_lib.baseboard_fab2(sch_1):page125_i88:a" )
			)
			( pin "R2U30.2"
				( objectStatus "@baseboard_fab2_lib.baseboard_fab2(sch_1):page125_i88:b" )
			)
			( pin "R4P7.1"
				( objectStatus "@baseboard_fab2_lib.baseboard_fab2(sch_1):page90_i72:a" )
			)
			( pin "R4P7.2"
				( objectStatus "@baseboard_fab2_lib.baseboard_fab2(sch_1):page90_i72:b" )
			)
			( pin "R7P15.1"
				( objectStatus "@baseboard_fab2_lib.baseboard_fab2(sch_1):page90_i74:a" )
			)
			( pin "R7P15.2"
				( objectStatus "@baseboard_fab2_lib.baseboard_fab2(sch_1):page90_i74:b" )
			)
			( pin "R7P22.1"
				( objectStatus "@baseboard_fab2_lib.baseboard_fab2(sch_1):page90_i76:a" )
			)
			( pin "R7P22.2"
				( objectStatus "@baseboard_fab2_lib.baseboard_fab2(sch_1):page90_i76:b" )
			)
			( pin "R5P2.1"
				( objectStatus "@baseboard_fab2_lib.baseboard_fab2(sch_1):page90_i79:a" )
			)
			( pin "R5P2.2"
				( objectStatus "@baseboard_fab2_lib.baseboard_fab2(sch_1):page90_i79:b" )
			)
			( pin "R5P3.1"
				( objectStatus "@baseboard_fab2_lib.baseboard_fab2(sch_1):page90_i80:a" )
			)
			( pin "R5P3.2"
				( objectStatus "@baseboard_fab2_lib.baseboard_fab2(sch_1):page90_i80:b" )
			)
			( pin "R6D5.1"
				( objectStatus "@baseboard_fab2_lib.baseboard_fab2(sch_1):page90_i81:a" )
			)
			( pin "R6D5.2"
				( objectStatus "@baseboard_fab2_lib.baseboard_fab2(sch_1):page90_i81:b" )
			)
			( pin "R8P1.1"
				( objectStatus "@baseboard_fab2_lib.baseboard_fab2(sch_1):page90_i85:a" )
			)
			( pin "R8P1.2"
				( objectStatus "@baseboard_fab2_lib.baseboard_fab2(sch_1):page90_i85:b" )
			)
			( pin "R8P2.1"
				( objectStatus "@baseboard_fab2_lib.baseboard_fab2(sch_1):page90_i86:a" )
			)
			( pin "R8P2.2"
				( objectStatus "@baseboard_fab2_lib.baseboard_fab2(sch_1):page90_i86:b" )
			)
			( pin "R3D9.1"
				( objectStatus "@baseboard_fab2_lib.baseboard_fab2(sch_1):page90_i88:a" )
			)
			( pin "R3D9.2"
				( objectStatus "@baseboard_fab2_lib.baseboard_fab2(sch_1):page90_i88:b" )
			)
			( pin "J8B1.1"
				( objectStatus "@baseboard_fab2_lib.baseboard_fab2(sch_1):page91_i1:io1" )
			)
			( pin "J8B1.2"
				( objectStatus "@baseboard_fab2_lib.baseboard_fab2(sch_1):page91_i1:io2" )
			)
			( pin "J8B1.3"
				( objectStatus "@baseboard_fab2_lib.baseboard_fab2(sch_1):page91_i1:io3" )
			)
			( pin "J8B1.4"
				( objectStatus "@baseboard_fab2_lib.baseboard_fab2(sch_1):page91_i1:io4" )
			)
			( pin "J8B1.5"
				( objectStatus "@baseboard_fab2_lib.baseboard_fab2(sch_1):page91_i1:io5" )
			)
			( pin "J8B1.6"
				( objectStatus "@baseboard_fab2_lib.baseboard_fab2(sch_1):page91_i1:io6" )
			)
			( pin "J8B1.7"
				( objectStatus "@baseboard_fab2_lib.baseboard_fab2(sch_1):page91_i1:io7" )
			)
			( pin "J8B1.8"
				( objectStatus "@baseboard_fab2_lib.baseboard_fab2(sch_1):page91_i1:io8" )
			)
			( pin "J8B1.9"
				( objectStatus "@baseboard_fab2_lib.baseboard_fab2(sch_1):page91_i1:io9" )
			)
			( pin "J8B1.10"
				( objectStatus "@baseboard_fab2_lib.baseboard_fab2(sch_1):page91_i1:io10" )
			)
			( pin "J8B1.11"
				( objectStatus "@baseboard_fab2_lib.baseboard_fab2(sch_1):page91_i1:io11" )
			)
			( pin "J8B1.12"
				( objectStatus "@baseboard_fab2_lib.baseboard_fab2(sch_1):page91_i1:io12" )
			)
			( pin "J8B1.13"
				( objectStatus "@baseboard_fab2_lib.baseboard_fab2(sch_1):page91_i1:io13" )
			)
			( pin "J8B1.14"
				( objectStatus "@baseboard_fab2_lib.baseboard_fab2(sch_1):page91_i1:io14" )
			)
			( pin "J8B1.15"
				( objectStatus "@baseboard_fab2_lib.baseboard_fab2(sch_1):page91_i1:io15" )
			)
			( pin "J8B1.16"
				( objectStatus "@baseboard_fab2_lib.baseboard_fab2(sch_1):page91_i1:io16" )
			)
			( pin "J8B1.17"
				( objectStatus "@baseboard_fab2_lib.baseboard_fab2(sch_1):page91_i1:io17" )
			)
			( pin "J8B1.18"
				( objectStatus "@baseboard_fab2_lib.baseboard_fab2(sch_1):page91_i1:io18" )
			)
			( pin "J8B1.19"
				( objectStatus "@baseboard_fab2_lib.baseboard_fab2(sch_1):page91_i1:io19" )
			)
			( pin "J8B1.20"
				( objectStatus "@baseboard_fab2_lib.baseboard_fab2(sch_1):page91_i1:io20" )
			)
			( pin "J8B1.21"
				( objectStatus "@baseboard_fab2_lib.baseboard_fab2(sch_1):page91_i1:io21" )
			)
			( pin "J8B1.22"
				( objectStatus "@baseboard_fab2_lib.baseboard_fab2(sch_1):page91_i1:io22" )
			)
			( pin "J8B1.23"
				( objectStatus "@baseboard_fab2_lib.baseboard_fab2(sch_1):page91_i1:io23" )
			)
			( pin "J8B1.24"
				( objectStatus "@baseboard_fab2_lib.baseboard_fab2(sch_1):page91_i1:io24" )
			)
			( pin "J8B1.MP1"
				( objectStatus "@baseboard_fab2_lib.baseboard_fab2(sch_1):page91_i1:mp1" )
			)
			( pin "J8B1.MP2"
				( objectStatus "@baseboard_fab2_lib.baseboard_fab2(sch_1):page91_i1:mp2" )
			)
			( pin "R8B8.1"
				( objectStatus "@baseboard_fab2_lib.baseboard_fab2(sch_1):page91_i14:a" )
			)
			( pin "R8B8.2"
				( objectStatus "@baseboard_fab2_lib.baseboard_fab2(sch_1):page91_i14:b" )
			)
			( pin "R8B10.1"
				( objectStatus "@baseboard_fab2_lib.baseboard_fab2(sch_1):page91_i16:a" )
			)
			( pin "R8B10.2"
				( objectStatus "@baseboard_fab2_lib.baseboard_fab2(sch_1):page91_i16:b" )
			)
			( pin "R8B16.1"
				( objectStatus "@baseboard_fab2_lib.baseboard_fab2(sch_1):page91_i17:a" )
			)
			( pin "R8B16.2"
				( objectStatus "@baseboard_fab2_lib.baseboard_fab2(sch_1):page91_i17:b" )
			)
			( pin "R8B17.1"
				( objectStatus "@baseboard_fab2_lib.baseboard_fab2(sch_1):page91_i18:a" )
			)
			( pin "R8B17.2"
				( objectStatus "@baseboard_fab2_lib.baseboard_fab2(sch_1):page91_i18:b" )
			)
			( pin "R8B18.1"
				( objectStatus "@baseboard_fab2_lib.baseboard_fab2(sch_1):page91_i20:a" )
			)
			( pin "R8B18.2"
				( objectStatus "@baseboard_fab2_lib.baseboard_fab2(sch_1):page91_i20:b" )
			)
			( pin "R8B19.1"
				( objectStatus "@baseboard_fab2_lib.baseboard_fab2(sch_1):page91_i21:a" )
			)
			( pin "R8B19.2"
				( objectStatus "@baseboard_fab2_lib.baseboard_fab2(sch_1):page91_i21:b" )
			)
			( pin "R8B5.1"
				( objectStatus "@baseboard_fab2_lib.baseboard_fab2(sch_1):page91_i22:a" )
			)
			( pin "R8B5.2"
				( objectStatus "@baseboard_fab2_lib.baseboard_fab2(sch_1):page91_i22:b" )
			)
			( pin "R8B3.1"
				( objectStatus "@baseboard_fab2_lib.baseboard_fab2(sch_1):page91_i24:a" )
			)
			( pin "R8B3.2"
				( objectStatus "@baseboard_fab2_lib.baseboard_fab2(sch_1):page91_i24:b" )
			)
			( pin "R8B13.1"
				( objectStatus "@baseboard_fab2_lib.baseboard_fab2(sch_1):page91_i34:a" )
			)
			( pin "R8B13.2"
				( objectStatus "@baseboard_fab2_lib.baseboard_fab2(sch_1):page91_i34:b" )
			)
			( pin "R8B11.1"
				( objectStatus "@baseboard_fab2_lib.baseboard_fab2(sch_1):page91_i35:a" )
			)
			( pin "R8B11.2"
				( objectStatus "@baseboard_fab2_lib.baseboard_fab2(sch_1):page91_i35:b" )
			)
			( pin "R8B7.1"
				( objectStatus "@baseboard_fab2_lib.baseboard_fab2(sch_1):page91_i36:a" )
			)
			( pin "R8B7.2"
				( objectStatus "@baseboard_fab2_lib.baseboard_fab2(sch_1):page91_i36:b" )
			)
			( pin "R8B6.1"
				( objectStatus "@baseboard_fab2_lib.baseboard_fab2(sch_1):page91_i37:a" )
			)
			( pin "R8B6.2"
				( objectStatus "@baseboard_fab2_lib.baseboard_fab2(sch_1):page91_i37:b" )
			)
			( pin "U3P2.13"
				( objectStatus "@baseboard_fab2_lib.baseboard_fab2(sch_1):page92_i1:a0" )
			)
			( pin "U3P2.12"
				( objectStatus "@baseboard_fab2_lib.baseboard_fab2(sch_1):page92_i1:a1" )
			)
			( pin "U3P2.10"
				( objectStatus "@baseboard_fab2_lib.baseboard_fab2(sch_1):page92_i1:a2" )
			)
			( pin "U3P2.9"
				( objectStatus "@baseboard_fab2_lib.baseboard_fab2(sch_1):page92_i1:a3" )
			)
			( pin "U3P2.2"
				( objectStatus "@baseboard_fab2_lib.baseboard_fab2(sch_1):page92_i1:b0" )
			)
			( pin "U3P2.3"
				( objectStatus "@baseboard_fab2_lib.baseboard_fab2(sch_1):page92_i1:b1" )
			)
			( pin "U3P2.5"
				( objectStatus "@baseboard_fab2_lib.baseboard_fab2(sch_1):page92_i1:b2" )
			)
			( pin "U3P2.6"
				( objectStatus "@baseboard_fab2_lib.baseboard_fab2(sch_1):page92_i1:b3" )
			)
			( pin "U3P2.1"
				( objectStatus "@baseboard_fab2_lib.baseboard_fab2(sch_1):page92_i1:dir" )
			)
			( pin "U3P2.7"
				( objectStatus "@baseboard_fab2_lib.baseboard_fab2(sch_1):page92_i1:gnd(0)" )
			)
			( pin "U3P2.8"
				( objectStatus "@baseboard_fab2_lib.baseboard_fab2(sch_1):page92_i1:gnd(1)" )
			)
			( pin "U3P2.11"
				( objectStatus "@baseboard_fab2_lib.baseboard_fab2(sch_1):page92_i1:gnd(2)" )
			)
			( pin "U3P2.14"
				( objectStatus "@baseboard_fab2_lib.baseboard_fab2(sch_1):page92_i1:vcc" )
			)
			( pin "U3P2.4"
				( objectStatus "@baseboard_fab2_lib.baseboard_fab2(sch_1):page92_i1:vref" )
			)
			( pin "R3P41.1"
				( objectStatus "@baseboard_fab2_lib.baseboard_fab2(sch_1):page92_i9:a" )
			)
			( pin "R3P41.2"
				( objectStatus "@baseboard_fab2_lib.baseboard_fab2(sch_1):page92_i9:b" )
			)
			( pin "R3P46.1"
				( objectStatus "@baseboard_fab2_lib.baseboard_fab2(sch_1):page92_i12:a" )
			)
			( pin "R3P46.2"
				( objectStatus "@baseboard_fab2_lib.baseboard_fab2(sch_1):page92_i12:b" )
			)
			( pin "R3P43.1"
				( objectStatus "@baseboard_fab2_lib.baseboard_fab2(sch_1):page92_i13:a" )
			)
			( pin "R3P43.2"
				( objectStatus "@baseboard_fab2_lib.baseboard_fab2(sch_1):page92_i13:b" )
			)
			( pin "R3P42.1"
				( objectStatus "@baseboard_fab2_lib.baseboard_fab2(sch_1):page92_i14:a" )
			)
			( pin "R3P42.2"
				( objectStatus "@baseboard_fab2_lib.baseboard_fab2(sch_1):page92_i14:b" )
			)
			( pin "R7E2.1"
				( objectStatus "@baseboard_fab2_lib.baseboard_fab2(sch_1):page92_i19:a" )
			)
			( pin "R7E2.2"
				( objectStatus "@baseboard_fab2_lib.baseboard_fab2(sch_1):page92_i19:b" )
			)
			( pin "R7D34.1"
				( objectStatus "@baseboard_fab2_lib.baseboard_fab2(sch_1):page92_i24:a" )
			)
			( pin "R7D34.2"
				( objectStatus "@baseboard_fab2_lib.baseboard_fab2(sch_1):page92_i24:b" )
			)
			( pin "R7D31.1"
				( objectStatus "@baseboard_fab2_lib.baseboard_fab2(sch_1):page92_i29:a" )
			)
			( pin "R7D31.2"
				( objectStatus "@baseboard_fab2_lib.baseboard_fab2(sch_1):page92_i29:b" )
			)
			( pin "R7D29.1"
				( objectStatus "@baseboard_fab2_lib.baseboard_fab2(sch_1):page92_i30:a" )
			)
			( pin "R7D29.2"
				( objectStatus "@baseboard_fab2_lib.baseboard_fab2(sch_1):page92_i30:b" )
			)
			( pin "U7D2.13"
				( objectStatus "@baseboard_fab2_lib.baseboard_fab2(sch_1):page92_i32:a0" )
			)
			( pin "U7D2.12"
				( objectStatus "@baseboard_fab2_lib.baseboard_fab2(sch_1):page92_i32:a1" )
			)
			( pin "U7D2.10"
				( objectStatus "@baseboard_fab2_lib.baseboard_fab2(sch_1):page92_i32:a2" )
			)
			( pin "U7D2.9"
				( objectStatus "@baseboard_fab2_lib.baseboard_fab2(sch_1):page92_i32:a3" )
			)
			( pin "U7D2.2"
				( objectStatus "@baseboard_fab2_lib.baseboard_fab2(sch_1):page92_i32:b0" )
			)
			( pin "U7D2.3"
				( objectStatus "@baseboard_fab2_lib.baseboard_fab2(sch_1):page92_i32:b1" )
			)
			( pin "U7D2.5"
				( objectStatus "@baseboard_fab2_lib.baseboard_fab2(sch_1):page92_i32:b2" )
			)
			( pin "U7D2.6"
				( objectStatus "@baseboard_fab2_lib.baseboard_fab2(sch_1):page92_i32:b3" )
			)
			( pin "U7D2.1"
				( objectStatus "@baseboard_fab2_lib.baseboard_fab2(sch_1):page92_i32:dir" )
			)
			( pin "U7D2.7"
				( objectStatus "@baseboard_fab2_lib.baseboard_fab2(sch_1):page92_i32:gnd(0)" )
			)
			( pin "U7D2.8"
				( objectStatus "@baseboard_fab2_lib.baseboard_fab2(sch_1):page92_i32:gnd(1)" )
			)
			( pin "U7D2.11"
				( objectStatus "@baseboard_fab2_lib.baseboard_fab2(sch_1):page92_i32:gnd(2)" )
			)
			( pin "U7D2.14"
				( objectStatus "@baseboard_fab2_lib.baseboard_fab2(sch_1):page92_i32:vcc" )
			)
			( pin "U7D2.4"
				( objectStatus "@baseboard_fab2_lib.baseboard_fab2(sch_1):page92_i32:vref" )
			)
			( pin "C3P49.1"
				( objectStatus "@baseboard_fab2_lib.baseboard_fab2(sch_1):page92_i37:a" )
			)
			( pin "C3P49.2"
				( objectStatus "@baseboard_fab2_lib.baseboard_fab2(sch_1):page92_i37:b" )
			)
			( pin "R3P49.1"
				( objectStatus "@baseboard_fab2_lib.baseboard_fab2(sch_1):page92_i38:a" )
			)
			( pin "R3P49.2"
				( objectStatus "@baseboard_fab2_lib.baseboard_fab2(sch_1):page92_i38:b" )
			)
			( pin "R1W39.1"
				( objectStatus "@baseboard_fab2_lib.baseboard_fab2(sch_1):page176_i175:a" )
			)
			( pin "R1W39.2"
				( objectStatus "@baseboard_fab2_lib.baseboard_fab2(sch_1):page176_i175:b" )
			)
			( pin "R3R1.1"
				( objectStatus "@baseboard_fab2_lib.baseboard_fab2(sch_1):page92_i46:a" )
			)
			( pin "R3R1.2"
				( objectStatus "@baseboard_fab2_lib.baseboard_fab2(sch_1):page92_i46:b" )
			)
			( pin "R7D32.1"
				( objectStatus "@baseboard_fab2_lib.baseboard_fab2(sch_1):page92_i48:a" )
			)
			( pin "R7D32.2"
				( objectStatus "@baseboard_fab2_lib.baseboard_fab2(sch_1):page92_i48:b" )
			)
			( pin "R2T36.1"
				( objectStatus "@baseboard_fab2_lib.baseboard_fab2(sch_1):page93_i148:\1\" )
			)
			( pin "R2T36.2"
				( objectStatus "@baseboard_fab2_lib.baseboard_fab2(sch_1):page93_i148:\2\" )
			)
			( pin "C7D5.1"
				( objectStatus "@baseboard_fab2_lib.baseboard_fab2(sch_1):page92_i52:a" )
			)
			( pin "C7D5.2"
				( objectStatus "@baseboard_fab2_lib.baseboard_fab2(sch_1):page92_i52:b" )
			)
			( pin "R7D26.1"
				( objectStatus "@baseboard_fab2_lib.baseboard_fab2(sch_1):page92_i54:a" )
			)
			( pin "R7D26.2"
				( objectStatus "@baseboard_fab2_lib.baseboard_fab2(sch_1):page92_i54:b" )
			)
			( pin "R3R3.1"
				( objectStatus "@baseboard_fab2_lib.baseboard_fab2(sch_1):page92_i61:a" )
			)
			( pin "R3R3.2"
				( objectStatus "@baseboard_fab2_lib.baseboard_fab2(sch_1):page92_i61:b" )
			)
			( pin "R6D9.1"
				( objectStatus "@baseboard_fab2_lib.baseboard_fab2(sch_1):page92_i64:a" )
			)
			( pin "R6D9.2"
				( objectStatus "@baseboard_fab2_lib.baseboard_fab2(sch_1):page92_i64:b" )
			)
			( pin "R7P27.1"
				( objectStatus "@baseboard_fab2_lib.baseboard_fab2(sch_1):page92_i65:a" )
			)
			( pin "R7P27.2"
				( objectStatus "@baseboard_fab2_lib.baseboard_fab2(sch_1):page92_i65:b" )
			)
			( pin "R7D28.1"
				( objectStatus "@baseboard_fab2_lib.baseboard_fab2(sch_1):page92_i67:a" )
			)
			( pin "R7D28.2"
				( objectStatus "@baseboard_fab2_lib.baseboard_fab2(sch_1):page92_i67:b" )
			)
			( pin "R7D27.1"
				( objectStatus "@baseboard_fab2_lib.baseboard_fab2(sch_1):page92_i68:a" )
			)
			( pin "R7D27.2"
				( objectStatus "@baseboard_fab2_lib.baseboard_fab2(sch_1):page92_i68:b" )
			)
			( pin "R7D25.1"
				( objectStatus "@baseboard_fab2_lib.baseboard_fab2(sch_1):page92_i70:a" )
			)
			( pin "R7D25.2"
				( objectStatus "@baseboard_fab2_lib.baseboard_fab2(sch_1):page92_i70:b" )
			)
			( pin "R3R2.1"
				( objectStatus "@baseboard_fab2_lib.baseboard_fab2(sch_1):page92_i75:a" )
			)
			( pin "R3R2.2"
				( objectStatus "@baseboard_fab2_lib.baseboard_fab2(sch_1):page92_i75:b" )
			)
			( pin "C7D4.1"
				( objectStatus "@baseboard_fab2_lib.baseboard_fab2(sch_1):page92_i79:a" )
			)
			( pin "C7D4.2"
				( objectStatus "@baseboard_fab2_lib.baseboard_fab2(sch_1):page92_i79:b" )
			)
			( pin "C3P50.1"
				( objectStatus "@baseboard_fab2_lib.baseboard_fab2(sch_1):page92_i84:a" )
			)
			( pin "C3P50.2"
				( objectStatus "@baseboard_fab2_lib.baseboard_fab2(sch_1):page92_i84:b" )
			)
			( pin "R2T44.1"
				( objectStatus "@baseboard_fab2_lib.baseboard_fab2(sch_1):page92_i92:a" )
			)
			( pin "R2T44.2"
				( objectStatus "@baseboard_fab2_lib.baseboard_fab2(sch_1):page92_i92:b" )
			)
			( pin "R2T40.1"
				( objectStatus "@baseboard_fab2_lib.baseboard_fab2(sch_1):page92_i93:a" )
			)
			( pin "R2T40.2"
				( objectStatus "@baseboard_fab2_lib.baseboard_fab2(sch_1):page92_i93:b" )
			)
			( pin "R2T37.1"
				( objectStatus "@baseboard_fab2_lib.baseboard_fab2(sch_1):page92_i94:a" )
			)
			( pin "R2T37.2"
				( objectStatus "@baseboard_fab2_lib.baseboard_fab2(sch_1):page92_i94:b" )
			)
			( pin "R2T43.1"
				( objectStatus "@baseboard_fab2_lib.baseboard_fab2(sch_1):page92_i96:a" )
			)
			( pin "R2T43.2"
				( objectStatus "@baseboard_fab2_lib.baseboard_fab2(sch_1):page92_i96:b" )
			)
			( pin "R3P59.1"
				( objectStatus "@baseboard_fab2_lib.baseboard_fab2(sch_1):page92_i97:a" )
			)
			( pin "R3P59.2"
				( objectStatus "@baseboard_fab2_lib.baseboard_fab2(sch_1):page92_i97:b" )
			)
			( pin "R3P58.1"
				( objectStatus "@baseboard_fab2_lib.baseboard_fab2(sch_1):page92_i98:a" )
			)
			( pin "R3P58.2"
				( objectStatus "@baseboard_fab2_lib.baseboard_fab2(sch_1):page92_i98:b" )
			)
			( pin "R7P18.1"
				( objectStatus "@baseboard_fab2_lib.baseboard_fab2(sch_1):page92_i100:a" )
			)
			( pin "R7P18.2"
				( objectStatus "@baseboard_fab2_lib.baseboard_fab2(sch_1):page92_i100:b" )
			)
			( pin "R4R2.1"
				( objectStatus "@baseboard_fab2_lib.baseboard_fab2(sch_1):page92_i101:a" )
			)
			( pin "R4R2.2"
				( objectStatus "@baseboard_fab2_lib.baseboard_fab2(sch_1):page92_i101:b" )
			)
			( pin "R2T27.1"
				( objectStatus "@baseboard_fab2_lib.baseboard_fab2(sch_1):page93_i13:a" )
			)
			( pin "R2T27.2"
				( objectStatus "@baseboard_fab2_lib.baseboard_fab2(sch_1):page93_i13:b" )
			)
			( pin "R2T32.1"
				( objectStatus "@baseboard_fab2_lib.baseboard_fab2(sch_1):page93_i15:a" )
			)
			( pin "R2T32.2"
				( objectStatus "@baseboard_fab2_lib.baseboard_fab2(sch_1):page93_i15:b" )
			)
			( pin "R2T20.1"
				( objectStatus "@baseboard_fab2_lib.baseboard_fab2(sch_1):page93_i16:a" )
			)
			( pin "R2T20.2"
				( objectStatus "@baseboard_fab2_lib.baseboard_fab2(sch_1):page93_i16:b" )
			)
			( pin "R2T17.1"
				( objectStatus "@baseboard_fab2_lib.baseboard_fab2(sch_1):page93_i23:a" )
			)
			( pin "R2T17.2"
				( objectStatus "@baseboard_fab2_lib.baseboard_fab2(sch_1):page93_i23:b" )
			)
			( pin "U2T4.13"
				( objectStatus "@baseboard_fab2_lib.baseboard_fab2(sch_1):page93_i30:a0" )
			)
			( pin "U2T4.12"
				( objectStatus "@baseboard_fab2_lib.baseboard_fab2(sch_1):page93_i30:a1" )
			)
			( pin "U2T4.10"
				( objectStatus "@baseboard_fab2_lib.baseboard_fab2(sch_1):page93_i30:a2" )
			)
			( pin "U2T4.9"
				( objectStatus "@baseboard_fab2_lib.baseboard_fab2(sch_1):page93_i30:a3" )
			)
			( pin "U2T4.2"
				( objectStatus "@baseboard_fab2_lib.baseboard_fab2(sch_1):page93_i30:b0" )
			)
			( pin "U2T4.3"
				( objectStatus "@baseboard_fab2_lib.baseboard_fab2(sch_1):page93_i30:b1" )
			)
			( pin "U2T4.5"
				( objectStatus "@baseboard_fab2_lib.baseboard_fab2(sch_1):page93_i30:b2" )
			)
			( pin "U2T4.6"
				( objectStatus "@baseboard_fab2_lib.baseboard_fab2(sch_1):page93_i30:b3" )
			)
			( pin "U2T4.1"
				( objectStatus "@baseboard_fab2_lib.baseboard_fab2(sch_1):page93_i30:dir" )
			)
			( pin "U2T4.7"
				( objectStatus "@baseboard_fab2_lib.baseboard_fab2(sch_1):page93_i30:gnd(0)" )
			)
			( pin "U2T4.8"
				( objectStatus "@baseboard_fab2_lib.baseboard_fab2(sch_1):page93_i30:gnd(1)" )
			)
			( pin "U2T4.11"
				( objectStatus "@baseboard_fab2_lib.baseboard_fab2(sch_1):page93_i30:gnd(2)" )
			)
			( pin "U2T4.14"
				( objectStatus "@baseboard_fab2_lib.baseboard_fab2(sch_1):page93_i30:vcc" )
			)
			( pin "U2T4.4"
				( objectStatus "@baseboard_fab2_lib.baseboard_fab2(sch_1):page93_i30:vref" )
			)
			( pin "R2T38.1"
				( objectStatus "@baseboard_fab2_lib.baseboard_fab2(sch_1):page93_i39:a" )
			)
			( pin "R2T38.2"
				( objectStatus "@baseboard_fab2_lib.baseboard_fab2(sch_1):page93_i39:b" )
			)
			( pin "R2T33.1"
				( objectStatus "@baseboard_fab2_lib.baseboard_fab2(sch_1):page93_i40:a" )
			)
			( pin "R2T33.2"
				( objectStatus "@baseboard_fab2_lib.baseboard_fab2(sch_1):page93_i40:b" )
			)
			( pin "R2T30.1"
				( objectStatus "@baseboard_fab2_lib.baseboard_fab2(sch_1):page93_i42:a" )
			)
			( pin "R2T30.2"
				( objectStatus "@baseboard_fab2_lib.baseboard_fab2(sch_1):page93_i42:b" )
			)
			( pin "R7D24.1"
				( objectStatus "@baseboard_fab2_lib.baseboard_fab2(sch_1):page93_i62:a" )
			)
			( pin "R7D24.2"
				( objectStatus "@baseboard_fab2_lib.baseboard_fab2(sch_1):page93_i62:b" )
			)
			( pin "R2T19.1"
				( objectStatus "@baseboard_fab2_lib.baseboard_fab2(sch_1):page93_i63:a" )
			)
			( pin "R2T19.2"
				( objectStatus "@baseboard_fab2_lib.baseboard_fab2(sch_1):page93_i63:b" )
			)
			( pin "R2T16.1"
				( objectStatus "@baseboard_fab2_lib.baseboard_fab2(sch_1):page93_i67:a" )
			)
			( pin "R2T16.2"
				( objectStatus "@baseboard_fab2_lib.baseboard_fab2(sch_1):page93_i67:b" )
			)
			( pin "R2T31.1"
				( objectStatus "@baseboard_fab2_lib.baseboard_fab2(sch_1):page93_i68:a" )
			)
			( pin "R2T31.2"
				( objectStatus "@baseboard_fab2_lib.baseboard_fab2(sch_1):page93_i68:b" )
			)
			( pin "C2T33.1"
				( objectStatus "@baseboard_fab2_lib.baseboard_fab2(sch_1):page93_i72:a" )
			)
			( pin "C2T33.2"
				( objectStatus "@baseboard_fab2_lib.baseboard_fab2(sch_1):page93_i72:b" )
			)
			( pin "R4R3.1"
				( objectStatus "@baseboard_fab2_lib.baseboard_fab2(sch_1):page93_i79:a" )
			)
			( pin "R4R3.2"
				( objectStatus "@baseboard_fab2_lib.baseboard_fab2(sch_1):page93_i79:b" )
			)
			( pin "R2T26.1"
				( objectStatus "@baseboard_fab2_lib.baseboard_fab2(sch_1):page93_i87:a" )
			)
			( pin "R2T26.2"
				( objectStatus "@baseboard_fab2_lib.baseboard_fab2(sch_1):page93_i87:b" )
			)
			( pin "R2T57.1"
				( objectStatus "@baseboard_fab2_lib.baseboard_fab2(sch_1):page93_i88:a" )
			)
			( pin "R2T57.2"
				( objectStatus "@baseboard_fab2_lib.baseboard_fab2(sch_1):page93_i88:b" )
			)
			( pin "R2T61.1"
				( objectStatus "@baseboard_fab2_lib.baseboard_fab2(sch_1):page93_i89:a" )
			)
			( pin "R2T61.2"
				( objectStatus "@baseboard_fab2_lib.baseboard_fab2(sch_1):page93_i89:b" )
			)
			( pin "R2T62.1"
				( objectStatus "@baseboard_fab2_lib.baseboard_fab2(sch_1):page93_i93:a" )
			)
			( pin "R2T62.2"
				( objectStatus "@baseboard_fab2_lib.baseboard_fab2(sch_1):page93_i93:b" )
			)
			( pin "R2T58.1"
				( objectStatus "@baseboard_fab2_lib.baseboard_fab2(sch_1):page93_i94:a" )
			)
			( pin "R2T58.2"
				( objectStatus "@baseboard_fab2_lib.baseboard_fab2(sch_1):page93_i94:b" )
			)
			( pin "C2T32.1"
				( objectStatus "@baseboard_fab2_lib.baseboard_fab2(sch_1):page93_i95:a" )
			)
			( pin "C2T32.2"
				( objectStatus "@baseboard_fab2_lib.baseboard_fab2(sch_1):page93_i95:b" )
			)
			( pin "R1U43.1"
				( objectStatus "@baseboard_fab2_lib.baseboard_fab2(sch_1):page152_i106:\1\" )
			)
			( pin "R1U43.2"
				( objectStatus "@baseboard_fab2_lib.baseboard_fab2(sch_1):page152_i106:\2\" )
			)
			( pin "R2T39.1"
				( objectStatus "@baseboard_fab2_lib.baseboard_fab2(sch_1):page93_i98:a" )
			)
			( pin "R2T39.2"
				( objectStatus "@baseboard_fab2_lib.baseboard_fab2(sch_1):page93_i98:b" )
			)
			( pin "R2T68.1"
				( objectStatus "@baseboard_fab2_lib.baseboard_fab2(sch_1):page93_i102:a" )
			)
			( pin "R2T68.2"
				( objectStatus "@baseboard_fab2_lib.baseboard_fab2(sch_1):page93_i102:b" )
			)
			( pin "R2T60.1"
				( objectStatus "@baseboard_fab2_lib.baseboard_fab2(sch_1):page93_i103:a" )
			)
			( pin "R2T60.2"
				( objectStatus "@baseboard_fab2_lib.baseboard_fab2(sch_1):page93_i103:b" )
			)
			( pin "R7P28.1"
				( objectStatus "@baseboard_fab2_lib.baseboard_fab2(sch_1):page93_i106:a" )
			)
			( pin "R7P28.2"
				( objectStatus "@baseboard_fab2_lib.baseboard_fab2(sch_1):page93_i106:b" )
			)
			( pin "R2T59.1"
				( objectStatus "@baseboard_fab2_lib.baseboard_fab2(sch_1):page93_i107:a" )
			)
			( pin "R2T59.2"
				( objectStatus "@baseboard_fab2_lib.baseboard_fab2(sch_1):page93_i107:b" )
			)
			( pin "R2T69.1"
				( objectStatus "@baseboard_fab2_lib.baseboard_fab2(sch_1):page93_i108:a" )
			)
			( pin "R2T69.2"
				( objectStatus "@baseboard_fab2_lib.baseboard_fab2(sch_1):page93_i108:b" )
			)
			( pin "R2T71.1"
				( objectStatus "@baseboard_fab2_lib.baseboard_fab2(sch_1):page93_i109:a" )
			)
			( pin "R2T71.2"
				( objectStatus "@baseboard_fab2_lib.baseboard_fab2(sch_1):page93_i109:b" )
			)
			( pin "R7D43.1"
				( objectStatus "@baseboard_fab2_lib.baseboard_fab2(sch_1):page93_i110:a" )
			)
			( pin "R7D43.2"
				( objectStatus "@baseboard_fab2_lib.baseboard_fab2(sch_1):page93_i110:b" )
			)
			( pin "R2T65.1"
				( objectStatus "@baseboard_fab2_lib.baseboard_fab2(sch_1):page93_i111:a" )
			)
			( pin "R2T65.2"
				( objectStatus "@baseboard_fab2_lib.baseboard_fab2(sch_1):page93_i111:b" )
			)
			( pin "R2T66.1"
				( objectStatus "@baseboard_fab2_lib.baseboard_fab2(sch_1):page93_i112:a" )
			)
			( pin "R2T66.2"
				( objectStatus "@baseboard_fab2_lib.baseboard_fab2(sch_1):page93_i112:b" )
			)
			( pin "R2T67.1"
				( objectStatus "@baseboard_fab2_lib.baseboard_fab2(sch_1):page93_i113:a" )
			)
			( pin "R2T67.2"
				( objectStatus "@baseboard_fab2_lib.baseboard_fab2(sch_1):page93_i113:b" )
			)
			( pin "R7D41.1"
				( objectStatus "@baseboard_fab2_lib.baseboard_fab2(sch_1):page93_i114:a" )
			)
			( pin "R7D41.2"
				( objectStatus "@baseboard_fab2_lib.baseboard_fab2(sch_1):page93_i114:b" )
			)
			( pin "R8F38.1"
				( objectStatus "@baseboard_fab2_lib.baseboard_fab2(sch_1):page93_i119:a" )
			)
			( pin "R8F38.2"
				( objectStatus "@baseboard_fab2_lib.baseboard_fab2(sch_1):page93_i119:b" )
			)
			( pin "R2T64.1"
				( objectStatus "@baseboard_fab2_lib.baseboard_fab2(sch_1):page93_i121:a" )
			)
			( pin "R2T64.2"
				( objectStatus "@baseboard_fab2_lib.baseboard_fab2(sch_1):page93_i121:b" )
			)
			( pin "R1T36.1"
				( objectStatus "@baseboard_fab2_lib.baseboard_fab2(sch_1):page93_i122:a" )
			)
			( pin "R1T36.2"
				( objectStatus "@baseboard_fab2_lib.baseboard_fab2(sch_1):page93_i122:b" )
			)
			( pin "R1T37.1"
				( objectStatus "@baseboard_fab2_lib.baseboard_fab2(sch_1):page93_i123:a" )
			)
			( pin "R1T37.2"
				( objectStatus "@baseboard_fab2_lib.baseboard_fab2(sch_1):page93_i123:b" )
			)
			( pin "R2T50.1"
				( objectStatus "@baseboard_fab2_lib.baseboard_fab2(sch_1):page93_i127:a" )
			)
			( pin "R2T50.2"
				( objectStatus "@baseboard_fab2_lib.baseboard_fab2(sch_1):page93_i127:b" )
			)
			( pin "R8F37.1"
				( objectStatus "@baseboard_fab2_lib.baseboard_fab2(sch_1):page93_i131:a" )
			)
			( pin "R8F37.2"
				( objectStatus "@baseboard_fab2_lib.baseboard_fab2(sch_1):page93_i131:b" )
			)
			( pin "R2T63.1"
				( objectStatus "@baseboard_fab2_lib.baseboard_fab2(sch_1):page93_i133:a" )
			)
			( pin "R2T63.2"
				( objectStatus "@baseboard_fab2_lib.baseboard_fab2(sch_1):page93_i133:b" )
			)
			( pin "R1T35.1"
				( objectStatus "@baseboard_fab2_lib.baseboard_fab2(sch_1):page93_i135:a" )
			)
			( pin "R1T35.2"
				( objectStatus "@baseboard_fab2_lib.baseboard_fab2(sch_1):page93_i135:b" )
			)
			( pin "R1T38.1"
				( objectStatus "@baseboard_fab2_lib.baseboard_fab2(sch_1):page93_i137:a" )
			)
			( pin "R1T38.2"
				( objectStatus "@baseboard_fab2_lib.baseboard_fab2(sch_1):page93_i137:b" )
			)
			( pin "R2T72.1"
				( objectStatus "@baseboard_fab2_lib.baseboard_fab2(sch_1):page93_i143:a" )
			)
			( pin "R2T72.2"
				( objectStatus "@baseboard_fab2_lib.baseboard_fab2(sch_1):page93_i143:b" )
			)
			( pin "R2T73.1"
				( objectStatus "@baseboard_fab2_lib.baseboard_fab2(sch_1):page93_i144:a" )
			)
			( pin "R2T73.2"
				( objectStatus "@baseboard_fab2_lib.baseboard_fab2(sch_1):page93_i144:b" )
			)
			( pin "Q3U1.6"
				( objectStatus "@baseboard_fab2_lib.baseboard_fab2(sch_1):page94_i49:drain(0)" )
			)
			( pin "Q3U1.2"
				( objectStatus "@baseboard_fab2_lib.baseboard_fab2(sch_1):page94_i49:gate(0)" )
			)
			( pin "Q3U1.1"
				( objectStatus "@baseboard_fab2_lib.baseboard_fab2(sch_1):page94_i49:source(0)" )
			)
			( pin "R7G7.1"
				( objectStatus "@baseboard_fab2_lib.baseboard_fab2(sch_1):page94_i51:a" )
			)
			( pin "R7G7.2"
				( objectStatus "@baseboard_fab2_lib.baseboard_fab2(sch_1):page94_i51:b" )
			)
			( pin "Q7E1.6"
				( objectStatus "@baseboard_fab2_lib.baseboard_fab2(sch_1):page94_i60:drain(0)" )
			)
			( pin "Q7E1.2"
				( objectStatus "@baseboard_fab2_lib.baseboard_fab2(sch_1):page94_i60:gate(0)" )
			)
			( pin "Q7E1.1"
				( objectStatus "@baseboard_fab2_lib.baseboard_fab2(sch_1):page94_i60:source(0)" )
			)
			( pin "Q7E1.3"
				( objectStatus "@baseboard_fab2_lib.baseboard_fab2(sch_1):page94_i64:drain(0)" )
			)
			( pin "Q7E1.5"
				( objectStatus "@baseboard_fab2_lib.baseboard_fab2(sch_1):page94_i64:gate(0)" )
			)
			( pin "Q7E1.4"
				( objectStatus "@baseboard_fab2_lib.baseboard_fab2(sch_1):page94_i64:source(0)" )
			)
			( pin "R3R4.1"
				( objectStatus "@baseboard_fab2_lib.baseboard_fab2(sch_1):page94_i66:a" )
			)
			( pin "R3R4.2"
				( objectStatus "@baseboard_fab2_lib.baseboard_fab2(sch_1):page94_i66:b" )
			)
			( pin "Q7E2.6"
				( objectStatus "@baseboard_fab2_lib.baseboard_fab2(sch_1):page94_i69:drain(0)" )
			)
			( pin "Q7E2.2"
				( objectStatus "@baseboard_fab2_lib.baseboard_fab2(sch_1):page94_i69:gate(0)" )
			)
			( pin "Q7E2.1"
				( objectStatus "@baseboard_fab2_lib.baseboard_fab2(sch_1):page94_i69:source(0)" )
			)
			( pin "Q7E2.3"
				( objectStatus "@baseboard_fab2_lib.baseboard_fab2(sch_1):page94_i75:drain(0)" )
			)
			( pin "Q7E2.5"
				( objectStatus "@baseboard_fab2_lib.baseboard_fab2(sch_1):page94_i75:gate(0)" )
			)
			( pin "Q7E2.4"
				( objectStatus "@baseboard_fab2_lib.baseboard_fab2(sch_1):page94_i75:source(0)" )
			)
			( pin "Q4B1.3"
				( objectStatus "@baseboard_fab2_lib.baseboard_fab2(sch_1):page94_i77:drain(0)" )
			)
			( pin "Q4B1.5"
				( objectStatus "@baseboard_fab2_lib.baseboard_fab2(sch_1):page94_i77:gate(0)" )
			)
			( pin "Q4B1.4"
				( objectStatus "@baseboard_fab2_lib.baseboard_fab2(sch_1):page94_i77:source(0)" )
			)
			( pin "R3R10.1"
				( objectStatus "@baseboard_fab2_lib.baseboard_fab2(sch_1):page94_i79:a" )
			)
			( pin "R3R10.2"
				( objectStatus "@baseboard_fab2_lib.baseboard_fab2(sch_1):page94_i79:b" )
			)
			( pin "R6M4.1"
				( objectStatus "@baseboard_fab2_lib.baseboard_fab2(sch_1):page94_i82:a" )
			)
			( pin "R6M4.2"
				( objectStatus "@baseboard_fab2_lib.baseboard_fab2(sch_1):page94_i82:b" )
			)
			( pin "Q4B1.6"
				( objectStatus "@baseboard_fab2_lib.baseboard_fab2(sch_1):page94_i84:drain(0)" )
			)
			( pin "Q4B1.2"
				( objectStatus "@baseboard_fab2_lib.baseboard_fab2(sch_1):page94_i84:gate(0)" )
			)
			( pin "Q4B1.1"
				( objectStatus "@baseboard_fab2_lib.baseboard_fab2(sch_1):page94_i84:source(0)" )
			)
			( pin "Q3U1.3"
				( objectStatus "@baseboard_fab2_lib.baseboard_fab2(sch_1):page94_i89:drain(0)" )
			)
			( pin "Q3U1.5"
				( objectStatus "@baseboard_fab2_lib.baseboard_fab2(sch_1):page94_i89:gate(0)" )
			)
			( pin "Q3U1.4"
				( objectStatus "@baseboard_fab2_lib.baseboard_fab2(sch_1):page94_i89:source(0)" )
			)
			( pin "R4U1.1"
				( objectStatus "@baseboard_fab2_lib.baseboard_fab2(sch_1):page94_i91:a" )
			)
			( pin "R4U1.2"
				( objectStatus "@baseboard_fab2_lib.baseboard_fab2(sch_1):page94_i91:b" )
			)
			( pin "R4U3.1"
				( objectStatus "@baseboard_fab2_lib.baseboard_fab2(sch_1):page94_i94:a" )
			)
			( pin "R4U3.2"
				( objectStatus "@baseboard_fab2_lib.baseboard_fab2(sch_1):page94_i94:b" )
			)
			( pin "Q4U1.6"
				( objectStatus "@baseboard_fab2_lib.baseboard_fab2(sch_1):page94_i98:drain(0)" )
			)
			( pin "Q4U1.2"
				( objectStatus "@baseboard_fab2_lib.baseboard_fab2(sch_1):page94_i98:gate(0)" )
			)
			( pin "Q4U1.1"
				( objectStatus "@baseboard_fab2_lib.baseboard_fab2(sch_1):page94_i98:source(0)" )
			)
			( pin "R4U2.1"
				( objectStatus "@baseboard_fab2_lib.baseboard_fab2(sch_1):page94_i100:a" )
			)
			( pin "R4U2.2"
				( objectStatus "@baseboard_fab2_lib.baseboard_fab2(sch_1):page94_i100:b" )
			)
			( pin "Q4U1.3"
				( objectStatus "@baseboard_fab2_lib.baseboard_fab2(sch_1):page94_i102:drain(0)" )
			)
			( pin "Q4U1.5"
				( objectStatus "@baseboard_fab2_lib.baseboard_fab2(sch_1):page94_i102:gate(0)" )
			)
			( pin "Q4U1.4"
				( objectStatus "@baseboard_fab2_lib.baseboard_fab2(sch_1):page94_i102:source(0)" )
			)
			( pin "R4U4.1"
				( objectStatus "@baseboard_fab2_lib.baseboard_fab2(sch_1):page94_i104:a" )
			)
			( pin "R4U4.2"
				( objectStatus "@baseboard_fab2_lib.baseboard_fab2(sch_1):page94_i104:b" )
			)
			( pin "Q2U1.6"
				( objectStatus "@baseboard_fab2_lib.baseboard_fab2(sch_1):page95_i28:drain(0)" )
			)
			( pin "Q2U1.2"
				( objectStatus "@baseboard_fab2_lib.baseboard_fab2(sch_1):page95_i28:gate(0)" )
			)
			( pin "Q2U1.1"
				( objectStatus "@baseboard_fab2_lib.baseboard_fab2(sch_1):page95_i28:source(0)" )
			)
			( pin "Q4B2.6"
				( objectStatus "@baseboard_fab2_lib.baseboard_fab2(sch_1):page95_i32:drain(0)" )
			)
			( pin "Q4B2.2"
				( objectStatus "@baseboard_fab2_lib.baseboard_fab2(sch_1):page95_i32:gate(0)" )
			)
			( pin "Q4B2.1"
				( objectStatus "@baseboard_fab2_lib.baseboard_fab2(sch_1):page95_i32:source(0)" )
			)
			( pin "Q4B2.3"
				( objectStatus "@baseboard_fab2_lib.baseboard_fab2(sch_1):page95_i33:drain(0)" )
			)
			( pin "Q4B2.5"
				( objectStatus "@baseboard_fab2_lib.baseboard_fab2(sch_1):page95_i33:gate(0)" )
			)
			( pin "Q4B2.4"
				( objectStatus "@baseboard_fab2_lib.baseboard_fab2(sch_1):page95_i33:source(0)" )
			)
			( pin "Q7E3.3"
				( objectStatus "@baseboard_fab2_lib.baseboard_fab2(sch_1):page95_i51:drain(0)" )
			)
			( pin "Q7E3.5"
				( objectStatus "@baseboard_fab2_lib.baseboard_fab2(sch_1):page95_i51:gate(0)" )
			)
			( pin "Q7E3.4"
				( objectStatus "@baseboard_fab2_lib.baseboard_fab2(sch_1):page95_i51:source(0)" )
			)
			( pin "Q7E3.6"
				( objectStatus "@baseboard_fab2_lib.baseboard_fab2(sch_1):page95_i52:drain(0)" )
			)
			( pin "Q7E3.2"
				( objectStatus "@baseboard_fab2_lib.baseboard_fab2(sch_1):page95_i52:gate(0)" )
			)
			( pin "Q7E3.1"
				( objectStatus "@baseboard_fab2_lib.baseboard_fab2(sch_1):page95_i52:source(0)" )
			)
			( pin "Q7E5.3"
				( objectStatus "@baseboard_fab2_lib.baseboard_fab2(sch_1):page95_i59:drain(0)" )
			)
			( pin "Q7E5.5"
				( objectStatus "@baseboard_fab2_lib.baseboard_fab2(sch_1):page95_i59:gate(0)" )
			)
			( pin "Q7E5.4"
				( objectStatus "@baseboard_fab2_lib.baseboard_fab2(sch_1):page95_i59:source(0)" )
			)
			( pin "R7E10.1"
				( objectStatus "@baseboard_fab2_lib.baseboard_fab2(sch_1):page95_i62:a" )
			)
			( pin "R7E10.2"
				( objectStatus "@baseboard_fab2_lib.baseboard_fab2(sch_1):page95_i62:b" )
			)
			( pin "Q7E6.3"
				( objectStatus "@baseboard_fab2_lib.baseboard_fab2(sch_1):page95_i69:drain(0)" )
			)
			( pin "Q7E6.5"
				( objectStatus "@baseboard_fab2_lib.baseboard_fab2(sch_1):page95_i69:gate(0)" )
			)
			( pin "Q7E6.4"
				( objectStatus "@baseboard_fab2_lib.baseboard_fab2(sch_1):page95_i69:source(0)" )
			)
			( pin "R7E11.1"
				( objectStatus "@baseboard_fab2_lib.baseboard_fab2(sch_1):page95_i72:a" )
			)
			( pin "R7E11.2"
				( objectStatus "@baseboard_fab2_lib.baseboard_fab2(sch_1):page95_i72:b" )
			)
			( pin "C7E3.1"
				( objectStatus "@baseboard_fab2_lib.baseboard_fab2(sch_1):page95_i92:a" )
			)
			( pin "C7E3.2"
				( objectStatus "@baseboard_fab2_lib.baseboard_fab2(sch_1):page95_i92:b" )
			)
			( pin "Q8D2.3"
				( objectStatus "@baseboard_fab2_lib.baseboard_fab2(sch_1):page134_i15:drn" )
			)
			( pin "Q8D2.1"
				( objectStatus "@baseboard_fab2_lib.baseboard_fab2(sch_1):page134_i15:gate" )
			)
			( pin "Q8D2.2"
				( objectStatus "@baseboard_fab2_lib.baseboard_fab2(sch_1):page134_i15:src" )
			)
			( pin "R7E7.1"
				( objectStatus "@baseboard_fab2_lib.baseboard_fab2(sch_1):page95_i106:a" )
			)
			( pin "R7E7.2"
				( objectStatus "@baseboard_fab2_lib.baseboard_fab2(sch_1):page95_i106:b" )
			)
			( pin "R7E9.1"
				( objectStatus "@baseboard_fab2_lib.baseboard_fab2(sch_1):page95_i108:a" )
			)
			( pin "R7E9.2"
				( objectStatus "@baseboard_fab2_lib.baseboard_fab2(sch_1):page95_i108:b" )
			)
			( pin "Q7E5.6"
				( objectStatus "@baseboard_fab2_lib.baseboard_fab2(sch_1):page95_i111:drain(0)" )
			)
			( pin "Q7E5.2"
				( objectStatus "@baseboard_fab2_lib.baseboard_fab2(sch_1):page95_i111:gate(0)" )
			)
			( pin "Q7E5.1"
				( objectStatus "@baseboard_fab2_lib.baseboard_fab2(sch_1):page95_i111:source(0)" )
			)
			( pin "Q7E6.6"
				( objectStatus "@baseboard_fab2_lib.baseboard_fab2(sch_1):page95_i112:drain(0)" )
			)
			( pin "Q7E6.2"
				( objectStatus "@baseboard_fab2_lib.baseboard_fab2(sch_1):page95_i112:gate(0)" )
			)
			( pin "Q7E6.1"
				( objectStatus "@baseboard_fab2_lib.baseboard_fab2(sch_1):page95_i112:source(0)" )
			)
			( pin "Q2U1.3"
				( objectStatus "@baseboard_fab2_lib.baseboard_fab2(sch_1):page95_i113:drain(0)" )
			)
			( pin "Q2U1.5"
				( objectStatus "@baseboard_fab2_lib.baseboard_fab2(sch_1):page95_i113:gate(0)" )
			)
			( pin "Q2U1.4"
				( objectStatus "@baseboard_fab2_lib.baseboard_fab2(sch_1):page95_i113:source(0)" )
			)
			( pin "C7E4.1"
				( objectStatus "@baseboard_fab2_lib.baseboard_fab2(sch_1):page95_i115:a" )
			)
			( pin "C7E4.2"
				( objectStatus "@baseboard_fab2_lib.baseboard_fab2(sch_1):page95_i115:b" )
			)
			( pin "U7E2.1"
				( objectStatus "@baseboard_fab2_lib.baseboard_fab2(sch_1):page95_i117:a(0)" )
			)
			( pin "U7E2.2"
				( objectStatus "@baseboard_fab2_lib.baseboard_fab2(sch_1):page95_i117:b(0)" )
			)
			( pin "U7E2.4"
				( objectStatus "@baseboard_fab2_lib.baseboard_fab2(sch_1):page95_i117:y(0)" )
			)
			( pin "U7E3.1"
				( objectStatus "@baseboard_fab2_lib.baseboard_fab2(sch_1):page95_i118:a(0)" )
			)
			( pin "U7E3.2"
				( objectStatus "@baseboard_fab2_lib.baseboard_fab2(sch_1):page95_i118:b(0)" )
			)
			( pin "U7E3.4"
				( objectStatus "@baseboard_fab2_lib.baseboard_fab2(sch_1):page95_i118:y(0)" )
			)
			( pin "R25W93.1"
				( objectStatus "@baseboard_fab2_lib.baseboard_fab2(sch_1):page149_i90:a" )
			)
			( pin "R25W93.2"
				( objectStatus "@baseboard_fab2_lib.baseboard_fab2(sch_1):page149_i90:b" )
			)
			( pin "R6D12.1"
				( objectStatus "@baseboard_fab2_lib.baseboard_fab2(sch_1):page96_i2:a" )
			)
			( pin "R6D12.2"
				( objectStatus "@baseboard_fab2_lib.baseboard_fab2(sch_1):page96_i2:b" )
			)
			( pin "R6D8.1"
				( objectStatus "@baseboard_fab2_lib.baseboard_fab2(sch_1):page96_i3:a" )
			)
			( pin "R6D8.2"
				( objectStatus "@baseboard_fab2_lib.baseboard_fab2(sch_1):page96_i3:b" )
			)
			( pin "R3P29.1"
				( objectStatus "@baseboard_fab2_lib.baseboard_fab2(sch_1):page96_i5:a" )
			)
			( pin "R3P29.2"
				( objectStatus "@baseboard_fab2_lib.baseboard_fab2(sch_1):page96_i5:b" )
			)
			( pin "R3P38.1"
				( objectStatus "@baseboard_fab2_lib.baseboard_fab2(sch_1):page96_i7:a" )
			)
			( pin "R3P38.2"
				( objectStatus "@baseboard_fab2_lib.baseboard_fab2(sch_1):page96_i7:b" )
			)
			( pin "R3D20.1"
				( objectStatus "@baseboard_fab2_lib.baseboard_fab2(sch_1):page96_i25:a" )
			)
			( pin "R3D20.2"
				( objectStatus "@baseboard_fab2_lib.baseboard_fab2(sch_1):page96_i25:b" )
			)
			( pin "R3D15.1"
				( objectStatus "@baseboard_fab2_lib.baseboard_fab2(sch_1):page96_i26:a" )
			)
			( pin "R3D15.2"
				( objectStatus "@baseboard_fab2_lib.baseboard_fab2(sch_1):page96_i26:b" )
			)
			( pin "R7M9.1"
				( objectStatus "@baseboard_fab2_lib.baseboard_fab2(sch_1):page96_i28:a" )
			)
			( pin "R7M9.2"
				( objectStatus "@baseboard_fab2_lib.baseboard_fab2(sch_1):page96_i28:b" )
			)
			( pin "R3D21.1"
				( objectStatus "@baseboard_fab2_lib.baseboard_fab2(sch_1):page96_i30:a" )
			)
			( pin "R3D21.2"
				( objectStatus "@baseboard_fab2_lib.baseboard_fab2(sch_1):page96_i30:b" )
			)
			( pin "R3P36.1"
				( objectStatus "@baseboard_fab2_lib.baseboard_fab2(sch_1):page96_i36:a" )
			)
			( pin "R3P36.2"
				( objectStatus "@baseboard_fab2_lib.baseboard_fab2(sch_1):page96_i36:b" )
			)
			( pin "U3P1.13"
				( objectStatus "@baseboard_fab2_lib.baseboard_fab2(sch_1):page96_i42:a0" )
			)
			( pin "U3P1.12"
				( objectStatus "@baseboard_fab2_lib.baseboard_fab2(sch_1):page96_i42:a1" )
			)
			( pin "U3P1.10"
				( objectStatus "@baseboard_fab2_lib.baseboard_fab2(sch_1):page96_i42:a2" )
			)
			( pin "U3P1.9"
				( objectStatus "@baseboard_fab2_lib.baseboard_fab2(sch_1):page96_i42:a3" )
			)
			( pin "U3P1.2"
				( objectStatus "@baseboard_fab2_lib.baseboard_fab2(sch_1):page96_i42:b0" )
			)
			( pin "U3P1.3"
				( objectStatus "@baseboard_fab2_lib.baseboard_fab2(sch_1):page96_i42:b1" )
			)
			( pin "U3P1.5"
				( objectStatus "@baseboard_fab2_lib.baseboard_fab2(sch_1):page96_i42:b2" )
			)
			( pin "U3P1.6"
				( objectStatus "@baseboard_fab2_lib.baseboard_fab2(sch_1):page96_i42:b3" )
			)
			( pin "U3P1.1"
				( objectStatus "@baseboard_fab2_lib.baseboard_fab2(sch_1):page96_i42:dir" )
			)
			( pin "U3P1.7"
				( objectStatus "@baseboard_fab2_lib.baseboard_fab2(sch_1):page96_i42:gnd(0)" )
			)
			( pin "U3P1.8"
				( objectStatus "@baseboard_fab2_lib.baseboard_fab2(sch_1):page96_i42:gnd(1)" )
			)
			( pin "U3P1.11"
				( objectStatus "@baseboard_fab2_lib.baseboard_fab2(sch_1):page96_i42:gnd(2)" )
			)
			( pin "U3P1.14"
				( objectStatus "@baseboard_fab2_lib.baseboard_fab2(sch_1):page96_i42:vcc" )
			)
			( pin "U3P1.4"
				( objectStatus "@baseboard_fab2_lib.baseboard_fab2(sch_1):page96_i42:vref" )
			)
			( pin "U4C2.13"
				( objectStatus "@baseboard_fab2_lib.baseboard_fab2(sch_1):page96_i46:a0" )
			)
			( pin "U4C2.12"
				( objectStatus "@baseboard_fab2_lib.baseboard_fab2(sch_1):page96_i46:a1" )
			)
			( pin "U4C2.10"
				( objectStatus "@baseboard_fab2_lib.baseboard_fab2(sch_1):page96_i46:a2" )
			)
			( pin "U4C2.9"
				( objectStatus "@baseboard_fab2_lib.baseboard_fab2(sch_1):page96_i46:a3" )
			)
			( pin "U4C2.2"
				( objectStatus "@baseboard_fab2_lib.baseboard_fab2(sch_1):page96_i46:b0" )
			)
			( pin "U4C2.3"
				( objectStatus "@baseboard_fab2_lib.baseboard_fab2(sch_1):page96_i46:b1" )
			)
			( pin "U4C2.5"
				( objectStatus "@baseboard_fab2_lib.baseboard_fab2(sch_1):page96_i46:b2" )
			)
			( pin "U4C2.6"
				( objectStatus "@baseboard_fab2_lib.baseboard_fab2(sch_1):page96_i46:b3" )
			)
			( pin "U4C2.1"
				( objectStatus "@baseboard_fab2_lib.baseboard_fab2(sch_1):page96_i46:dir" )
			)
			( pin "U4C2.7"
				( objectStatus "@baseboard_fab2_lib.baseboard_fab2(sch_1):page96_i46:gnd(0)" )
			)
			( pin "U4C2.8"
				( objectStatus "@baseboard_fab2_lib.baseboard_fab2(sch_1):page96_i46:gnd(1)" )
			)
			( pin "U4C2.11"
				( objectStatus "@baseboard_fab2_lib.baseboard_fab2(sch_1):page96_i46:gnd(2)" )
			)
			( pin "U4C2.14"
				( objectStatus "@baseboard_fab2_lib.baseboard_fab2(sch_1):page96_i46:vcc" )
			)
			( pin "U4C2.4"
				( objectStatus "@baseboard_fab2_lib.baseboard_fab2(sch_1):page96_i46:vref" )
			)
			( pin "R4C8.1"
				( objectStatus "@baseboard_fab2_lib.baseboard_fab2(sch_1):page96_i55:a" )
			)
			( pin "R4C8.2"
				( objectStatus "@baseboard_fab2_lib.baseboard_fab2(sch_1):page96_i55:b" )
			)
			( pin "R4C9.1"
				( objectStatus "@baseboard_fab2_lib.baseboard_fab2(sch_1):page96_i69:a" )
			)
			( pin "R4C9.2"
				( objectStatus "@baseboard_fab2_lib.baseboard_fab2(sch_1):page96_i69:b" )
			)
			( pin "R3P32.1"
				( objectStatus "@baseboard_fab2_lib.baseboard_fab2(sch_1):page96_i71:a" )
			)
			( pin "R3P32.2"
				( objectStatus "@baseboard_fab2_lib.baseboard_fab2(sch_1):page96_i71:b" )
			)
			( pin "C3P42.1"
				( objectStatus "@baseboard_fab2_lib.baseboard_fab2(sch_1):page96_i73:a" )
			)
			( pin "C3P42.2"
				( objectStatus "@baseboard_fab2_lib.baseboard_fab2(sch_1):page96_i73:b" )
			)
			( pin "C4C3.1"
				( objectStatus "@baseboard_fab2_lib.baseboard_fab2(sch_1):page96_i75:a" )
			)
			( pin "C4C3.2"
				( objectStatus "@baseboard_fab2_lib.baseboard_fab2(sch_1):page96_i75:b" )
			)
			( pin "R3D18.1"
				( objectStatus "@baseboard_fab2_lib.baseboard_fab2(sch_1):page97_i33:a" )
			)
			( pin "R3D18.2"
				( objectStatus "@baseboard_fab2_lib.baseboard_fab2(sch_1):page97_i33:b" )
			)
			( pin "R4R4.1"
				( objectStatus "@baseboard_fab2_lib.baseboard_fab2(sch_1):page97_i42:a" )
			)
			( pin "R4R4.2"
				( objectStatus "@baseboard_fab2_lib.baseboard_fab2(sch_1):page97_i42:b" )
			)
			( pin "R7P20.1"
				( objectStatus "@baseboard_fab2_lib.baseboard_fab2(sch_1):page97_i44:a" )
			)
			( pin "R7P20.2"
				( objectStatus "@baseboard_fab2_lib.baseboard_fab2(sch_1):page97_i44:b" )
			)
			( pin "R4P21.1"
				( objectStatus "@baseboard_fab2_lib.baseboard_fab2(sch_1):page97_i72:a" )
			)
			( pin "R4P21.2"
				( objectStatus "@baseboard_fab2_lib.baseboard_fab2(sch_1):page97_i72:b" )
			)
			( pin "R4C10.1"
				( objectStatus "@baseboard_fab2_lib.baseboard_fab2(sch_1):page97_i76:a" )
			)
			( pin "R4C10.2"
				( objectStatus "@baseboard_fab2_lib.baseboard_fab2(sch_1):page97_i76:b" )
			)
			( pin "R4P5.1"
				( objectStatus "@baseboard_fab2_lib.baseboard_fab2(sch_1):page97_i80:a" )
			)
			( pin "R4P5.2"
				( objectStatus "@baseboard_fab2_lib.baseboard_fab2(sch_1):page97_i80:b" )
			)
			( pin "R7P13.1"
				( objectStatus "@baseboard_fab2_lib.baseboard_fab2(sch_1):page97_i81:a" )
			)
			( pin "R7P13.2"
				( objectStatus "@baseboard_fab2_lib.baseboard_fab2(sch_1):page97_i81:b" )
			)
			( pin "R4F5.1"
				( objectStatus "@baseboard_fab2_lib.baseboard_fab2(sch_1):page98_i4:a" )
			)
			( pin "R4F5.2"
				( objectStatus "@baseboard_fab2_lib.baseboard_fab2(sch_1):page98_i4:b" )
			)
			( pin "R4F3.1"
				( objectStatus "@baseboard_fab2_lib.baseboard_fab2(sch_1):page98_i5:a" )
			)
			( pin "R4F3.2"
				( objectStatus "@baseboard_fab2_lib.baseboard_fab2(sch_1):page98_i5:b" )
			)
			( pin "C4F9.1"
				( objectStatus "@baseboard_fab2_lib.baseboard_fab2(sch_1):page98_i7:a" )
			)
			( pin "C4F9.2"
				( objectStatus "@baseboard_fab2_lib.baseboard_fab2(sch_1):page98_i7:b" )
			)
			( pin "R6M1.1"
				( objectStatus "@baseboard_fab2_lib.baseboard_fab2(sch_1):page98_i9:a" )
			)
			( pin "R6M1.2"
				( objectStatus "@baseboard_fab2_lib.baseboard_fab2(sch_1):page98_i9:b" )
			)
			( pin "R6L16.1"
				( objectStatus "@baseboard_fab2_lib.baseboard_fab2(sch_1):page98_i12:a" )
			)
			( pin "R6L16.2"
				( objectStatus "@baseboard_fab2_lib.baseboard_fab2(sch_1):page98_i12:b" )
			)
			( pin "R6M2.1"
				( objectStatus "@baseboard_fab2_lib.baseboard_fab2(sch_1):page98_i14:a" )
			)
			( pin "R6M2.2"
				( objectStatus "@baseboard_fab2_lib.baseboard_fab2(sch_1):page98_i14:b" )
			)
			( pin "C6M2.1"
				( objectStatus "@baseboard_fab2_lib.baseboard_fab2(sch_1):page98_i33:a" )
			)
			( pin "C6M2.2"
				( objectStatus "@baseboard_fab2_lib.baseboard_fab2(sch_1):page98_i33:b" )
			)
			( pin "R4F4.1"
				( objectStatus "@baseboard_fab2_lib.baseboard_fab2(sch_1):page98_i36:a" )
			)
			( pin "R4F4.2"
				( objectStatus "@baseboard_fab2_lib.baseboard_fab2(sch_1):page98_i36:b" )
			)
			( pin "R4G2.1"
				( objectStatus "@baseboard_fab2_lib.baseboard_fab2(sch_1):page98_i38:a" )
			)
			( pin "R4G2.2"
				( objectStatus "@baseboard_fab2_lib.baseboard_fab2(sch_1):page98_i38:b" )
			)
			( pin "R4G3.1"
				( objectStatus "@baseboard_fab2_lib.baseboard_fab2(sch_1):page98_i40:a" )
			)
			( pin "R4G3.2"
				( objectStatus "@baseboard_fab2_lib.baseboard_fab2(sch_1):page98_i40:b" )
			)
			( pin "R4G1.1"
				( objectStatus "@baseboard_fab2_lib.baseboard_fab2(sch_1):page98_i42:a" )
			)
			( pin "R4G1.2"
				( objectStatus "@baseboard_fab2_lib.baseboard_fab2(sch_1):page98_i42:b" )
			)
			( pin "C4G1.1"
				( objectStatus "@baseboard_fab2_lib.baseboard_fab2(sch_1):page98_i43:a" )
			)
			( pin "C4G1.2"
				( objectStatus "@baseboard_fab2_lib.baseboard_fab2(sch_1):page98_i43:b" )
			)
			( pin "R4G21.1"
				( objectStatus "@baseboard_fab2_lib.baseboard_fab2(sch_1):page98_i46:a" )
			)
			( pin "R4G21.2"
				( objectStatus "@baseboard_fab2_lib.baseboard_fab2(sch_1):page98_i46:b" )
			)
			( pin "R4G22.1"
				( objectStatus "@baseboard_fab2_lib.baseboard_fab2(sch_1):page98_i48:a" )
			)
			( pin "R4G22.2"
				( objectStatus "@baseboard_fab2_lib.baseboard_fab2(sch_1):page98_i48:b" )
			)
			( pin "R4G20.1"
				( objectStatus "@baseboard_fab2_lib.baseboard_fab2(sch_1):page98_i50:a" )
			)
			( pin "R4G20.2"
				( objectStatus "@baseboard_fab2_lib.baseboard_fab2(sch_1):page98_i50:b" )
			)
			( pin "C4G17.1"
				( objectStatus "@baseboard_fab2_lib.baseboard_fab2(sch_1):page98_i51:a" )
			)
			( pin "C4G17.2"
				( objectStatus "@baseboard_fab2_lib.baseboard_fab2(sch_1):page98_i51:b" )
			)
			( pin "R6L13.1"
				( objectStatus "@baseboard_fab2_lib.baseboard_fab2(sch_1):page98_i54:a" )
			)
			( pin "R6L13.2"
				( objectStatus "@baseboard_fab2_lib.baseboard_fab2(sch_1):page98_i54:b" )
			)
			( pin "R6L12.1"
				( objectStatus "@baseboard_fab2_lib.baseboard_fab2(sch_1):page98_i56:a" )
			)
			( pin "R6L12.2"
				( objectStatus "@baseboard_fab2_lib.baseboard_fab2(sch_1):page98_i56:b" )
			)
			( pin "R6L14.1"
				( objectStatus "@baseboard_fab2_lib.baseboard_fab2(sch_1):page98_i58:a" )
			)
			( pin "R6L14.2"
				( objectStatus "@baseboard_fab2_lib.baseboard_fab2(sch_1):page98_i58:b" )
			)
			( pin "C6L7.1"
				( objectStatus "@baseboard_fab2_lib.baseboard_fab2(sch_1):page98_i59:a" )
			)
			( pin "C6L7.2"
				( objectStatus "@baseboard_fab2_lib.baseboard_fab2(sch_1):page98_i59:b" )
			)
			( pin "R6L2.1"
				( objectStatus "@baseboard_fab2_lib.baseboard_fab2(sch_1):page98_i62:a" )
			)
			( pin "R6L2.2"
				( objectStatus "@baseboard_fab2_lib.baseboard_fab2(sch_1):page98_i62:b" )
			)
			( pin "R6L1.1"
				( objectStatus "@baseboard_fab2_lib.baseboard_fab2(sch_1):page98_i64:a" )
			)
			( pin "R6L1.2"
				( objectStatus "@baseboard_fab2_lib.baseboard_fab2(sch_1):page98_i64:b" )
			)
			( pin "R6L3.1"
				( objectStatus "@baseboard_fab2_lib.baseboard_fab2(sch_1):page98_i66:a" )
			)
			( pin "R6L3.2"
				( objectStatus "@baseboard_fab2_lib.baseboard_fab2(sch_1):page98_i66:b" )
			)
			( pin "C6L2.1"
				( objectStatus "@baseboard_fab2_lib.baseboard_fab2(sch_1):page98_i67:a" )
			)
			( pin "C6L2.2"
				( objectStatus "@baseboard_fab2_lib.baseboard_fab2(sch_1):page98_i67:b" )
			)
			( pin "C6F2.1"
				( objectStatus "@baseboard_fab2_lib.baseboard_fab2(sch_1):page99_i2:a" )
			)
			( pin "C6F2.2"
				( objectStatus "@baseboard_fab2_lib.baseboard_fab2(sch_1):page99_i2:b" )
			)
			( pin "C6F3.1"
				( objectStatus "@baseboard_fab2_lib.baseboard_fab2(sch_1):page99_i7:a" )
			)
			( pin "C6F3.2"
				( objectStatus "@baseboard_fab2_lib.baseboard_fab2(sch_1):page99_i7:b" )
			)
			( pin "R4T9.1"
				( objectStatus "@baseboard_fab2_lib.baseboard_fab2(sch_1):page99_i9:a" )
			)
			( pin "R4T9.2"
				( objectStatus "@baseboard_fab2_lib.baseboard_fab2(sch_1):page99_i9:b" )
			)
			( pin "R4T10.1"
				( objectStatus "@baseboard_fab2_lib.baseboard_fab2(sch_1):page99_i10:a" )
			)
			( pin "R4T10.2"
				( objectStatus "@baseboard_fab2_lib.baseboard_fab2(sch_1):page99_i10:b" )
			)
			( pin "R4T8.1"
				( objectStatus "@baseboard_fab2_lib.baseboard_fab2(sch_1):page99_i11:a" )
			)
			( pin "R4T8.2"
				( objectStatus "@baseboard_fab2_lib.baseboard_fab2(sch_1):page99_i11:b" )
			)
			( pin "R4T7.1"
				( objectStatus "@baseboard_fab2_lib.baseboard_fab2(sch_1):page99_i13:a" )
			)
			( pin "R4T7.2"
				( objectStatus "@baseboard_fab2_lib.baseboard_fab2(sch_1):page99_i13:b" )
			)
			( pin "U6F1.5"
				( objectStatus "@baseboard_fab2_lib.baseboard_fab2(sch_1):page99_i15:en" )
			)
			( pin "U6F1.2"
				( objectStatus "@baseboard_fab2_lib.baseboard_fab2(sch_1):page99_i15:scla" )
			)
			( pin "U6F1.7"
				( objectStatus "@baseboard_fab2_lib.baseboard_fab2(sch_1):page99_i15:sclb" )
			)
			( pin "U6F1.3"
				( objectStatus "@baseboard_fab2_lib.baseboard_fab2(sch_1):page99_i15:sdaa" )
			)
			( pin "U6F1.6"
				( objectStatus "@baseboard_fab2_lib.baseboard_fab2(sch_1):page99_i15:sdab" )
			)
			( pin "U6F1.1"
				( objectStatus "@baseboard_fab2_lib.baseboard_fab2(sch_1):page99_i15:vcca" )
			)
			( pin "U6F1.8"
				( objectStatus "@baseboard_fab2_lib.baseboard_fab2(sch_1):page99_i15:vccb" )
			)
			( pin "R4T6.1"
				( objectStatus "@baseboard_fab2_lib.baseboard_fab2(sch_1):page99_i17:a" )
			)
			( pin "R4T6.2"
				( objectStatus "@baseboard_fab2_lib.baseboard_fab2(sch_1):page99_i17:b" )
			)
			( pin "R4T5.1"
				( objectStatus "@baseboard_fab2_lib.baseboard_fab2(sch_1):page99_i19:a" )
			)
			( pin "R4T5.2"
				( objectStatus "@baseboard_fab2_lib.baseboard_fab2(sch_1):page99_i19:b" )
			)
			( pin "R4T4.1"
				( objectStatus "@baseboard_fab2_lib.baseboard_fab2(sch_1):page99_i20:a" )
			)
			( pin "R4T4.2"
				( objectStatus "@baseboard_fab2_lib.baseboard_fab2(sch_1):page99_i20:b" )
			)
			( pin "C7E1.1"
				( objectStatus "@baseboard_fab2_lib.baseboard_fab2(sch_1):page99_i23:a" )
			)
			( pin "C7E1.2"
				( objectStatus "@baseboard_fab2_lib.baseboard_fab2(sch_1):page99_i23:b" )
			)
			( pin "C4G22.1"
				( objectStatus "@baseboard_fab2_lib.baseboard_fab2(sch_1):page99_i27:a" )
			)
			( pin "C4G22.2"
				( objectStatus "@baseboard_fab2_lib.baseboard_fab2(sch_1):page99_i27:b" )
			)
			( pin "C7E2.1"
				( objectStatus "@baseboard_fab2_lib.baseboard_fab2(sch_1):page99_i32:a" )
			)
			( pin "C7E2.2"
				( objectStatus "@baseboard_fab2_lib.baseboard_fab2(sch_1):page99_i32:b" )
			)
			( pin "R3R9.1"
				( objectStatus "@baseboard_fab2_lib.baseboard_fab2(sch_1):page99_i34:a" )
			)
			( pin "R3R9.2"
				( objectStatus "@baseboard_fab2_lib.baseboard_fab2(sch_1):page99_i34:b" )
			)
			( pin "R3R8.1"
				( objectStatus "@baseboard_fab2_lib.baseboard_fab2(sch_1):page99_i35:a" )
			)
			( pin "R3R8.2"
				( objectStatus "@baseboard_fab2_lib.baseboard_fab2(sch_1):page99_i35:b" )
			)
			( pin "C4G25.1"
				( objectStatus "@baseboard_fab2_lib.baseboard_fab2(sch_1):page99_i41:a" )
			)
			( pin "C4G25.2"
				( objectStatus "@baseboard_fab2_lib.baseboard_fab2(sch_1):page99_i41:b" )
			)
			( pin "R6U13.1"
				( objectStatus "@baseboard_fab2_lib.baseboard_fab2(sch_1):page99_i42:a" )
			)
			( pin "R6U13.2"
				( objectStatus "@baseboard_fab2_lib.baseboard_fab2(sch_1):page99_i42:b" )
			)
			( pin "C8U11.1"
				( objectStatus "@baseboard_fab2_lib.baseboard_fab2(sch_1):page225_i307:a" )
			)
			( pin "C8U11.2"
				( objectStatus "@baseboard_fab2_lib.baseboard_fab2(sch_1):page225_i307:b" )
			)
			( pin "C3B4.1"
				( objectStatus "@baseboard_fab2_lib.baseboard_fab2(sch_1):page99_i47:a" )
			)
			( pin "C3B4.2"
				( objectStatus "@baseboard_fab2_lib.baseboard_fab2(sch_1):page99_i47:b" )
			)
			( pin "C3B5.1"
				( objectStatus "@baseboard_fab2_lib.baseboard_fab2(sch_1):page99_i53:a" )
			)
			( pin "C3B5.2"
				( objectStatus "@baseboard_fab2_lib.baseboard_fab2(sch_1):page99_i53:b" )
			)
			( pin "R7M5.1"
				( objectStatus "@baseboard_fab2_lib.baseboard_fab2(sch_1):page99_i55:a" )
			)
			( pin "R7M5.2"
				( objectStatus "@baseboard_fab2_lib.baseboard_fab2(sch_1):page99_i55:b" )
			)
			( pin "R7M4.1"
				( objectStatus "@baseboard_fab2_lib.baseboard_fab2(sch_1):page99_i56:a" )
			)
			( pin "R7M4.2"
				( objectStatus "@baseboard_fab2_lib.baseboard_fab2(sch_1):page99_i56:b" )
			)
			( pin "U7E1.5"
				( objectStatus "@baseboard_fab2_lib.baseboard_fab2(sch_1):page99_i61:en" )
			)
			( pin "U7E1.2"
				( objectStatus "@baseboard_fab2_lib.baseboard_fab2(sch_1):page99_i61:scla" )
			)
			( pin "U7E1.7"
				( objectStatus "@baseboard_fab2_lib.baseboard_fab2(sch_1):page99_i61:sclb" )
			)
			( pin "U7E1.3"
				( objectStatus "@baseboard_fab2_lib.baseboard_fab2(sch_1):page99_i61:sdaa" )
			)
			( pin "U7E1.6"
				( objectStatus "@baseboard_fab2_lib.baseboard_fab2(sch_1):page99_i61:sdab" )
			)
			( pin "U7E1.1"
				( objectStatus "@baseboard_fab2_lib.baseboard_fab2(sch_1):page99_i61:vcca" )
			)
			( pin "U7E1.8"
				( objectStatus "@baseboard_fab2_lib.baseboard_fab2(sch_1):page99_i61:vccb" )
			)
			( pin "U4G1.5"
				( objectStatus "@baseboard_fab2_lib.baseboard_fab2(sch_1):page99_i63:en" )
			)
			( pin "U4G1.2"
				( objectStatus "@baseboard_fab2_lib.baseboard_fab2(sch_1):page99_i63:scla" )
			)
			( pin "U4G1.7"
				( objectStatus "@baseboard_fab2_lib.baseboard_fab2(sch_1):page99_i63:sclb" )
			)
			( pin "U4G1.3"
				( objectStatus "@baseboard_fab2_lib.baseboard_fab2(sch_1):page99_i63:sdaa" )
			)
			( pin "U4G1.6"
				( objectStatus "@baseboard_fab2_lib.baseboard_fab2(sch_1):page99_i63:sdab" )
			)
			( pin "U4G1.1"
				( objectStatus "@baseboard_fab2_lib.baseboard_fab2(sch_1):page99_i63:vcca" )
			)
			( pin "U4G1.8"
				( objectStatus "@baseboard_fab2_lib.baseboard_fab2(sch_1):page99_i63:vccb" )
			)
			( pin "R3R13.1"
				( objectStatus "@baseboard_fab2_lib.baseboard_fab2(sch_1):page99_i65:a" )
			)
			( pin "R3R13.2"
				( objectStatus "@baseboard_fab2_lib.baseboard_fab2(sch_1):page99_i65:b" )
			)
			( pin "R3P60.1"
				( objectStatus "@baseboard_fab2_lib.baseboard_fab2(sch_1):page99_i67:a" )
			)
			( pin "R3P60.2"
				( objectStatus "@baseboard_fab2_lib.baseboard_fab2(sch_1):page99_i67:b" )
			)
			( pin "R6T1.1"
				( objectStatus "@baseboard_fab2_lib.baseboard_fab2(sch_1):page99_i70:a" )
			)
			( pin "R6T1.2"
				( objectStatus "@baseboard_fab2_lib.baseboard_fab2(sch_1):page99_i70:b" )
			)
			( pin "R6T2.1"
				( objectStatus "@baseboard_fab2_lib.baseboard_fab2(sch_1):page99_i72:a" )
			)
			( pin "R6T2.2"
				( objectStatus "@baseboard_fab2_lib.baseboard_fab2(sch_1):page99_i72:b" )
			)
			( pin "U3B1.5"
				( objectStatus "@baseboard_fab2_lib.baseboard_fab2(sch_1):page99_i75:en" )
			)
			( pin "U3B1.2"
				( objectStatus "@baseboard_fab2_lib.baseboard_fab2(sch_1):page99_i75:scla" )
			)
			( pin "U3B1.7"
				( objectStatus "@baseboard_fab2_lib.baseboard_fab2(sch_1):page99_i75:sclb" )
			)
			( pin "U3B1.3"
				( objectStatus "@baseboard_fab2_lib.baseboard_fab2(sch_1):page99_i75:sdaa" )
			)
			( pin "U3B1.6"
				( objectStatus "@baseboard_fab2_lib.baseboard_fab2(sch_1):page99_i75:sdab" )
			)
			( pin "U3B1.1"
				( objectStatus "@baseboard_fab2_lib.baseboard_fab2(sch_1):page99_i75:vcca" )
			)
			( pin "U3B1.8"
				( objectStatus "@baseboard_fab2_lib.baseboard_fab2(sch_1):page99_i75:vccb" )
			)
			( pin "R7M7.1"
				( objectStatus "@baseboard_fab2_lib.baseboard_fab2(sch_1):page99_i77:a" )
			)
			( pin "R7M7.2"
				( objectStatus "@baseboard_fab2_lib.baseboard_fab2(sch_1):page99_i77:b" )
			)
			( pin "R7M2.1"
				( objectStatus "@baseboard_fab2_lib.baseboard_fab2(sch_1):page99_i79:a" )
			)
			( pin "R7M2.2"
				( objectStatus "@baseboard_fab2_lib.baseboard_fab2(sch_1):page99_i79:b" )
			)
			( pin "R4T3.1"
				( objectStatus "@baseboard_fab2_lib.baseboard_fab2(sch_1):page99_i83:a" )
			)
			( pin "R4T3.2"
				( objectStatus "@baseboard_fab2_lib.baseboard_fab2(sch_1):page99_i83:b" )
			)
			( pin "R3R7.1"
				( objectStatus "@baseboard_fab2_lib.baseboard_fab2(sch_1):page99_i88:a" )
			)
			( pin "R3R7.2"
				( objectStatus "@baseboard_fab2_lib.baseboard_fab2(sch_1):page99_i88:b" )
			)
			( pin "R6T3.1"
				( objectStatus "@baseboard_fab2_lib.baseboard_fab2(sch_1):page99_i92:a" )
			)
			( pin "R6T3.2"
				( objectStatus "@baseboard_fab2_lib.baseboard_fab2(sch_1):page99_i92:b" )
			)
			( pin "R7M3.1"
				( objectStatus "@baseboard_fab2_lib.baseboard_fab2(sch_1):page99_i98:a" )
			)
			( pin "R7M3.2"
				( objectStatus "@baseboard_fab2_lib.baseboard_fab2(sch_1):page99_i98:b" )
			)
			( pin "R3R12.1"
				( objectStatus "@baseboard_fab2_lib.baseboard_fab2(sch_1):page99_i101:a" )
			)
			( pin "R3R12.2"
				( objectStatus "@baseboard_fab2_lib.baseboard_fab2(sch_1):page99_i101:b" )
			)
			( pin "R3R5.1"
				( objectStatus "@baseboard_fab2_lib.baseboard_fab2(sch_1):page99_i103:a" )
			)
			( pin "R3R5.2"
				( objectStatus "@baseboard_fab2_lib.baseboard_fab2(sch_1):page99_i103:b" )
			)
			( pin "R6U18.1"
				( objectStatus "@baseboard_fab2_lib.baseboard_fab2(sch_1):page99_i104:a" )
			)
			( pin "R6U18.2"
				( objectStatus "@baseboard_fab2_lib.baseboard_fab2(sch_1):page99_i104:b" )
			)
			( pin "R6U17.1"
				( objectStatus "@baseboard_fab2_lib.baseboard_fab2(sch_1):page99_i106:a" )
			)
			( pin "R6U17.2"
				( objectStatus "@baseboard_fab2_lib.baseboard_fab2(sch_1):page99_i106:b" )
			)
			( pin "R7M6.1"
				( objectStatus "@baseboard_fab2_lib.baseboard_fab2(sch_1):page99_i107:a" )
			)
			( pin "R7M6.2"
				( objectStatus "@baseboard_fab2_lib.baseboard_fab2(sch_1):page99_i107:b" )
			)
			( pin "R7M1.1"
				( objectStatus "@baseboard_fab2_lib.baseboard_fab2(sch_1):page99_i109:a" )
			)
			( pin "R7M1.2"
				( objectStatus "@baseboard_fab2_lib.baseboard_fab2(sch_1):page99_i109:b" )
			)
			( pin "R3R14.1"
				( objectStatus "@baseboard_fab2_lib.baseboard_fab2(sch_1):page99_i110:a" )
			)
			( pin "R3R14.2"
				( objectStatus "@baseboard_fab2_lib.baseboard_fab2(sch_1):page99_i110:b" )
			)
			( pin "R6T4.1"
				( objectStatus "@baseboard_fab2_lib.baseboard_fab2(sch_1):page99_i111:a" )
			)
			( pin "R6T4.2"
				( objectStatus "@baseboard_fab2_lib.baseboard_fab2(sch_1):page99_i111:b" )
			)
			( pin "R7M8.1"
				( objectStatus "@baseboard_fab2_lib.baseboard_fab2(sch_1):page99_i112:a" )
			)
			( pin "R7M8.2"
				( objectStatus "@baseboard_fab2_lib.baseboard_fab2(sch_1):page99_i112:b" )
			)
			( pin "R1F6.1"
				( objectStatus "@baseboard_fab2_lib.baseboard_fab2(sch_1):page100_i2:a" )
			)
			( pin "R1F6.2"
				( objectStatus "@baseboard_fab2_lib.baseboard_fab2(sch_1):page100_i2:b" )
			)
			( pin "R9L11.1"
				( objectStatus "@baseboard_fab2_lib.baseboard_fab2(sch_1):page100_i4:a" )
			)
			( pin "R9L11.2"
				( objectStatus "@baseboard_fab2_lib.baseboard_fab2(sch_1):page100_i4:b" )
			)
			( pin "R1F5.1"
				( objectStatus "@baseboard_fab2_lib.baseboard_fab2(sch_1):page100_i6:a" )
			)
			( pin "R1F5.2"
				( objectStatus "@baseboard_fab2_lib.baseboard_fab2(sch_1):page100_i6:b" )
			)
			( pin "R1F4.1"
				( objectStatus "@baseboard_fab2_lib.baseboard_fab2(sch_1):page100_i7:a" )
			)
			( pin "R1F4.2"
				( objectStatus "@baseboard_fab2_lib.baseboard_fab2(sch_1):page100_i7:b" )
			)
			( pin "C1F19.1"
				( objectStatus "@baseboard_fab2_lib.baseboard_fab2(sch_1):page100_i8:a" )
			)
			( pin "C1F19.2"
				( objectStatus "@baseboard_fab2_lib.baseboard_fab2(sch_1):page100_i8:b" )
			)
			( pin "R9M1.1"
				( objectStatus "@baseboard_fab2_lib.baseboard_fab2(sch_1):page100_i11:a" )
			)
			( pin "R9M1.2"
				( objectStatus "@baseboard_fab2_lib.baseboard_fab2(sch_1):page100_i11:b" )
			)
			( pin "R9M2.1"
				( objectStatus "@baseboard_fab2_lib.baseboard_fab2(sch_1):page100_i13:a" )
			)
			( pin "R9M2.2"
				( objectStatus "@baseboard_fab2_lib.baseboard_fab2(sch_1):page100_i13:b" )
			)
			( pin "C9M2.1"
				( objectStatus "@baseboard_fab2_lib.baseboard_fab2(sch_1):page100_i15:a" )
			)
			( pin "C9M2.2"
				( objectStatus "@baseboard_fab2_lib.baseboard_fab2(sch_1):page100_i15:b" )
			)
			( pin "R1G2.1"
				( objectStatus "@baseboard_fab2_lib.baseboard_fab2(sch_1):page100_i19:a" )
			)
			( pin "R1G2.2"
				( objectStatus "@baseboard_fab2_lib.baseboard_fab2(sch_1):page100_i19:b" )
			)
			( pin "R1G3.1"
				( objectStatus "@baseboard_fab2_lib.baseboard_fab2(sch_1):page100_i20:a" )
			)
			( pin "R1G3.2"
				( objectStatus "@baseboard_fab2_lib.baseboard_fab2(sch_1):page100_i20:b" )
			)
			( pin "R9L7.1"
				( objectStatus "@baseboard_fab2_lib.baseboard_fab2(sch_1):page100_i22:a" )
			)
			( pin "R9L7.2"
				( objectStatus "@baseboard_fab2_lib.baseboard_fab2(sch_1):page100_i22:b" )
			)
			( pin "R9L6.1"
				( objectStatus "@baseboard_fab2_lib.baseboard_fab2(sch_1):page100_i24:a" )
			)
			( pin "R9L6.2"
				( objectStatus "@baseboard_fab2_lib.baseboard_fab2(sch_1):page100_i24:b" )
			)
			( pin "R1G1.1"
				( objectStatus "@baseboard_fab2_lib.baseboard_fab2(sch_1):page100_i25:a" )
			)
			( pin "R1G1.2"
				( objectStatus "@baseboard_fab2_lib.baseboard_fab2(sch_1):page100_i25:b" )
			)
			( pin "C1G8.1"
				( objectStatus "@baseboard_fab2_lib.baseboard_fab2(sch_1):page100_i26:a" )
			)
			( pin "C1G8.2"
				( objectStatus "@baseboard_fab2_lib.baseboard_fab2(sch_1):page100_i26:b" )
			)
			( pin "R9L8.1"
				( objectStatus "@baseboard_fab2_lib.baseboard_fab2(sch_1):page100_i29:a" )
			)
			( pin "R9L8.2"
				( objectStatus "@baseboard_fab2_lib.baseboard_fab2(sch_1):page100_i29:b" )
			)
			( pin "C9L8.1"
				( objectStatus "@baseboard_fab2_lib.baseboard_fab2(sch_1):page100_i30:a" )
			)
			( pin "C9L8.2"
				( objectStatus "@baseboard_fab2_lib.baseboard_fab2(sch_1):page100_i30:b" )
			)
			( pin "R1G15.1"
				( objectStatus "@baseboard_fab2_lib.baseboard_fab2(sch_1):page100_i35:a" )
			)
			( pin "R1G15.2"
				( objectStatus "@baseboard_fab2_lib.baseboard_fab2(sch_1):page100_i35:b" )
			)
			( pin "R1G17.1"
				( objectStatus "@baseboard_fab2_lib.baseboard_fab2(sch_1):page100_i36:a" )
			)
			( pin "R1G17.2"
				( objectStatus "@baseboard_fab2_lib.baseboard_fab2(sch_1):page100_i36:b" )
			)
			( pin "R9L2.1"
				( objectStatus "@baseboard_fab2_lib.baseboard_fab2(sch_1):page100_i38:a" )
			)
			( pin "R9L2.2"
				( objectStatus "@baseboard_fab2_lib.baseboard_fab2(sch_1):page100_i38:b" )
			)
			( pin "R9L1.1"
				( objectStatus "@baseboard_fab2_lib.baseboard_fab2(sch_1):page100_i40:a" )
			)
			( pin "R9L1.2"
				( objectStatus "@baseboard_fab2_lib.baseboard_fab2(sch_1):page100_i40:b" )
			)
			( pin "R1G14.1"
				( objectStatus "@baseboard_fab2_lib.baseboard_fab2(sch_1):page100_i41:a" )
			)
			( pin "R1G14.2"
				( objectStatus "@baseboard_fab2_lib.baseboard_fab2(sch_1):page100_i41:b" )
			)
			( pin "C1G18.1"
				( objectStatus "@baseboard_fab2_lib.baseboard_fab2(sch_1):page100_i42:a" )
			)
			( pin "C1G18.2"
				( objectStatus "@baseboard_fab2_lib.baseboard_fab2(sch_1):page100_i42:b" )
			)
			( pin "R9L3.1"
				( objectStatus "@baseboard_fab2_lib.baseboard_fab2(sch_1):page100_i45:a" )
			)
			( pin "R9L3.2"
				( objectStatus "@baseboard_fab2_lib.baseboard_fab2(sch_1):page100_i45:b" )
			)
			( pin "C9L3.1"
				( objectStatus "@baseboard_fab2_lib.baseboard_fab2(sch_1):page100_i46:a" )
			)
			( pin "C9L3.2"
				( objectStatus "@baseboard_fab2_lib.baseboard_fab2(sch_1):page100_i46:b" )
			)
			( pin "R8F29.1"
				( objectStatus "@baseboard_fab2_lib.baseboard_fab2(sch_1):page101_i20:a" )
			)
			( pin "R8F29.2"
				( objectStatus "@baseboard_fab2_lib.baseboard_fab2(sch_1):page101_i20:b" )
			)
			( pin "R8F25.1"
				( objectStatus "@baseboard_fab2_lib.baseboard_fab2(sch_1):page101_i28:a" )
			)
			( pin "R8F25.2"
				( objectStatus "@baseboard_fab2_lib.baseboard_fab2(sch_1):page101_i28:b" )
			)
			( pin "EU8F2.16"
				( objectStatus "@baseboard_fab2_lib.baseboard_fab2(sch_1):page101_i34:\25mhz_0\" )
			)
			( pin "EU8F2.17"
				( objectStatus "@baseboard_fab2_lib.baseboard_fab2(sch_1):page101_i34:\25mhz_1\" )
			)
			( pin "EU8F2.13"
				( objectStatus "@baseboard_fab2_lib.baseboard_fab2(sch_1):page101_i34:\32khz\" )
			)
			( pin "EU8F2.22"
				( objectStatus "@baseboard_fab2_lib.baseboard_fab2(sch_1):page101_i34:\33mhz_smbadr\" )
			)
			( pin "EU8F2.8"
				( objectStatus "@baseboard_fab2_lib.baseboard_fab2(sch_1):page101_i34:cpuclkc0" )
			)
			( pin "EU8F2.7"
				( objectStatus "@baseboard_fab2_lib.baseboard_fab2(sch_1):page101_i34:cpuclkt0" )
			)
			( pin "EU8F2.4"
				( objectStatus "@baseboard_fab2_lib.baseboard_fab2(sch_1):page101_i34:dot96ssc" )
			)
			( pin "EU8F2.3"
				( objectStatus "@baseboard_fab2_lib.baseboard_fab2(sch_1):page101_i34:dot96sst" )
			)
			( pin "EU8F2.1"
				( objectStatus "@baseboard_fab2_lib.baseboard_fab2(sch_1):page101_i34:gnd(0)" )
			)
			( pin "EU8F2.41"
				( objectStatus "@baseboard_fab2_lib.baseboard_fab2(sch_1):page101_i34:gnd(1)" )
			)
			( pin "EU8F2.14"
				( objectStatus "@baseboard_fab2_lib.baseboard_fab2(sch_1):page101_i34:gnd32k" )
			)
			( pin "EU8F2.21"
				( objectStatus "@baseboard_fab2_lib.baseboard_fab2(sch_1):page101_i34:gnd33" )
			)
			( pin "EU8F2.35"
				( objectStatus "@baseboard_fab2_lib.baseboard_fab2(sch_1):page101_i34:gnd_rgmii" )
			)
			( pin "EU8F2.10"
				( objectStatus "@baseboard_fab2_lib.baseboard_fab2(sch_1):page101_i34:gndcpu" )
			)
			( pin "EU8F2.18"
				( objectStatus "@baseboard_fab2_lib.baseboard_fab2(sch_1):page101_i34:gndref" )
			)
			( pin "EU8F2.27"
				( objectStatus "@baseboard_fab2_lib.baseboard_fab2(sch_1):page101_i34:gndrmii(0)" )
			)
			( pin "EU8F2.30"
				( objectStatus "@baseboard_fab2_lib.baseboard_fab2(sch_1):page101_i34:gndrmii(1)" )
			)
			( pin "EU8F2.11"
				( objectStatus "@baseboard_fab2_lib.baseboard_fab2(sch_1):page101_i34:iref" )
			)
			( pin "EU8F2.5"
				( objectStatus "@baseboard_fab2_lib.baseboard_fab2(sch_1):page101_i34:oe_96" )
			)
			( pin "EU8F2.6"
				( objectStatus "@baseboard_fab2_lib.baseboard_fab2(sch_1):page101_i34:oe_cpu" )
			)
			( pin "EU8F2.37"
				( objectStatus "@baseboard_fab2_lib.baseboard_fab2(sch_1):page101_i34:rgmii(0)" )
			)
			( pin "EU8F2.36"
				( objectStatus "@baseboard_fab2_lib.baseboard_fab2(sch_1):page101_i34:rgmii(1)" )
			)
			( pin "EU8F2.33"
				( objectStatus "@baseboard_fab2_lib.baseboard_fab2(sch_1):page101_i34:rmii(0)" )
			)
			( pin "EU8F2.32"
				( objectStatus "@baseboard_fab2_lib.baseboard_fab2(sch_1):page101_i34:rmii(1)" )
			)
			( pin "EU8F2.29"
				( objectStatus "@baseboard_fab2_lib.baseboard_fab2(sch_1):page101_i34:rmii(2)" )
			)
			( pin "EU8F2.28"
				( objectStatus "@baseboard_fab2_lib.baseboard_fab2(sch_1):page101_i34:rmii(3)" )
			)
			( pin "EU8F2.25"
				( objectStatus "@baseboard_fab2_lib.baseboard_fab2(sch_1):page101_i34:rmii(4)" )
			)
			( pin "EU8F2.24"
				( objectStatus "@baseboard_fab2_lib.baseboard_fab2(sch_1):page101_i34:rmii(5)" )
			)
			( pin "EU8F2.38"
				( objectStatus "@baseboard_fab2_lib.baseboard_fab2(sch_1):page101_i34:smbclk" )
			)
			( pin "EU8F2.39"
				( objectStatus "@baseboard_fab2_lib.baseboard_fab2(sch_1):page101_i34:smbdat" )
			)
			( pin "EU8F2.12"
				( objectStatus "@baseboard_fab2_lib.baseboard_fab2(sch_1):page101_i34:vdd32k" )
			)
			( pin "EU8F2.23"
				( objectStatus "@baseboard_fab2_lib.baseboard_fab2(sch_1):page101_i34:vdd33" )
			)
			( pin "EU8F2.2"
				( objectStatus "@baseboard_fab2_lib.baseboard_fab2(sch_1):page101_i34:vdd96" )
			)
			( pin "EU8F2.34"
				( objectStatus "@baseboard_fab2_lib.baseboard_fab2(sch_1):page101_i34:vdd_rgmii" )
			)
			( pin "EU8F2.9"
				( objectStatus "@baseboard_fab2_lib.baseboard_fab2(sch_1):page101_i34:vddcpu" )
			)
			( pin "EU8F2.15"
				( objectStatus "@baseboard_fab2_lib.baseboard_fab2(sch_1):page101_i34:vddref" )
			)
			( pin "EU8F2.26"
				( objectStatus "@baseboard_fab2_lib.baseboard_fab2(sch_1):page101_i34:vddrmii(0)" )
			)
			( pin "EU8F2.31"
				( objectStatus "@baseboard_fab2_lib.baseboard_fab2(sch_1):page101_i34:vddrmii(1)" )
			)
			( pin "EU8F2.40"
				( objectStatus "@baseboard_fab2_lib.baseboard_fab2(sch_1):page101_i34:vttpwr_gd_pd_n" )
			)
			( pin "EU8F2.19"
				( objectStatus "@baseboard_fab2_lib.baseboard_fab2(sch_1):page101_i34:x1_25" )
			)
			( pin "EU8F2.20"
				( objectStatus "@baseboard_fab2_lib.baseboard_fab2(sch_1):page101_i34:x2_25" )
			)
			( pin "R2T25.1"
				( objectStatus "@baseboard_fab2_lib.baseboard_fab2(sch_1):page101_i48:a" )
			)
			( pin "R2T25.2"
				( objectStatus "@baseboard_fab2_lib.baseboard_fab2(sch_1):page101_i48:b" )
			)
			( pin "Y8F1.1"
				( objectStatus "@baseboard_fab2_lib.baseboard_fab2(sch_1):page101_i52:a" )
			)
			( pin "Y8F1.3"
				( objectStatus "@baseboard_fab2_lib.baseboard_fab2(sch_1):page101_i52:b" )
			)
			( pin "L1A1.2"
				( objectStatus "@baseboard_fab2_lib.baseboard_fab2(sch_1):page227_i153:f" )
			)
			( pin "L1A1.1"
				( objectStatus "@baseboard_fab2_lib.baseboard_fab2(sch_1):page227_i153:s" )
			)
			( pin "C2T31.1"
				( objectStatus "@baseboard_fab2_lib.baseboard_fab2(sch_1):page101_i89:a" )
			)
			( pin "C2T31.2"
				( objectStatus "@baseboard_fab2_lib.baseboard_fab2(sch_1):page101_i89:b" )
			)
			( pin "C2T27.1"
				( objectStatus "@baseboard_fab2_lib.baseboard_fab2(sch_1):page101_i90:a" )
			)
			( pin "C2T27.2"
				( objectStatus "@baseboard_fab2_lib.baseboard_fab2(sch_1):page101_i90:b" )
			)
			( pin "R2T23.1"
				( objectStatus "@baseboard_fab2_lib.baseboard_fab2(sch_1):page101_i94:a" )
			)
			( pin "R2T23.2"
				( objectStatus "@baseboard_fab2_lib.baseboard_fab2(sch_1):page101_i94:b" )
			)
			( pin "R2T52.1"
				( objectStatus "@baseboard_fab2_lib.baseboard_fab2(sch_1):page101_i95:a" )
			)
			( pin "R2T52.2"
				( objectStatus "@baseboard_fab2_lib.baseboard_fab2(sch_1):page101_i95:b" )
			)
			( pin "C2T38.1"
				( objectStatus "@baseboard_fab2_lib.baseboard_fab2(sch_1):page101_i97:a" )
			)
			( pin "C2T38.2"
				( objectStatus "@baseboard_fab2_lib.baseboard_fab2(sch_1):page101_i97:b" )
			)
			( pin "C2T37.1"
				( objectStatus "@baseboard_fab2_lib.baseboard_fab2(sch_1):page101_i99:a" )
			)
			( pin "C2T37.2"
				( objectStatus "@baseboard_fab2_lib.baseboard_fab2(sch_1):page101_i99:b" )
			)
			( pin "C2T18.1"
				( objectStatus "@baseboard_fab2_lib.baseboard_fab2(sch_1):page101_i104:a" )
			)
			( pin "C2T18.2"
				( objectStatus "@baseboard_fab2_lib.baseboard_fab2(sch_1):page101_i104:b" )
			)
			( pin "R2T21.1"
				( objectStatus "@baseboard_fab2_lib.baseboard_fab2(sch_1):page101_i105:a" )
			)
			( pin "R2T21.2"
				( objectStatus "@baseboard_fab2_lib.baseboard_fab2(sch_1):page101_i105:b" )
			)
			( pin "C2T19.1"
				( objectStatus "@baseboard_fab2_lib.baseboard_fab2(sch_1):page101_i106:a" )
			)
			( pin "C2T19.2"
				( objectStatus "@baseboard_fab2_lib.baseboard_fab2(sch_1):page101_i106:b" )
			)
			( pin "C2T34.1"
				( objectStatus "@baseboard_fab2_lib.baseboard_fab2(sch_1):page101_i109:a" )
			)
			( pin "C2T34.2"
				( objectStatus "@baseboard_fab2_lib.baseboard_fab2(sch_1):page101_i109:b" )
			)
			( pin "C2T30.1"
				( objectStatus "@baseboard_fab2_lib.baseboard_fab2(sch_1):page101_i110:a" )
			)
			( pin "C2T30.2"
				( objectStatus "@baseboard_fab2_lib.baseboard_fab2(sch_1):page101_i110:b" )
			)
			( pin "C2T25.1"
				( objectStatus "@baseboard_fab2_lib.baseboard_fab2(sch_1):page101_i111:a" )
			)
			( pin "C2T25.2"
				( objectStatus "@baseboard_fab2_lib.baseboard_fab2(sch_1):page101_i111:b" )
			)
			( pin "C2T17.1"
				( objectStatus "@baseboard_fab2_lib.baseboard_fab2(sch_1):page101_i112:a" )
			)
			( pin "C2T17.2"
				( objectStatus "@baseboard_fab2_lib.baseboard_fab2(sch_1):page101_i112:b" )
			)
			( pin "C2T22.1"
				( objectStatus "@baseboard_fab2_lib.baseboard_fab2(sch_1):page101_i113:a" )
			)
			( pin "C2T22.2"
				( objectStatus "@baseboard_fab2_lib.baseboard_fab2(sch_1):page101_i113:b" )
			)
			( pin "FB2T2.1"
				( objectStatus "@baseboard_fab2_lib.baseboard_fab2(sch_1):page101_i114:a" )
			)
			( pin "FB2T2.2"
				( objectStatus "@baseboard_fab2_lib.baseboard_fab2(sch_1):page101_i114:b" )
			)
			( pin "C2T28.1"
				( objectStatus "@baseboard_fab2_lib.baseboard_fab2(sch_1):page101_i116:a" )
			)
			( pin "C2T28.2"
				( objectStatus "@baseboard_fab2_lib.baseboard_fab2(sch_1):page101_i116:b" )
			)
			( pin "R2T42.1"
				( objectStatus "@baseboard_fab2_lib.baseboard_fab2(sch_1):page101_i124:a" )
			)
			( pin "R2T42.2"
				( objectStatus "@baseboard_fab2_lib.baseboard_fab2(sch_1):page101_i124:b" )
			)
			( pin "R2T46.1"
				( objectStatus "@baseboard_fab2_lib.baseboard_fab2(sch_1):page101_i125:a" )
			)
			( pin "R2T46.2"
				( objectStatus "@baseboard_fab2_lib.baseboard_fab2(sch_1):page101_i125:b" )
			)
			( pin "R8G24.1"
				( objectStatus "@baseboard_fab2_lib.baseboard_fab2(sch_1):page101_i143:a" )
			)
			( pin "R8G24.2"
				( objectStatus "@baseboard_fab2_lib.baseboard_fab2(sch_1):page101_i143:b" )
			)
			( pin "R2T47.1"
				( objectStatus "@baseboard_fab2_lib.baseboard_fab2(sch_1):page101_i130:a" )
			)
			( pin "R2T47.2"
				( objectStatus "@baseboard_fab2_lib.baseboard_fab2(sch_1):page101_i130:b" )
			)
			( pin "EU4D2.4"
				( objectStatus "@baseboard_fab2_lib.baseboard_fab2(sch_1):page102_i1:\100m_133m_n\" )
			)
			( pin "EU4D2.10"
				( objectStatus "@baseboard_fab2_lib.baseboard_fab2(sch_1):page102_i1:clk_inn" )
			)
			( pin "EU4D2.9"
				( objectStatus "@baseboard_fab2_lib.baseboard_fab2(sch_1):page102_i1:clk_inp" )
			)
			( pin "EU4D2.18"
				( objectStatus "@baseboard_fab2_lib.baseboard_fab2(sch_1):page102_i1:dif_0n" )
			)
			( pin "EU4D2.17"
				( objectStatus "@baseboard_fab2_lib.baseboard_fab2(sch_1):page102_i1:dif_0p" )
			)
			( pin "EU4D2.22"
				( objectStatus "@baseboard_fab2_lib.baseboard_fab2(sch_1):page102_i1:dif_1n" )
			)
			( pin "EU4D2.21"
				( objectStatus "@baseboard_fab2_lib.baseboard_fab2(sch_1):page102_i1:dif_1p" )
			)
			( pin "EU4D2.27"
				( objectStatus "@baseboard_fab2_lib.baseboard_fab2(sch_1):page102_i1:dif_2n" )
			)
			( pin "EU4D2.26"
				( objectStatus "@baseboard_fab2_lib.baseboard_fab2(sch_1):page102_i1:dif_2p" )
			)
			( pin "EU4D2.31"
				( objectStatus "@baseboard_fab2_lib.baseboard_fab2(sch_1):page102_i1:dif_3n" )
			)
			( pin "EU4D2.30"
				( objectStatus "@baseboard_fab2_lib.baseboard_fab2(sch_1):page102_i1:dif_3p" )
			)
			( pin "EU4D2.35"
				( objectStatus "@baseboard_fab2_lib.baseboard_fab2(sch_1):page102_i1:dif_4n" )
			)
			( pin "EU4D2.34"
				( objectStatus "@baseboard_fab2_lib.baseboard_fab2(sch_1):page102_i1:dif_4p" )
			)
			( pin "EU4D2.39"
				( objectStatus "@baseboard_fab2_lib.baseboard_fab2(sch_1):page102_i1:dif_5n" )
			)
			( pin "EU4D2.38"
				( objectStatus "@baseboard_fab2_lib.baseboard_fab2(sch_1):page102_i1:dif_5p" )
			)
			( pin "EU4D2.43"
				( objectStatus "@baseboard_fab2_lib.baseboard_fab2(sch_1):page102_i1:dif_6n" )
			)
			( pin "EU4D2.42"
				( objectStatus "@baseboard_fab2_lib.baseboard_fab2(sch_1):page102_i1:dif_6p" )
			)
			( pin "EU4D2.47"
				( objectStatus "@baseboard_fab2_lib.baseboard_fab2(sch_1):page102_i1:dif_7n" )
			)
			( pin "EU4D2.46"
				( objectStatus "@baseboard_fab2_lib.baseboard_fab2(sch_1):page102_i1:dif_7p" )
			)
			( pin "EU4D2.51"
				( objectStatus "@baseboard_fab2_lib.baseboard_fab2(sch_1):page102_i1:dif_8n" )
			)
			( pin "EU4D2.50"
				( objectStatus "@baseboard_fab2_lib.baseboard_fab2(sch_1):page102_i1:dif_8p" )
			)
			( pin "EU4D2.55"
				( objectStatus "@baseboard_fab2_lib.baseboard_fab2(sch_1):page102_i1:dif_9n" )
			)
			( pin "EU4D2.54"
				( objectStatus "@baseboard_fab2_lib.baseboard_fab2(sch_1):page102_i1:dif_9p" )
			)
			( pin "EU4D2.60"
				( objectStatus "@baseboard_fab2_lib.baseboard_fab2(sch_1):page102_i1:dif_10n" )
			)
			( pin "EU4D2.59"
				( objectStatus "@baseboard_fab2_lib.baseboard_fab2(sch_1):page102_i1:dif_10p" )
			)
			( pin "EU4D2.64"
				( objectStatus "@baseboard_fab2_lib.baseboard_fab2(sch_1):page102_i1:dif_11n" )
			)
			( pin "EU4D2.63"
				( objectStatus "@baseboard_fab2_lib.baseboard_fab2(sch_1):page102_i1:dif_11p" )
			)
			( pin "EU4D2.7"
				( objectStatus "@baseboard_fab2_lib.baseboard_fab2(sch_1):page102_i1:gnd(0)" )
			)
			( pin "EU4D2.23"
				( objectStatus "@baseboard_fab2_lib.baseboard_fab2(sch_1):page102_i1:gnd(1)" )
			)
			( pin "EU4D2.33"
				( objectStatus "@baseboard_fab2_lib.baseboard_fab2(sch_1):page102_i1:gnd(2)" )
			)
			( pin "EU4D2.41"
				( objectStatus "@baseboard_fab2_lib.baseboard_fab2(sch_1):page102_i1:gnd(3)" )
			)
			( pin "EU4D2.48"
				( objectStatus "@baseboard_fab2_lib.baseboard_fab2(sch_1):page102_i1:gnd(4)" )
			)
			( pin "EU4D2.58"
				( objectStatus "@baseboard_fab2_lib.baseboard_fab2(sch_1):page102_i1:gnd(5)" )
			)
			( pin "EU4D2.2"
				( objectStatus "@baseboard_fab2_lib.baseboard_fab2(sch_1):page102_i1:gnda" )
			)
			( pin "EU4D2.5"
				( objectStatus "@baseboard_fab2_lib.baseboard_fab2(sch_1):page102_i1:hbw_bypass_lobw_n" )
			)
			( pin "EU4D2.3"
				( objectStatus "@baseboard_fab2_lib.baseboard_fab2(sch_1):page102_i1:nc(0)" )
			)
			( pin "EU4D2.16"
				( objectStatus "@baseboard_fab2_lib.baseboard_fab2(sch_1):page102_i1:nc(1)" )
			)
			( pin "EU4D2.15"
				( objectStatus "@baseboard_fab2_lib.baseboard_fab2(sch_1):page102_i1:nc(2)" )
			)
			( pin "EU4D2.19"
				( objectStatus "@baseboard_fab2_lib.baseboard_fab2(sch_1):page102_i1:oe_0_n" )
			)
			( pin "EU4D2.20"
				( objectStatus "@baseboard_fab2_lib.baseboard_fab2(sch_1):page102_i1:oe_1_n" )
			)
			( pin "EU4D2.28"
				( objectStatus "@baseboard_fab2_lib.baseboard_fab2(sch_1):page102_i1:oe_2_n" )
			)
			( pin "EU4D2.29"
				( objectStatus "@baseboard_fab2_lib.baseboard_fab2(sch_1):page102_i1:oe_3_n" )
			)
			( pin "EU4D2.36"
				( objectStatus "@baseboard_fab2_lib.baseboard_fab2(sch_1):page102_i1:oe_4_n" )
			)
			( pin "EU4D2.37"
				( objectStatus "@baseboard_fab2_lib.baseboard_fab2(sch_1):page102_i1:oe_5_n" )
			)
			( pin "EU4D2.44"
				( objectStatus "@baseboard_fab2_lib.baseboard_fab2(sch_1):page102_i1:oe_6_n" )
			)
			( pin "EU4D2.45"
				( objectStatus "@baseboard_fab2_lib.baseboard_fab2(sch_1):page102_i1:oe_7_n" )
			)
			( pin "EU4D2.52"
				( objectStatus "@baseboard_fab2_lib.baseboard_fab2(sch_1):page102_i1:oe_8_n" )
			)
			( pin "EU4D2.53"
				( objectStatus "@baseboard_fab2_lib.baseboard_fab2(sch_1):page102_i1:oe_9_n" )
			)
			( pin "EU4D2.61"
				( objectStatus "@baseboard_fab2_lib.baseboard_fab2(sch_1):page102_i1:oe_10_n" )
			)
			( pin "EU4D2.62"
				( objectStatus "@baseboard_fab2_lib.baseboard_fab2(sch_1):page102_i1:oe_11_n" )
			)
			( pin "EU4D2.6"
				( objectStatus "@baseboard_fab2_lib.baseboard_fab2(sch_1):page102_i1:pwrgd_pwrdn_n" )
			)
			( pin "EU4D2.11"
				( objectStatus "@baseboard_fab2_lib.baseboard_fab2(sch_1):page102_i1:sa_0" )
			)
			( pin "EU4D2.14"
				( objectStatus "@baseboard_fab2_lib.baseboard_fab2(sch_1):page102_i1:sa_1" )
			)
			( pin "EU4D2.13"
				( objectStatus "@baseboard_fab2_lib.baseboard_fab2(sch_1):page102_i1:scl" )
			)
			( pin "EU4D2.12"
				( objectStatus "@baseboard_fab2_lib.baseboard_fab2(sch_1):page102_i1:sda" )
			)
			( pin "EU4D2.65"
				( objectStatus "@baseboard_fab2_lib.baseboard_fab2(sch_1):page102_i1:thpad" )
			)
			( pin "EU4D2.24"
				( objectStatus "@baseboard_fab2_lib.baseboard_fab2(sch_1):page102_i1:vdd(0)" )
			)
			( pin "EU4D2.40"
				( objectStatus "@baseboard_fab2_lib.baseboard_fab2(sch_1):page102_i1:vdd(1)" )
			)
			( pin "EU4D2.57"
				( objectStatus "@baseboard_fab2_lib.baseboard_fab2(sch_1):page102_i1:vdd(2)" )
			)
			( pin "EU4D2.1"
				( objectStatus "@baseboard_fab2_lib.baseboard_fab2(sch_1):page102_i1:vdda" )
			)
			( pin "EU4D2.25"
				( objectStatus "@baseboard_fab2_lib.baseboard_fab2(sch_1):page102_i1:vddio(0)" )
			)
			( pin "EU4D2.32"
				( objectStatus "@baseboard_fab2_lib.baseboard_fab2(sch_1):page102_i1:vddio(1)" )
			)
			( pin "EU4D2.49"
				( objectStatus "@baseboard_fab2_lib.baseboard_fab2(sch_1):page102_i1:vddio(2)" )
			)
			( pin "EU4D2.56"
				( objectStatus "@baseboard_fab2_lib.baseboard_fab2(sch_1):page102_i1:vddio(3)" )
			)
			( pin "EU4D2.8"
				( objectStatus "@baseboard_fab2_lib.baseboard_fab2(sch_1):page102_i1:vddr" )
			)
			( pin "FB6P1.1"
				( objectStatus "@baseboard_fab2_lib.baseboard_fab2(sch_1):page102_i8:a" )
			)
			( pin "FB6P1.2"
				( objectStatus "@baseboard_fab2_lib.baseboard_fab2(sch_1):page102_i8:b" )
			)
			( pin "C3D22.1"
				( objectStatus "@baseboard_fab2_lib.baseboard_fab2(sch_1):page102_i10:a" )
			)
			( pin "C3D22.2"
				( objectStatus "@baseboard_fab2_lib.baseboard_fab2(sch_1):page102_i10:b" )
			)
			( pin "C6P4.1"
				( objectStatus "@baseboard_fab2_lib.baseboard_fab2(sch_1):page102_i11:a" )
			)
			( pin "C6P4.2"
				( objectStatus "@baseboard_fab2_lib.baseboard_fab2(sch_1):page102_i11:b" )
			)
			( pin "C6P6.1"
				( objectStatus "@baseboard_fab2_lib.baseboard_fab2(sch_1):page102_i12:a" )
			)
			( pin "C6P6.2"
				( objectStatus "@baseboard_fab2_lib.baseboard_fab2(sch_1):page102_i12:b" )
			)
			( pin "C6P10.1"
				( objectStatus "@baseboard_fab2_lib.baseboard_fab2(sch_1):page102_i13:a" )
			)
			( pin "C6P10.2"
				( objectStatus "@baseboard_fab2_lib.baseboard_fab2(sch_1):page102_i13:b" )
			)
			( pin "C6P5.1"
				( objectStatus "@baseboard_fab2_lib.baseboard_fab2(sch_1):page102_i14:a" )
			)
			( pin "C6P5.2"
				( objectStatus "@baseboard_fab2_lib.baseboard_fab2(sch_1):page102_i14:b" )
			)
			( pin "C6P12.1"
				( objectStatus "@baseboard_fab2_lib.baseboard_fab2(sch_1):page102_i15:a" )
			)
			( pin "C6P12.2"
				( objectStatus "@baseboard_fab2_lib.baseboard_fab2(sch_1):page102_i15:b" )
			)
			( pin "C6P11.1"
				( objectStatus "@baseboard_fab2_lib.baseboard_fab2(sch_1):page102_i16:a" )
			)
			( pin "C6P11.2"
				( objectStatus "@baseboard_fab2_lib.baseboard_fab2(sch_1):page102_i16:b" )
			)
			( pin "C4D24.1"
				( objectStatus "@baseboard_fab2_lib.baseboard_fab2(sch_1):page102_i18:a" )
			)
			( pin "C4D24.2"
				( objectStatus "@baseboard_fab2_lib.baseboard_fab2(sch_1):page102_i18:b" )
			)
			( pin "C4D23.1"
				( objectStatus "@baseboard_fab2_lib.baseboard_fab2(sch_1):page102_i19:a" )
			)
			( pin "C4D23.2"
				( objectStatus "@baseboard_fab2_lib.baseboard_fab2(sch_1):page102_i19:b" )
			)
			( pin "R3D14.1"
				( objectStatus "@baseboard_fab2_lib.baseboard_fab2(sch_1):page102_i21:a" )
			)
			( pin "R3D14.2"
				( objectStatus "@baseboard_fab2_lib.baseboard_fab2(sch_1):page102_i21:b" )
			)
			( pin "R6P25.1"
				( objectStatus "@baseboard_fab2_lib.baseboard_fab2(sch_1):page102_i26:a" )
			)
			( pin "R6P25.2"
				( objectStatus "@baseboard_fab2_lib.baseboard_fab2(sch_1):page102_i26:b" )
			)
			( pin "C4D22.1"
				( objectStatus "@baseboard_fab2_lib.baseboard_fab2(sch_1):page102_i28:a" )
			)
			( pin "C4D22.2"
				( objectStatus "@baseboard_fab2_lib.baseboard_fab2(sch_1):page102_i28:b" )
			)
			( pin "C4D27.1"
				( objectStatus "@baseboard_fab2_lib.baseboard_fab2(sch_1):page102_i30:a" )
			)
			( pin "C4D27.2"
				( objectStatus "@baseboard_fab2_lib.baseboard_fab2(sch_1):page102_i30:b" )
			)
			( pin "R4D38.1"
				( objectStatus "@baseboard_fab2_lib.baseboard_fab2(sch_1):page102_i37:a" )
			)
			( pin "R4D38.2"
				( objectStatus "@baseboard_fab2_lib.baseboard_fab2(sch_1):page102_i37:b" )
			)
			( pin "R4D35.1"
				( objectStatus "@baseboard_fab2_lib.baseboard_fab2(sch_1):page102_i38:a" )
			)
			( pin "R4D35.2"
				( objectStatus "@baseboard_fab2_lib.baseboard_fab2(sch_1):page102_i38:b" )
			)
			( pin "R4D40.1"
				( objectStatus "@baseboard_fab2_lib.baseboard_fab2(sch_1):page102_i45:a" )
			)
			( pin "R4D40.2"
				( objectStatus "@baseboard_fab2_lib.baseboard_fab2(sch_1):page102_i45:b" )
			)
			( pin "R6P23.1"
				( objectStatus "@baseboard_fab2_lib.baseboard_fab2(sch_1):page102_i46:a" )
			)
			( pin "R6P23.2"
				( objectStatus "@baseboard_fab2_lib.baseboard_fab2(sch_1):page102_i46:b" )
			)
			( pin "R6P22.1"
				( objectStatus "@baseboard_fab2_lib.baseboard_fab2(sch_1):page102_i47:a" )
			)
			( pin "R6P22.2"
				( objectStatus "@baseboard_fab2_lib.baseboard_fab2(sch_1):page102_i47:b" )
			)
			( pin "R4D41.1"
				( objectStatus "@baseboard_fab2_lib.baseboard_fab2(sch_1):page102_i53:a" )
			)
			( pin "R4D41.2"
				( objectStatus "@baseboard_fab2_lib.baseboard_fab2(sch_1):page102_i53:b" )
			)
			( pin "C6P9.1"
				( objectStatus "@baseboard_fab2_lib.baseboard_fab2(sch_1):page102_i79:a" )
			)
			( pin "C6P9.2"
				( objectStatus "@baseboard_fab2_lib.baseboard_fab2(sch_1):page102_i79:b" )
			)
			( pin "R6P21.1"
				( objectStatus "@baseboard_fab2_lib.baseboard_fab2(sch_1):page102_i80:a" )
			)
			( pin "R6P21.2"
				( objectStatus "@baseboard_fab2_lib.baseboard_fab2(sch_1):page102_i80:b" )
			)
			( pin "R6P20.1"
				( objectStatus "@baseboard_fab2_lib.baseboard_fab2(sch_1):page102_i81:a" )
			)
			( pin "R6P20.2"
				( objectStatus "@baseboard_fab2_lib.baseboard_fab2(sch_1):page102_i81:b" )
			)
			( pin "R4W3.1"
				( objectStatus "@baseboard_fab2_lib.baseboard_fab2(sch_1):page102_i105:a" )
			)
			( pin "R4W3.2"
				( objectStatus "@baseboard_fab2_lib.baseboard_fab2(sch_1):page102_i105:b" )
			)
			( pin "Q4W1.6"
				( objectStatus "@baseboard_fab2_lib.baseboard_fab2(sch_1):page102_i102:drain(0)" )
			)
			( pin "Q4W1.2"
				( objectStatus "@baseboard_fab2_lib.baseboard_fab2(sch_1):page102_i102:gate(0)" )
			)
			( pin "Q4W1.1"
				( objectStatus "@baseboard_fab2_lib.baseboard_fab2(sch_1):page102_i102:source(0)" )
			)
			( pin "R4D69.1"
				( objectStatus "@baseboard_fab2_lib.baseboard_fab2(sch_1):page102_i93:a" )
			)
			( pin "R4D69.2"
				( objectStatus "@baseboard_fab2_lib.baseboard_fab2(sch_1):page102_i93:b" )
			)
			( pin "R4D70.1"
				( objectStatus "@baseboard_fab2_lib.baseboard_fab2(sch_1):page102_i94:a" )
			)
			( pin "R4D70.2"
				( objectStatus "@baseboard_fab2_lib.baseboard_fab2(sch_1):page102_i94:b" )
			)
			( pin "R4D25.1"
				( objectStatus "@baseboard_fab2_lib.baseboard_fab2(sch_1):page103_i1:a" )
			)
			( pin "R4D25.2"
				( objectStatus "@baseboard_fab2_lib.baseboard_fab2(sch_1):page103_i1:b" )
			)
			( pin "R4D23.1"
				( objectStatus "@baseboard_fab2_lib.baseboard_fab2(sch_1):page103_i9:a" )
			)
			( pin "R4D23.2"
				( objectStatus "@baseboard_fab2_lib.baseboard_fab2(sch_1):page103_i9:b" )
			)
			( pin "R4D28.1"
				( objectStatus "@baseboard_fab2_lib.baseboard_fab2(sch_1):page103_i14:a" )
			)
			( pin "R4D28.2"
				( objectStatus "@baseboard_fab2_lib.baseboard_fab2(sch_1):page103_i14:b" )
			)
			( pin "R4D19.1"
				( objectStatus "@baseboard_fab2_lib.baseboard_fab2(sch_1):page103_i19:a" )
			)
			( pin "R4D19.2"
				( objectStatus "@baseboard_fab2_lib.baseboard_fab2(sch_1):page103_i19:b" )
			)
			( pin "R4D21.1"
				( objectStatus "@baseboard_fab2_lib.baseboard_fab2(sch_1):page103_i24:a" )
			)
			( pin "R4D21.2"
				( objectStatus "@baseboard_fab2_lib.baseboard_fab2(sch_1):page103_i24:b" )
			)
			( pin "R4D13.1"
				( objectStatus "@baseboard_fab2_lib.baseboard_fab2(sch_1):page103_i29:a" )
			)
			( pin "R4D13.2"
				( objectStatus "@baseboard_fab2_lib.baseboard_fab2(sch_1):page103_i29:b" )
			)
			( pin "R4D16.1"
				( objectStatus "@baseboard_fab2_lib.baseboard_fab2(sch_1):page103_i34:a" )
			)
			( pin "R4D16.2"
				( objectStatus "@baseboard_fab2_lib.baseboard_fab2(sch_1):page103_i34:b" )
			)
			( pin "R4D9.1"
				( objectStatus "@baseboard_fab2_lib.baseboard_fab2(sch_1):page103_i39:a" )
			)
			( pin "R4D9.2"
				( objectStatus "@baseboard_fab2_lib.baseboard_fab2(sch_1):page103_i39:b" )
			)
			( pin "R4D11.1"
				( objectStatus "@baseboard_fab2_lib.baseboard_fab2(sch_1):page103_i44:a" )
			)
			( pin "R4D11.2"
				( objectStatus "@baseboard_fab2_lib.baseboard_fab2(sch_1):page103_i44:b" )
			)
			( pin "R4D2.1"
				( objectStatus "@baseboard_fab2_lib.baseboard_fab2(sch_1):page103_i49:a" )
			)
			( pin "R4D2.2"
				( objectStatus "@baseboard_fab2_lib.baseboard_fab2(sch_1):page103_i49:b" )
			)
			( pin "R4D1.1"
				( objectStatus "@baseboard_fab2_lib.baseboard_fab2(sch_1):page103_i54:a" )
			)
			( pin "R4D1.2"
				( objectStatus "@baseboard_fab2_lib.baseboard_fab2(sch_1):page103_i54:b" )
			)
			( pin "R4D4.1"
				( objectStatus "@baseboard_fab2_lib.baseboard_fab2(sch_1):page103_i59:a" )
			)
			( pin "R4D4.2"
				( objectStatus "@baseboard_fab2_lib.baseboard_fab2(sch_1):page103_i59:b" )
			)
			( pin "R4D3.1"
				( objectStatus "@baseboard_fab2_lib.baseboard_fab2(sch_1):page103_i64:a" )
			)
			( pin "R4D3.2"
				( objectStatus "@baseboard_fab2_lib.baseboard_fab2(sch_1):page103_i64:b" )
			)
			( pin "R4D29.1"
				( objectStatus "@baseboard_fab2_lib.baseboard_fab2(sch_1):page103_i69:a" )
			)
			( pin "R4D29.2"
				( objectStatus "@baseboard_fab2_lib.baseboard_fab2(sch_1):page103_i69:b" )
			)
			( pin "R4D6.1"
				( objectStatus "@baseboard_fab2_lib.baseboard_fab2(sch_1):page103_i74:a" )
			)
			( pin "R4D6.2"
				( objectStatus "@baseboard_fab2_lib.baseboard_fab2(sch_1):page103_i74:b" )
			)
			( pin "R4D5.1"
				( objectStatus "@baseboard_fab2_lib.baseboard_fab2(sch_1):page103_i79:a" )
			)
			( pin "R4D5.2"
				( objectStatus "@baseboard_fab2_lib.baseboard_fab2(sch_1):page103_i79:b" )
			)
			( pin "R4D8.1"
				( objectStatus "@baseboard_fab2_lib.baseboard_fab2(sch_1):page103_i84:a" )
			)
			( pin "R4D8.2"
				( objectStatus "@baseboard_fab2_lib.baseboard_fab2(sch_1):page103_i84:b" )
			)
			( pin "R4D7.1"
				( objectStatus "@baseboard_fab2_lib.baseboard_fab2(sch_1):page103_i89:a" )
			)
			( pin "R4D7.2"
				( objectStatus "@baseboard_fab2_lib.baseboard_fab2(sch_1):page103_i89:b" )
			)
			( pin "R4D12.1"
				( objectStatus "@baseboard_fab2_lib.baseboard_fab2(sch_1):page103_i94:a" )
			)
			( pin "R4D12.2"
				( objectStatus "@baseboard_fab2_lib.baseboard_fab2(sch_1):page103_i94:b" )
			)
			( pin "R4D10.1"
				( objectStatus "@baseboard_fab2_lib.baseboard_fab2(sch_1):page103_i99:a" )
			)
			( pin "R4D10.2"
				( objectStatus "@baseboard_fab2_lib.baseboard_fab2(sch_1):page103_i99:b" )
			)
			( pin "R4D17.1"
				( objectStatus "@baseboard_fab2_lib.baseboard_fab2(sch_1):page103_i104:a" )
			)
			( pin "R4D17.2"
				( objectStatus "@baseboard_fab2_lib.baseboard_fab2(sch_1):page103_i104:b" )
			)
			( pin "R4D14.1"
				( objectStatus "@baseboard_fab2_lib.baseboard_fab2(sch_1):page103_i109:a" )
			)
			( pin "R4D14.2"
				( objectStatus "@baseboard_fab2_lib.baseboard_fab2(sch_1):page103_i109:b" )
			)
			( pin "R4D22.1"
				( objectStatus "@baseboard_fab2_lib.baseboard_fab2(sch_1):page103_i114:a" )
			)
			( pin "R4D22.2"
				( objectStatus "@baseboard_fab2_lib.baseboard_fab2(sch_1):page103_i114:b" )
			)
			( pin "R4D20.1"
				( objectStatus "@baseboard_fab2_lib.baseboard_fab2(sch_1):page103_i119:a" )
			)
			( pin "R4D20.2"
				( objectStatus "@baseboard_fab2_lib.baseboard_fab2(sch_1):page103_i119:b" )
			)
			( pin "R7P9.1"
				( objectStatus "@baseboard_fab2_lib.baseboard_fab2(sch_1):page103_i121:a" )
			)
			( pin "R7P9.2"
				( objectStatus "@baseboard_fab2_lib.baseboard_fab2(sch_1):page103_i121:b" )
			)
			( pin "R7P12.1"
				( objectStatus "@baseboard_fab2_lib.baseboard_fab2(sch_1):page103_i123:a" )
			)
			( pin "R7P12.2"
				( objectStatus "@baseboard_fab2_lib.baseboard_fab2(sch_1):page103_i123:b" )
			)
			( pin "R7P6.1"
				( objectStatus "@baseboard_fab2_lib.baseboard_fab2(sch_1):page103_i125:a" )
			)
			( pin "R7P6.2"
				( objectStatus "@baseboard_fab2_lib.baseboard_fab2(sch_1):page103_i125:b" )
			)
			( pin "R7P7.1"
				( objectStatus "@baseboard_fab2_lib.baseboard_fab2(sch_1):page103_i127:a" )
			)
			( pin "R7P7.2"
				( objectStatus "@baseboard_fab2_lib.baseboard_fab2(sch_1):page103_i127:b" )
			)
			( pin "R7P3.1"
				( objectStatus "@baseboard_fab2_lib.baseboard_fab2(sch_1):page103_i129:a" )
			)
			( pin "R7P3.2"
				( objectStatus "@baseboard_fab2_lib.baseboard_fab2(sch_1):page103_i129:b" )
			)
			( pin "R7P4.1"
				( objectStatus "@baseboard_fab2_lib.baseboard_fab2(sch_1):page103_i131:a" )
			)
			( pin "R7P4.2"
				( objectStatus "@baseboard_fab2_lib.baseboard_fab2(sch_1):page103_i131:b" )
			)
			( pin "R7P1.1"
				( objectStatus "@baseboard_fab2_lib.baseboard_fab2(sch_1):page103_i133:a" )
			)
			( pin "R7P1.2"
				( objectStatus "@baseboard_fab2_lib.baseboard_fab2(sch_1):page103_i133:b" )
			)
			( pin "R7P2.1"
				( objectStatus "@baseboard_fab2_lib.baseboard_fab2(sch_1):page103_i135:a" )
			)
			( pin "R7P2.2"
				( objectStatus "@baseboard_fab2_lib.baseboard_fab2(sch_1):page103_i135:b" )
			)
			( pin "R6P7.1"
				( objectStatus "@baseboard_fab2_lib.baseboard_fab2(sch_1):page103_i137:a" )
			)
			( pin "R6P7.2"
				( objectStatus "@baseboard_fab2_lib.baseboard_fab2(sch_1):page103_i137:b" )
			)
			( pin "R6P8.1"
				( objectStatus "@baseboard_fab2_lib.baseboard_fab2(sch_1):page103_i139:a" )
			)
			( pin "R6P8.2"
				( objectStatus "@baseboard_fab2_lib.baseboard_fab2(sch_1):page103_i139:b" )
			)
			( pin "R6P5.1"
				( objectStatus "@baseboard_fab2_lib.baseboard_fab2(sch_1):page103_i141:a" )
			)
			( pin "R6P5.2"
				( objectStatus "@baseboard_fab2_lib.baseboard_fab2(sch_1):page103_i141:b" )
			)
			( pin "R6P6.1"
				( objectStatus "@baseboard_fab2_lib.baseboard_fab2(sch_1):page103_i143:a" )
			)
			( pin "R6P6.2"
				( objectStatus "@baseboard_fab2_lib.baseboard_fab2(sch_1):page103_i143:b" )
			)
			( pin "R6P3.1"
				( objectStatus "@baseboard_fab2_lib.baseboard_fab2(sch_1):page103_i145:a" )
			)
			( pin "R6P3.2"
				( objectStatus "@baseboard_fab2_lib.baseboard_fab2(sch_1):page103_i145:b" )
			)
			( pin "R6P4.1"
				( objectStatus "@baseboard_fab2_lib.baseboard_fab2(sch_1):page103_i147:a" )
			)
			( pin "R6P4.2"
				( objectStatus "@baseboard_fab2_lib.baseboard_fab2(sch_1):page103_i147:b" )
			)
			( pin "R6P1.1"
				( objectStatus "@baseboard_fab2_lib.baseboard_fab2(sch_1):page103_i149:a" )
			)
			( pin "R6P1.2"
				( objectStatus "@baseboard_fab2_lib.baseboard_fab2(sch_1):page103_i149:b" )
			)
			( pin "R6P2.1"
				( objectStatus "@baseboard_fab2_lib.baseboard_fab2(sch_1):page103_i151:a" )
			)
			( pin "R6P2.2"
				( objectStatus "@baseboard_fab2_lib.baseboard_fab2(sch_1):page103_i151:b" )
			)
			( pin "R6P11.1"
				( objectStatus "@baseboard_fab2_lib.baseboard_fab2(sch_1):page103_i153:a" )
			)
			( pin "R6P11.2"
				( objectStatus "@baseboard_fab2_lib.baseboard_fab2(sch_1):page103_i153:b" )
			)
			( pin "R6P9.1"
				( objectStatus "@baseboard_fab2_lib.baseboard_fab2(sch_1):page103_i155:a" )
			)
			( pin "R6P9.2"
				( objectStatus "@baseboard_fab2_lib.baseboard_fab2(sch_1):page103_i155:b" )
			)
			( pin "R6P13.1"
				( objectStatus "@baseboard_fab2_lib.baseboard_fab2(sch_1):page103_i157:a" )
			)
			( pin "R6P13.2"
				( objectStatus "@baseboard_fab2_lib.baseboard_fab2(sch_1):page103_i157:b" )
			)
			( pin "R6P12.1"
				( objectStatus "@baseboard_fab2_lib.baseboard_fab2(sch_1):page103_i159:a" )
			)
			( pin "R6P12.2"
				( objectStatus "@baseboard_fab2_lib.baseboard_fab2(sch_1):page103_i159:b" )
			)
			( pin "R4D24.1"
				( objectStatus "@baseboard_fab2_lib.baseboard_fab2(sch_1):page103_i161:a" )
			)
			( pin "R4D24.2"
				( objectStatus "@baseboard_fab2_lib.baseboard_fab2(sch_1):page103_i161:b" )
			)
			( pin "R4D18.1"
				( objectStatus "@baseboard_fab2_lib.baseboard_fab2(sch_1):page103_i163:a" )
			)
			( pin "R4D18.2"
				( objectStatus "@baseboard_fab2_lib.baseboard_fab2(sch_1):page103_i163:b" )
			)
			( pin "R6P17.1"
				( objectStatus "@baseboard_fab2_lib.baseboard_fab2(sch_1):page103_i165:a" )
			)
			( pin "R6P17.2"
				( objectStatus "@baseboard_fab2_lib.baseboard_fab2(sch_1):page103_i165:b" )
			)
			( pin "R6P15.1"
				( objectStatus "@baseboard_fab2_lib.baseboard_fab2(sch_1):page103_i167:a" )
			)
			( pin "R6P15.2"
				( objectStatus "@baseboard_fab2_lib.baseboard_fab2(sch_1):page103_i167:b" )
			)
			( pin "C6F1.1"
				( objectStatus "@baseboard_fab2_lib.baseboard_fab2(sch_1):page104_i25:a" )
			)
			( pin "C6F1.2"
				( objectStatus "@baseboard_fab2_lib.baseboard_fab2(sch_1):page104_i25:b" )
			)
			( pin "C3F2.1"
				( objectStatus "@baseboard_fab2_lib.baseboard_fab2(sch_1):page104_i34:a" )
			)
			( pin "C3F2.2"
				( objectStatus "@baseboard_fab2_lib.baseboard_fab2(sch_1):page104_i34:b" )
			)
			( pin "R6F8.1"
				( objectStatus "@baseboard_fab2_lib.baseboard_fab2(sch_1):page104_i37:a" )
			)
			( pin "R6F8.2"
				( objectStatus "@baseboard_fab2_lib.baseboard_fab2(sch_1):page104_i37:b" )
			)
			( pin "R6F6.1"
				( objectStatus "@baseboard_fab2_lib.baseboard_fab2(sch_1):page104_i41:a" )
			)
			( pin "R6F6.2"
				( objectStatus "@baseboard_fab2_lib.baseboard_fab2(sch_1):page104_i41:b" )
			)
			( pin "R3F1.1"
				( objectStatus "@baseboard_fab2_lib.baseboard_fab2(sch_1):page104_i51:a" )
			)
			( pin "R3F1.2"
				( objectStatus "@baseboard_fab2_lib.baseboard_fab2(sch_1):page104_i51:b" )
			)
			( pin "R3F3.1"
				( objectStatus "@baseboard_fab2_lib.baseboard_fab2(sch_1):page104_i53:a" )
			)
			( pin "R3F3.2"
				( objectStatus "@baseboard_fab2_lib.baseboard_fab2(sch_1):page104_i53:b" )
			)
			( pin "R6F7.1"
				( objectStatus "@baseboard_fab2_lib.baseboard_fab2(sch_1):page104_i67:a" )
			)
			( pin "R6F7.2"
				( objectStatus "@baseboard_fab2_lib.baseboard_fab2(sch_1):page104_i67:b" )
			)
			( pin "R6F9.1"
				( objectStatus "@baseboard_fab2_lib.baseboard_fab2(sch_1):page104_i68:a" )
			)
			( pin "R6F9.2"
				( objectStatus "@baseboard_fab2_lib.baseboard_fab2(sch_1):page104_i68:b" )
			)
			( pin "R3F2.1"
				( objectStatus "@baseboard_fab2_lib.baseboard_fab2(sch_1):page104_i69:a" )
			)
			( pin "R3F2.2"
				( objectStatus "@baseboard_fab2_lib.baseboard_fab2(sch_1):page104_i69:b" )
			)
			( pin "R3F4.1"
				( objectStatus "@baseboard_fab2_lib.baseboard_fab2(sch_1):page104_i70:a" )
			)
			( pin "R3F4.2"
				( objectStatus "@baseboard_fab2_lib.baseboard_fab2(sch_1):page104_i70:b" )
			)
			( pin "Y6F1.1"
				( objectStatus "@baseboard_fab2_lib.baseboard_fab2(sch_1):page104_i71:enable_disable" )
			)
			( pin "Y6F1.3"
				( objectStatus "@baseboard_fab2_lib.baseboard_fab2(sch_1):page104_i71:gnd" )
			)
			( pin "Y6F1.2"
				( objectStatus "@baseboard_fab2_lib.baseboard_fab2(sch_1):page104_i71:nc_gnd" )
			)
			( pin "Y6F1.4"
				( objectStatus "@baseboard_fab2_lib.baseboard_fab2(sch_1):page104_i71:\out\" )
			)
			( pin "Y6F1.5"
				( objectStatus "@baseboard_fab2_lib.baseboard_fab2(sch_1):page104_i71:out_n" )
			)
			( pin "Y6F1.6"
				( objectStatus "@baseboard_fab2_lib.baseboard_fab2(sch_1):page104_i71:vcc" )
			)
			( pin "Y3F1.1"
				( objectStatus "@baseboard_fab2_lib.baseboard_fab2(sch_1):page104_i72:enable_disable" )
			)
			( pin "Y3F1.3"
				( objectStatus "@baseboard_fab2_lib.baseboard_fab2(sch_1):page104_i72:gnd" )
			)
			( pin "Y3F1.2"
				( objectStatus "@baseboard_fab2_lib.baseboard_fab2(sch_1):page104_i72:nc_gnd" )
			)
			( pin "Y3F1.4"
				( objectStatus "@baseboard_fab2_lib.baseboard_fab2(sch_1):page104_i72:\out\" )
			)
			( pin "Y3F1.5"
				( objectStatus "@baseboard_fab2_lib.baseboard_fab2(sch_1):page104_i72:out_n" )
			)
			( pin "Y3F1.6"
				( objectStatus "@baseboard_fab2_lib.baseboard_fab2(sch_1):page104_i72:vcc" )
			)
			( pin "R6F10.1"
				( objectStatus "@baseboard_fab2_lib.baseboard_fab2(sch_1):page104_i78:a" )
			)
			( pin "R6F10.2"
				( objectStatus "@baseboard_fab2_lib.baseboard_fab2(sch_1):page104_i78:b" )
			)
			( pin "R6F11.1"
				( objectStatus "@baseboard_fab2_lib.baseboard_fab2(sch_1):page104_i79:a" )
			)
			( pin "R6F11.2"
				( objectStatus "@baseboard_fab2_lib.baseboard_fab2(sch_1):page104_i79:b" )
			)
			( pin "R3F5.1"
				( objectStatus "@baseboard_fab2_lib.baseboard_fab2(sch_1):page104_i84:a" )
			)
			( pin "R3F5.2"
				( objectStatus "@baseboard_fab2_lib.baseboard_fab2(sch_1):page104_i84:b" )
			)
			( pin "R3F6.1"
				( objectStatus "@baseboard_fab2_lib.baseboard_fab2(sch_1):page104_i88:a" )
			)
			( pin "R3F6.2"
				( objectStatus "@baseboard_fab2_lib.baseboard_fab2(sch_1):page104_i88:b" )
			)
			( pin "R8D43.1"
				( objectStatus "@baseboard_fab2_lib.baseboard_fab2(sch_1):page104_i93:a" )
			)
			( pin "R8D43.2"
				( objectStatus "@baseboard_fab2_lib.baseboard_fab2(sch_1):page104_i93:b" )
			)
			( pin "R7D40.1"
				( objectStatus "@baseboard_fab2_lib.baseboard_fab2(sch_1):page104_i94:a" )
			)
			( pin "R7D40.2"
				( objectStatus "@baseboard_fab2_lib.baseboard_fab2(sch_1):page104_i94:b" )
			)
			( pin "R7D36.1"
				( objectStatus "@baseboard_fab2_lib.baseboard_fab2(sch_1):page104_i96:a" )
			)
			( pin "R7D36.2"
				( objectStatus "@baseboard_fab2_lib.baseboard_fab2(sch_1):page104_i96:b" )
			)
			( pin "R7D38.1"
				( objectStatus "@baseboard_fab2_lib.baseboard_fab2(sch_1):page104_i97:a" )
			)
			( pin "R7D38.2"
				( objectStatus "@baseboard_fab2_lib.baseboard_fab2(sch_1):page104_i97:b" )
			)
			( pin "C7G24.1"
				( objectStatus "@baseboard_fab2_lib.baseboard_fab2(sch_1):page105_i1:a" )
			)
			( pin "C7G24.2"
				( objectStatus "@baseboard_fab2_lib.baseboard_fab2(sch_1):page105_i1:b" )
			)
			( pin "C7G6.1"
				( objectStatus "@baseboard_fab2_lib.baseboard_fab2(sch_1):page105_i6:a" )
			)
			( pin "C7G6.2"
				( objectStatus "@baseboard_fab2_lib.baseboard_fab2(sch_1):page105_i6:b" )
			)
			( pin "C7G7.1"
				( objectStatus "@baseboard_fab2_lib.baseboard_fab2(sch_1):page105_i7:a" )
			)
			( pin "C7G7.2"
				( objectStatus "@baseboard_fab2_lib.baseboard_fab2(sch_1):page105_i7:b" )
			)
			( pin "C7G10.1"
				( objectStatus "@baseboard_fab2_lib.baseboard_fab2(sch_1):page105_i8:a" )
			)
			( pin "C7G10.2"
				( objectStatus "@baseboard_fab2_lib.baseboard_fab2(sch_1):page105_i8:b" )
			)
			( pin "C7G12.1"
				( objectStatus "@baseboard_fab2_lib.baseboard_fab2(sch_1):page105_i12:a" )
			)
			( pin "C7G12.2"
				( objectStatus "@baseboard_fab2_lib.baseboard_fab2(sch_1):page105_i12:b" )
			)
			( pin "C7G13.1"
				( objectStatus "@baseboard_fab2_lib.baseboard_fab2(sch_1):page105_i13:a" )
			)
			( pin "C7G13.2"
				( objectStatus "@baseboard_fab2_lib.baseboard_fab2(sch_1):page105_i13:b" )
			)
			( pin "C7G5.1"
				( objectStatus "@baseboard_fab2_lib.baseboard_fab2(sch_1):page105_i20:a" )
			)
			( pin "C7G5.2"
				( objectStatus "@baseboard_fab2_lib.baseboard_fab2(sch_1):page105_i20:b" )
			)
			( pin "C7G9.1"
				( objectStatus "@baseboard_fab2_lib.baseboard_fab2(sch_1):page105_i21:a" )
			)
			( pin "C7G9.2"
				( objectStatus "@baseboard_fab2_lib.baseboard_fab2(sch_1):page105_i21:b" )
			)
			( pin "C7G8.1"
				( objectStatus "@baseboard_fab2_lib.baseboard_fab2(sch_1):page105_i22:a" )
			)
			( pin "C7G8.2"
				( objectStatus "@baseboard_fab2_lib.baseboard_fab2(sch_1):page105_i22:b" )
			)
			( pin "C7G11.1"
				( objectStatus "@baseboard_fab2_lib.baseboard_fab2(sch_1):page105_i27:a" )
			)
			( pin "C7G11.2"
				( objectStatus "@baseboard_fab2_lib.baseboard_fab2(sch_1):page105_i27:b" )
			)
			( pin "C7G14.1"
				( objectStatus "@baseboard_fab2_lib.baseboard_fab2(sch_1):page105_i28:a" )
			)
			( pin "C7G14.2"
				( objectStatus "@baseboard_fab2_lib.baseboard_fab2(sch_1):page105_i28:b" )
			)
			( pin "C7G16.1"
				( objectStatus "@baseboard_fab2_lib.baseboard_fab2(sch_1):page105_i31:a" )
			)
			( pin "C7G16.2"
				( objectStatus "@baseboard_fab2_lib.baseboard_fab2(sch_1):page105_i31:b" )
			)
			( pin "C7G18.1"
				( objectStatus "@baseboard_fab2_lib.baseboard_fab2(sch_1):page105_i32:a" )
			)
			( pin "C7G18.2"
				( objectStatus "@baseboard_fab2_lib.baseboard_fab2(sch_1):page105_i32:b" )
			)
			( pin "C7G22.1"
				( objectStatus "@baseboard_fab2_lib.baseboard_fab2(sch_1):page105_i37:a" )
			)
			( pin "C7G22.2"
				( objectStatus "@baseboard_fab2_lib.baseboard_fab2(sch_1):page105_i37:b" )
			)
			( pin "C7G17.1"
				( objectStatus "@baseboard_fab2_lib.baseboard_fab2(sch_1):page105_i44:a" )
			)
			( pin "C7G17.2"
				( objectStatus "@baseboard_fab2_lib.baseboard_fab2(sch_1):page105_i44:b" )
			)
			( pin "C7G15.1"
				( objectStatus "@baseboard_fab2_lib.baseboard_fab2(sch_1):page105_i45:a" )
			)
			( pin "C7G15.2"
				( objectStatus "@baseboard_fab2_lib.baseboard_fab2(sch_1):page105_i45:b" )
			)
			( pin "C7G21.1"
				( objectStatus "@baseboard_fab2_lib.baseboard_fab2(sch_1):page105_i51:a" )
			)
			( pin "C7G21.2"
				( objectStatus "@baseboard_fab2_lib.baseboard_fab2(sch_1):page105_i51:b" )
			)
			( pin "C7G23.1"
				( objectStatus "@baseboard_fab2_lib.baseboard_fab2(sch_1):page105_i52:a" )
			)
			( pin "C7G23.2"
				( objectStatus "@baseboard_fab2_lib.baseboard_fab2(sch_1):page105_i52:b" )
			)
			( pin "C7G26.1"
				( objectStatus "@baseboard_fab2_lib.baseboard_fab2(sch_1):page105_i55:a" )
			)
			( pin "C7G26.2"
				( objectStatus "@baseboard_fab2_lib.baseboard_fab2(sch_1):page105_i55:b" )
			)
			( pin "C8G4.1"
				( objectStatus "@baseboard_fab2_lib.baseboard_fab2(sch_1):page105_i56:a" )
			)
			( pin "C8G4.2"
				( objectStatus "@baseboard_fab2_lib.baseboard_fab2(sch_1):page105_i56:b" )
			)
			( pin "C8G2.1"
				( objectStatus "@baseboard_fab2_lib.baseboard_fab2(sch_1):page105_i58:a" )
			)
			( pin "C8G2.2"
				( objectStatus "@baseboard_fab2_lib.baseboard_fab2(sch_1):page105_i58:b" )
			)
			( pin "C8G6.1"
				( objectStatus "@baseboard_fab2_lib.baseboard_fab2(sch_1):page105_i61:a" )
			)
			( pin "C8G6.2"
				( objectStatus "@baseboard_fab2_lib.baseboard_fab2(sch_1):page105_i61:b" )
			)
			( pin "C8G7.1"
				( objectStatus "@baseboard_fab2_lib.baseboard_fab2(sch_1):page105_i62:a" )
			)
			( pin "C8G7.2"
				( objectStatus "@baseboard_fab2_lib.baseboard_fab2(sch_1):page105_i62:b" )
			)
			( pin "C7G25.1"
				( objectStatus "@baseboard_fab2_lib.baseboard_fab2(sch_1):page105_i69:a" )
			)
			( pin "C7G25.2"
				( objectStatus "@baseboard_fab2_lib.baseboard_fab2(sch_1):page105_i69:b" )
			)
			( pin "C8G1.1"
				( objectStatus "@baseboard_fab2_lib.baseboard_fab2(sch_1):page105_i70:a" )
			)
			( pin "C8G1.2"
				( objectStatus "@baseboard_fab2_lib.baseboard_fab2(sch_1):page105_i70:b" )
			)
			( pin "C8G3.1"
				( objectStatus "@baseboard_fab2_lib.baseboard_fab2(sch_1):page105_i71:a" )
			)
			( pin "C8G3.2"
				( objectStatus "@baseboard_fab2_lib.baseboard_fab2(sch_1):page105_i71:b" )
			)
			( pin "C8G5.1"
				( objectStatus "@baseboard_fab2_lib.baseboard_fab2(sch_1):page105_i75:a" )
			)
			( pin "C8G5.2"
				( objectStatus "@baseboard_fab2_lib.baseboard_fab2(sch_1):page105_i75:b" )
			)
			( pin "C8G8.1"
				( objectStatus "@baseboard_fab2_lib.baseboard_fab2(sch_1):page105_i76:a" )
			)
			( pin "C8G8.2"
				( objectStatus "@baseboard_fab2_lib.baseboard_fab2(sch_1):page105_i76:b" )
			)
			( pin "C8G9.1"
				( objectStatus "@baseboard_fab2_lib.baseboard_fab2(sch_1):page105_i93:a" )
			)
			( pin "C8G9.2"
				( objectStatus "@baseboard_fab2_lib.baseboard_fab2(sch_1):page105_i93:b" )
			)
			( pin "C8G10.1"
				( objectStatus "@baseboard_fab2_lib.baseboard_fab2(sch_1):page105_i96:a" )
			)
			( pin "C8G10.2"
				( objectStatus "@baseboard_fab2_lib.baseboard_fab2(sch_1):page105_i96:b" )
			)
			( pin "C6B18.1"
				( objectStatus "@baseboard_fab2_lib.baseboard_fab2(sch_1):page105_i153:a" )
			)
			( pin "C6B18.2"
				( objectStatus "@baseboard_fab2_lib.baseboard_fab2(sch_1):page105_i153:b" )
			)
			( pin "C6B19.1"
				( objectStatus "@baseboard_fab2_lib.baseboard_fab2(sch_1):page105_i160:a" )
			)
			( pin "C6B19.2"
				( objectStatus "@baseboard_fab2_lib.baseboard_fab2(sch_1):page105_i160:b" )
			)
			( pin "C6B15.1"
				( objectStatus "@baseboard_fab2_lib.baseboard_fab2(sch_1):page105_i163:a" )
			)
			( pin "C6B15.2"
				( objectStatus "@baseboard_fab2_lib.baseboard_fab2(sch_1):page105_i163:b" )
			)
			( pin "C6B11.1"
				( objectStatus "@baseboard_fab2_lib.baseboard_fab2(sch_1):page105_i166:a" )
			)
			( pin "C6B11.2"
				( objectStatus "@baseboard_fab2_lib.baseboard_fab2(sch_1):page105_i166:b" )
			)
			( pin "C6B6.1"
				( objectStatus "@baseboard_fab2_lib.baseboard_fab2(sch_1):page105_i169:a" )
			)
			( pin "C6B6.2"
				( objectStatus "@baseboard_fab2_lib.baseboard_fab2(sch_1):page105_i169:b" )
			)
			( pin "C6B20.1"
				( objectStatus "@baseboard_fab2_lib.baseboard_fab2(sch_1):page105_i173:a" )
			)
			( pin "C6B20.2"
				( objectStatus "@baseboard_fab2_lib.baseboard_fab2(sch_1):page105_i173:b" )
			)
			( pin "C6B17.1"
				( objectStatus "@baseboard_fab2_lib.baseboard_fab2(sch_1):page105_i175:a" )
			)
			( pin "C6B17.2"
				( objectStatus "@baseboard_fab2_lib.baseboard_fab2(sch_1):page105_i175:b" )
			)
			( pin "C6B16.1"
				( objectStatus "@baseboard_fab2_lib.baseboard_fab2(sch_1):page105_i180:a" )
			)
			( pin "C6B16.2"
				( objectStatus "@baseboard_fab2_lib.baseboard_fab2(sch_1):page105_i180:b" )
			)
			( pin "C6B14.1"
				( objectStatus "@baseboard_fab2_lib.baseboard_fab2(sch_1):page105_i181:a" )
			)
			( pin "C6B14.2"
				( objectStatus "@baseboard_fab2_lib.baseboard_fab2(sch_1):page105_i181:b" )
			)
			( pin "C6B9.1"
				( objectStatus "@baseboard_fab2_lib.baseboard_fab2(sch_1):page105_i185:a" )
			)
			( pin "C6B9.2"
				( objectStatus "@baseboard_fab2_lib.baseboard_fab2(sch_1):page105_i185:b" )
			)
			( pin "C6B12.1"
				( objectStatus "@baseboard_fab2_lib.baseboard_fab2(sch_1):page105_i187:a" )
			)
			( pin "C6B12.2"
				( objectStatus "@baseboard_fab2_lib.baseboard_fab2(sch_1):page105_i187:b" )
			)
			( pin "C6B13.1"
				( objectStatus "@baseboard_fab2_lib.baseboard_fab2(sch_1):page105_i189:a" )
			)
			( pin "C6B13.2"
				( objectStatus "@baseboard_fab2_lib.baseboard_fab2(sch_1):page105_i189:b" )
			)
			( pin "C6B10.1"
				( objectStatus "@baseboard_fab2_lib.baseboard_fab2(sch_1):page105_i193:a" )
			)
			( pin "C6B10.2"
				( objectStatus "@baseboard_fab2_lib.baseboard_fab2(sch_1):page105_i193:b" )
			)
			( pin "C6B4.1"
				( objectStatus "@baseboard_fab2_lib.baseboard_fab2(sch_1):page105_i196:a" )
			)
			( pin "C6B4.2"
				( objectStatus "@baseboard_fab2_lib.baseboard_fab2(sch_1):page105_i196:b" )
			)
			( pin "C6B8.1"
				( objectStatus "@baseboard_fab2_lib.baseboard_fab2(sch_1):page105_i198:a" )
			)
			( pin "C6B8.2"
				( objectStatus "@baseboard_fab2_lib.baseboard_fab2(sch_1):page105_i198:b" )
			)
			( pin "C6B5.1"
				( objectStatus "@baseboard_fab2_lib.baseboard_fab2(sch_1):page105_i201:a" )
			)
			( pin "C6B5.2"
				( objectStatus "@baseboard_fab2_lib.baseboard_fab2(sch_1):page105_i201:b" )
			)
			( pin "C3M25.1"
				( objectStatus "@baseboard_fab2_lib.baseboard_fab2(sch_1):page105_i205:a" )
			)
			( pin "C3M25.2"
				( objectStatus "@baseboard_fab2_lib.baseboard_fab2(sch_1):page105_i205:b" )
			)
			( pin "C3M34.1"
				( objectStatus "@baseboard_fab2_lib.baseboard_fab2(sch_1):page105_i206:a" )
			)
			( pin "C3M34.2"
				( objectStatus "@baseboard_fab2_lib.baseboard_fab2(sch_1):page105_i206:b" )
			)
			( pin "C3M28.1"
				( objectStatus "@baseboard_fab2_lib.baseboard_fab2(sch_1):page105_i212:a" )
			)
			( pin "C3M28.2"
				( objectStatus "@baseboard_fab2_lib.baseboard_fab2(sch_1):page105_i212:b" )
			)
			( pin "C3M33.1"
				( objectStatus "@baseboard_fab2_lib.baseboard_fab2(sch_1):page105_i217:a" )
			)
			( pin "C3M33.2"
				( objectStatus "@baseboard_fab2_lib.baseboard_fab2(sch_1):page105_i217:b" )
			)
			( pin "C3M36.1"
				( objectStatus "@baseboard_fab2_lib.baseboard_fab2(sch_1):page105_i218:a" )
			)
			( pin "C3M36.2"
				( objectStatus "@baseboard_fab2_lib.baseboard_fab2(sch_1):page105_i218:b" )
			)
			( pin "C3M32.1"
				( objectStatus "@baseboard_fab2_lib.baseboard_fab2(sch_1):page105_i223:a" )
			)
			( pin "C3M32.2"
				( objectStatus "@baseboard_fab2_lib.baseboard_fab2(sch_1):page105_i223:b" )
			)
			( pin "C3M35.1"
				( objectStatus "@baseboard_fab2_lib.baseboard_fab2(sch_1):page105_i225:a" )
			)
			( pin "C3M35.2"
				( objectStatus "@baseboard_fab2_lib.baseboard_fab2(sch_1):page105_i225:b" )
			)
			( pin "C3M26.1"
				( objectStatus "@baseboard_fab2_lib.baseboard_fab2(sch_1):page105_i229:a" )
			)
			( pin "C3M26.2"
				( objectStatus "@baseboard_fab2_lib.baseboard_fab2(sch_1):page105_i229:b" )
			)
			( pin "C3M3.1"
				( objectStatus "@baseboard_fab2_lib.baseboard_fab2(sch_1):page105_i232:a" )
			)
			( pin "C3M3.2"
				( objectStatus "@baseboard_fab2_lib.baseboard_fab2(sch_1):page105_i232:b" )
			)
			( pin "C3M11.1"
				( objectStatus "@baseboard_fab2_lib.baseboard_fab2(sch_1):page105_i234:a" )
			)
			( pin "C3M11.2"
				( objectStatus "@baseboard_fab2_lib.baseboard_fab2(sch_1):page105_i234:b" )
			)
			( pin "C3M13.1"
				( objectStatus "@baseboard_fab2_lib.baseboard_fab2(sch_1):page105_i239:a" )
			)
			( pin "C3M13.2"
				( objectStatus "@baseboard_fab2_lib.baseboard_fab2(sch_1):page105_i239:b" )
			)
			( pin "C3M4.1"
				( objectStatus "@baseboard_fab2_lib.baseboard_fab2(sch_1):page105_i244:a" )
			)
			( pin "C3M4.2"
				( objectStatus "@baseboard_fab2_lib.baseboard_fab2(sch_1):page105_i244:b" )
			)
			( pin "C3M12.1"
				( objectStatus "@baseboard_fab2_lib.baseboard_fab2(sch_1):page105_i246:a" )
			)
			( pin "C3M12.2"
				( objectStatus "@baseboard_fab2_lib.baseboard_fab2(sch_1):page105_i246:b" )
			)
			( pin "C3M2.1"
				( objectStatus "@baseboard_fab2_lib.baseboard_fab2(sch_1):page105_i247:a" )
			)
			( pin "C3M2.2"
				( objectStatus "@baseboard_fab2_lib.baseboard_fab2(sch_1):page105_i247:b" )
			)
			( pin "C3M14.1"
				( objectStatus "@baseboard_fab2_lib.baseboard_fab2(sch_1):page105_i253:a" )
			)
			( pin "C3M14.2"
				( objectStatus "@baseboard_fab2_lib.baseboard_fab2(sch_1):page105_i253:b" )
			)
			( pin "C3M1.1"
				( objectStatus "@baseboard_fab2_lib.baseboard_fab2(sch_1):page105_i255:a" )
			)
			( pin "C3M1.2"
				( objectStatus "@baseboard_fab2_lib.baseboard_fab2(sch_1):page105_i255:b" )
			)
			( pin "C1R2.1"
				( objectStatus "@baseboard_fab2_lib.baseboard_fab2(sch_1):page106_i10:a" )
			)
			( pin "C1R2.2"
				( objectStatus "@baseboard_fab2_lib.baseboard_fab2(sch_1):page106_i10:b" )
			)
			( pin "C1R4.1"
				( objectStatus "@baseboard_fab2_lib.baseboard_fab2(sch_1):page106_i26:a" )
			)
			( pin "C1R4.2"
				( objectStatus "@baseboard_fab2_lib.baseboard_fab2(sch_1):page106_i26:b" )
			)
			( pin "C1R1.1"
				( objectStatus "@baseboard_fab2_lib.baseboard_fab2(sch_1):page106_i29:a" )
			)
			( pin "C1R1.2"
				( objectStatus "@baseboard_fab2_lib.baseboard_fab2(sch_1):page106_i29:b" )
			)
			( pin "C1R3.1"
				( objectStatus "@baseboard_fab2_lib.baseboard_fab2(sch_1):page106_i37:a" )
			)
			( pin "C1R3.2"
				( objectStatus "@baseboard_fab2_lib.baseboard_fab2(sch_1):page106_i37:b" )
			)
			( pin "C1R6.1"
				( objectStatus "@baseboard_fab2_lib.baseboard_fab2(sch_1):page106_i40:a" )
			)
			( pin "C1R6.2"
				( objectStatus "@baseboard_fab2_lib.baseboard_fab2(sch_1):page106_i40:b" )
			)
			( pin "C1R8.1"
				( objectStatus "@baseboard_fab2_lib.baseboard_fab2(sch_1):page106_i55:a" )
			)
			( pin "C1R8.2"
				( objectStatus "@baseboard_fab2_lib.baseboard_fab2(sch_1):page106_i55:b" )
			)
			( pin "C1R5.1"
				( objectStatus "@baseboard_fab2_lib.baseboard_fab2(sch_1):page106_i59:a" )
			)
			( pin "C1R5.2"
				( objectStatus "@baseboard_fab2_lib.baseboard_fab2(sch_1):page106_i59:b" )
			)
			( pin "C1R7.1"
				( objectStatus "@baseboard_fab2_lib.baseboard_fab2(sch_1):page106_i70:a" )
			)
			( pin "C1R7.2"
				( objectStatus "@baseboard_fab2_lib.baseboard_fab2(sch_1):page106_i70:b" )
			)
			( pin "C2M14.1"
				( objectStatus "@baseboard_fab2_lib.baseboard_fab2(sch_1):page106_i76:a" )
			)
			( pin "C2M14.2"
				( objectStatus "@baseboard_fab2_lib.baseboard_fab2(sch_1):page106_i76:b" )
			)
			( pin "C1M18.1"
				( objectStatus "@baseboard_fab2_lib.baseboard_fab2(sch_1):page106_i78:a" )
			)
			( pin "C1M18.2"
				( objectStatus "@baseboard_fab2_lib.baseboard_fab2(sch_1):page106_i78:b" )
			)
			( pin "C1M16.1"
				( objectStatus "@baseboard_fab2_lib.baseboard_fab2(sch_1):page106_i82:a" )
			)
			( pin "C1M16.2"
				( objectStatus "@baseboard_fab2_lib.baseboard_fab2(sch_1):page106_i82:b" )
			)
			( pin "C1M14.1"
				( objectStatus "@baseboard_fab2_lib.baseboard_fab2(sch_1):page106_i85:a" )
			)
			( pin "C1M14.2"
				( objectStatus "@baseboard_fab2_lib.baseboard_fab2(sch_1):page106_i85:b" )
			)
			( pin "C2M15.1"
				( objectStatus "@baseboard_fab2_lib.baseboard_fab2(sch_1):page106_i86:a" )
			)
			( pin "C2M15.2"
				( objectStatus "@baseboard_fab2_lib.baseboard_fab2(sch_1):page106_i86:b" )
			)
			( pin "C1M19.1"
				( objectStatus "@baseboard_fab2_lib.baseboard_fab2(sch_1):page106_i90:a" )
			)
			( pin "C1M19.2"
				( objectStatus "@baseboard_fab2_lib.baseboard_fab2(sch_1):page106_i90:b" )
			)
			( pin "C1M17.1"
				( objectStatus "@baseboard_fab2_lib.baseboard_fab2(sch_1):page106_i92:a" )
			)
			( pin "C1M17.2"
				( objectStatus "@baseboard_fab2_lib.baseboard_fab2(sch_1):page106_i92:b" )
			)
			( pin "C1M15.1"
				( objectStatus "@baseboard_fab2_lib.baseboard_fab2(sch_1):page106_i95:a" )
			)
			( pin "C1M15.2"
				( objectStatus "@baseboard_fab2_lib.baseboard_fab2(sch_1):page106_i95:b" )
			)
			( pin "C1M12.1"
				( objectStatus "@baseboard_fab2_lib.baseboard_fab2(sch_1):page106_i100:a" )
			)
			( pin "C1M12.2"
				( objectStatus "@baseboard_fab2_lib.baseboard_fab2(sch_1):page106_i100:b" )
			)
			( pin "C1M10.1"
				( objectStatus "@baseboard_fab2_lib.baseboard_fab2(sch_1):page106_i102:a" )
			)
			( pin "C1M10.2"
				( objectStatus "@baseboard_fab2_lib.baseboard_fab2(sch_1):page106_i102:b" )
			)
			( pin "C1M8.1"
				( objectStatus "@baseboard_fab2_lib.baseboard_fab2(sch_1):page106_i105:a" )
			)
			( pin "C1M8.2"
				( objectStatus "@baseboard_fab2_lib.baseboard_fab2(sch_1):page106_i105:b" )
			)
			( pin "C1M6.1"
				( objectStatus "@baseboard_fab2_lib.baseboard_fab2(sch_1):page106_i109:a" )
			)
			( pin "C1M6.2"
				( objectStatus "@baseboard_fab2_lib.baseboard_fab2(sch_1):page106_i109:b" )
			)
			( pin "C1M13.1"
				( objectStatus "@baseboard_fab2_lib.baseboard_fab2(sch_1):page106_i111:a" )
			)
			( pin "C1M13.2"
				( objectStatus "@baseboard_fab2_lib.baseboard_fab2(sch_1):page106_i111:b" )
			)
			( pin "C1M9.1"
				( objectStatus "@baseboard_fab2_lib.baseboard_fab2(sch_1):page106_i114:a" )
			)
			( pin "C1M9.2"
				( objectStatus "@baseboard_fab2_lib.baseboard_fab2(sch_1):page106_i114:b" )
			)
			( pin "C1M11.1"
				( objectStatus "@baseboard_fab2_lib.baseboard_fab2(sch_1):page106_i117:a" )
			)
			( pin "C1M11.2"
				( objectStatus "@baseboard_fab2_lib.baseboard_fab2(sch_1):page106_i117:b" )
			)
			( pin "C1M7.1"
				( objectStatus "@baseboard_fab2_lib.baseboard_fab2(sch_1):page106_i122:a" )
			)
			( pin "C1M7.2"
				( objectStatus "@baseboard_fab2_lib.baseboard_fab2(sch_1):page106_i122:b" )
			)
			( pin "C2R7.1"
				( objectStatus "@baseboard_fab2_lib.baseboard_fab2(sch_1):page106_i123:a" )
			)
			( pin "C2R7.2"
				( objectStatus "@baseboard_fab2_lib.baseboard_fab2(sch_1):page106_i123:b" )
			)
			( pin "C1R10.1"
				( objectStatus "@baseboard_fab2_lib.baseboard_fab2(sch_1):page106_i128:a" )
			)
			( pin "C1R10.2"
				( objectStatus "@baseboard_fab2_lib.baseboard_fab2(sch_1):page106_i128:b" )
			)
			( pin "C2R14.1"
				( objectStatus "@baseboard_fab2_lib.baseboard_fab2(sch_1):page106_i130:a" )
			)
			( pin "C2R14.2"
				( objectStatus "@baseboard_fab2_lib.baseboard_fab2(sch_1):page106_i130:b" )
			)
			( pin "C1R9.1"
				( objectStatus "@baseboard_fab2_lib.baseboard_fab2(sch_1):page106_i134:a" )
			)
			( pin "C1R9.2"
				( objectStatus "@baseboard_fab2_lib.baseboard_fab2(sch_1):page106_i134:b" )
			)
			( pin "C2R13.1"
				( objectStatus "@baseboard_fab2_lib.baseboard_fab2(sch_1):page106_i137:a" )
			)
			( pin "C2R13.2"
				( objectStatus "@baseboard_fab2_lib.baseboard_fab2(sch_1):page106_i137:b" )
			)
			( pin "C2R8.1"
				( objectStatus "@baseboard_fab2_lib.baseboard_fab2(sch_1):page106_i141:a" )
			)
			( pin "C2R8.2"
				( objectStatus "@baseboard_fab2_lib.baseboard_fab2(sch_1):page106_i141:b" )
			)
			( pin "C2R10.1"
				( objectStatus "@baseboard_fab2_lib.baseboard_fab2(sch_1):page106_i142:a" )
			)
			( pin "C2R10.2"
				( objectStatus "@baseboard_fab2_lib.baseboard_fab2(sch_1):page106_i142:b" )
			)
			( pin "C2R9.1"
				( objectStatus "@baseboard_fab2_lib.baseboard_fab2(sch_1):page106_i147:a" )
			)
			( pin "C2R9.2"
				( objectStatus "@baseboard_fab2_lib.baseboard_fab2(sch_1):page106_i147:b" )
			)
			( pin "C3P13.1"
				( objectStatus "@baseboard_fab2_lib.baseboard_fab2(sch_1):page107_i207:a" )
			)
			( pin "C3P13.2"
				( objectStatus "@baseboard_fab2_lib.baseboard_fab2(sch_1):page107_i207:b" )
			)
			( pin "C3P17.1"
				( objectStatus "@baseboard_fab2_lib.baseboard_fab2(sch_1):page107_i208:a" )
			)
			( pin "C3P17.2"
				( objectStatus "@baseboard_fab2_lib.baseboard_fab2(sch_1):page107_i208:b" )
			)
			( pin "C3P11.1"
				( objectStatus "@baseboard_fab2_lib.baseboard_fab2(sch_1):page107_i212:a" )
			)
			( pin "C3P11.2"
				( objectStatus "@baseboard_fab2_lib.baseboard_fab2(sch_1):page107_i212:b" )
			)
			( pin "C3P20.1"
				( objectStatus "@baseboard_fab2_lib.baseboard_fab2(sch_1):page107_i215:a" )
			)
			( pin "C3P20.2"
				( objectStatus "@baseboard_fab2_lib.baseboard_fab2(sch_1):page107_i215:b" )
			)
			( pin "C3P25.1"
				( objectStatus "@baseboard_fab2_lib.baseboard_fab2(sch_1):page107_i216:a" )
			)
			( pin "C3P25.2"
				( objectStatus "@baseboard_fab2_lib.baseboard_fab2(sch_1):page107_i216:b" )
			)
			( pin "C3P18.1"
				( objectStatus "@baseboard_fab2_lib.baseboard_fab2(sch_1):page107_i219:a" )
			)
			( pin "C3P18.2"
				( objectStatus "@baseboard_fab2_lib.baseboard_fab2(sch_1):page107_i219:b" )
			)
			( pin "C3P27.1"
				( objectStatus "@baseboard_fab2_lib.baseboard_fab2(sch_1):page107_i223:a" )
			)
			( pin "C3P27.2"
				( objectStatus "@baseboard_fab2_lib.baseboard_fab2(sch_1):page107_i223:b" )
			)
			( pin "C3P15.1"
				( objectStatus "@baseboard_fab2_lib.baseboard_fab2(sch_1):page107_i226:a" )
			)
			( pin "C3P15.2"
				( objectStatus "@baseboard_fab2_lib.baseboard_fab2(sch_1):page107_i226:b" )
			)
			( pin "C3P23.1"
				( objectStatus "@baseboard_fab2_lib.baseboard_fab2(sch_1):page107_i229:a" )
			)
			( pin "C3P23.2"
				( objectStatus "@baseboard_fab2_lib.baseboard_fab2(sch_1):page107_i229:b" )
			)
			( pin "C3P28.1"
				( objectStatus "@baseboard_fab2_lib.baseboard_fab2(sch_1):page107_i232:a" )
			)
			( pin "C3P28.2"
				( objectStatus "@baseboard_fab2_lib.baseboard_fab2(sch_1):page107_i232:b" )
			)
			( pin "C3P32.1"
				( objectStatus "@baseboard_fab2_lib.baseboard_fab2(sch_1):page107_i234:a" )
			)
			( pin "C3P32.2"
				( objectStatus "@baseboard_fab2_lib.baseboard_fab2(sch_1):page107_i234:b" )
			)
			( pin "C3P37.1"
				( objectStatus "@baseboard_fab2_lib.baseboard_fab2(sch_1):page107_i235:a" )
			)
			( pin "C3P37.2"
				( objectStatus "@baseboard_fab2_lib.baseboard_fab2(sch_1):page107_i235:b" )
			)
			( pin "C3P35.1"
				( objectStatus "@baseboard_fab2_lib.baseboard_fab2(sch_1):page107_i240:a" )
			)
			( pin "C3P35.2"
				( objectStatus "@baseboard_fab2_lib.baseboard_fab2(sch_1):page107_i240:b" )
			)
			( pin "C3P40.1"
				( objectStatus "@baseboard_fab2_lib.baseboard_fab2(sch_1):page107_i241:a" )
			)
			( pin "C3P40.2"
				( objectStatus "@baseboard_fab2_lib.baseboard_fab2(sch_1):page107_i241:b" )
			)
			( pin "C3P30.1"
				( objectStatus "@baseboard_fab2_lib.baseboard_fab2(sch_1):page107_i245:a" )
			)
			( pin "C3P30.2"
				( objectStatus "@baseboard_fab2_lib.baseboard_fab2(sch_1):page107_i245:b" )
			)
			( pin "C3P39.1"
				( objectStatus "@baseboard_fab2_lib.baseboard_fab2(sch_1):page107_i248:a" )
			)
			( pin "C3P39.2"
				( objectStatus "@baseboard_fab2_lib.baseboard_fab2(sch_1):page107_i248:b" )
			)
			( pin "C2U4.1"
				( objectStatus "@baseboard_fab2_lib.baseboard_fab2(sch_1):page107_i257:a" )
			)
			( pin "C2U4.2"
				( objectStatus "@baseboard_fab2_lib.baseboard_fab2(sch_1):page107_i257:b" )
			)
			( pin "C2U6.1"
				( objectStatus "@baseboard_fab2_lib.baseboard_fab2(sch_1):page107_i260:a" )
			)
			( pin "C2U6.2"
				( objectStatus "@baseboard_fab2_lib.baseboard_fab2(sch_1):page107_i260:b" )
			)
			( pin "C2U8.1"
				( objectStatus "@baseboard_fab2_lib.baseboard_fab2(sch_1):page107_i264:a" )
			)
			( pin "C2U8.2"
				( objectStatus "@baseboard_fab2_lib.baseboard_fab2(sch_1):page107_i264:b" )
			)
			( pin "C2U12.1"
				( objectStatus "@baseboard_fab2_lib.baseboard_fab2(sch_1):page107_i265:a" )
			)
			( pin "C2U12.2"
				( objectStatus "@baseboard_fab2_lib.baseboard_fab2(sch_1):page107_i265:b" )
			)
			( pin "C2U10.1"
				( objectStatus "@baseboard_fab2_lib.baseboard_fab2(sch_1):page107_i267:a" )
			)
			( pin "C2U10.2"
				( objectStatus "@baseboard_fab2_lib.baseboard_fab2(sch_1):page107_i267:b" )
			)
			( pin "C2U3.1"
				( objectStatus "@baseboard_fab2_lib.baseboard_fab2(sch_1):page107_i272:a" )
			)
			( pin "C2U3.2"
				( objectStatus "@baseboard_fab2_lib.baseboard_fab2(sch_1):page107_i272:b" )
			)
			( pin "C2U5.1"
				( objectStatus "@baseboard_fab2_lib.baseboard_fab2(sch_1):page107_i274:a" )
			)
			( pin "C2U5.2"
				( objectStatus "@baseboard_fab2_lib.baseboard_fab2(sch_1):page107_i274:b" )
			)
			( pin "C2U7.1"
				( objectStatus "@baseboard_fab2_lib.baseboard_fab2(sch_1):page107_i277:a" )
			)
			( pin "C2U7.2"
				( objectStatus "@baseboard_fab2_lib.baseboard_fab2(sch_1):page107_i277:b" )
			)
			( pin "C2U11.1"
				( objectStatus "@baseboard_fab2_lib.baseboard_fab2(sch_1):page107_i278:a" )
			)
			( pin "C2U11.2"
				( objectStatus "@baseboard_fab2_lib.baseboard_fab2(sch_1):page107_i278:b" )
			)
			( pin "C2U9.1"
				( objectStatus "@baseboard_fab2_lib.baseboard_fab2(sch_1):page107_i279:a" )
			)
			( pin "C2U9.2"
				( objectStatus "@baseboard_fab2_lib.baseboard_fab2(sch_1):page107_i279:b" )
			)
			( pin "C2U16.1"
				( objectStatus "@baseboard_fab2_lib.baseboard_fab2(sch_1):page107_i286:a" )
			)
			( pin "C2U16.2"
				( objectStatus "@baseboard_fab2_lib.baseboard_fab2(sch_1):page107_i286:b" )
			)
			( pin "C2U14.1"
				( objectStatus "@baseboard_fab2_lib.baseboard_fab2(sch_1):page107_i287:a" )
			)
			( pin "C2U14.2"
				( objectStatus "@baseboard_fab2_lib.baseboard_fab2(sch_1):page107_i287:b" )
			)
			( pin "C2U18.1"
				( objectStatus "@baseboard_fab2_lib.baseboard_fab2(sch_1):page107_i294:a" )
			)
			( pin "C2U18.2"
				( objectStatus "@baseboard_fab2_lib.baseboard_fab2(sch_1):page107_i294:b" )
			)
			( pin "C2U15.1"
				( objectStatus "@baseboard_fab2_lib.baseboard_fab2(sch_1):page107_i296:a" )
			)
			( pin "C2U15.2"
				( objectStatus "@baseboard_fab2_lib.baseboard_fab2(sch_1):page107_i296:b" )
			)
			( pin "C2U13.1"
				( objectStatus "@baseboard_fab2_lib.baseboard_fab2(sch_1):page107_i297:a" )
			)
			( pin "C2U13.2"
				( objectStatus "@baseboard_fab2_lib.baseboard_fab2(sch_1):page107_i297:b" )
			)
			( pin "C2U17.1"
				( objectStatus "@baseboard_fab2_lib.baseboard_fab2(sch_1):page107_i300:a" )
			)
			( pin "C2U17.2"
				( objectStatus "@baseboard_fab2_lib.baseboard_fab2(sch_1):page107_i300:b" )
			)
			( pin "C3P34.1"
				( objectStatus "@baseboard_fab2_lib.baseboard_fab2(sch_1):page107_i489:a" )
			)
			( pin "C3P34.2"
				( objectStatus "@baseboard_fab2_lib.baseboard_fab2(sch_1):page107_i489:b" )
			)
			( pin "R2U27.1"
				( objectStatus "@baseboard_fab2_lib.baseboard_fab2(sch_1):page107_i497:a" )
			)
			( pin "R2U27.2"
				( objectStatus "@baseboard_fab2_lib.baseboard_fab2(sch_1):page107_i497:b" )
			)
			( pin "C3P31.1"
				( objectStatus "@baseboard_fab2_lib.baseboard_fab2(sch_1):page107_i488:a" )
			)
			( pin "C3P31.2"
				( objectStatus "@baseboard_fab2_lib.baseboard_fab2(sch_1):page107_i488:b" )
			)
			( pin "C3P26.1"
				( objectStatus "@baseboard_fab2_lib.baseboard_fab2(sch_1):page107_i487:a" )
			)
			( pin "C3P26.2"
				( objectStatus "@baseboard_fab2_lib.baseboard_fab2(sch_1):page107_i487:b" )
			)
			( pin "C3P38.1"
				( objectStatus "@baseboard_fab2_lib.baseboard_fab2(sch_1):page107_i486:a" )
			)
			( pin "C3P38.2"
				( objectStatus "@baseboard_fab2_lib.baseboard_fab2(sch_1):page107_i486:b" )
			)
			( pin "R2U25.1"
				( objectStatus "@baseboard_fab2_lib.baseboard_fab2(sch_1):page107_i496:a" )
			)
			( pin "R2U25.2"
				( objectStatus "@baseboard_fab2_lib.baseboard_fab2(sch_1):page107_i496:b" )
			)
			( pin "R2U23.1"
				( objectStatus "@baseboard_fab2_lib.baseboard_fab2(sch_1):page107_i495:a" )
			)
			( pin "R2U23.2"
				( objectStatus "@baseboard_fab2_lib.baseboard_fab2(sch_1):page107_i495:b" )
			)
			( pin "R2U29.1"
				( objectStatus "@baseboard_fab2_lib.baseboard_fab2(sch_1):page107_i494:a" )
			)
			( pin "R2U29.2"
				( objectStatus "@baseboard_fab2_lib.baseboard_fab2(sch_1):page107_i494:b" )
			)
			( pin "C3P19.1"
				( objectStatus "@baseboard_fab2_lib.baseboard_fab2(sch_1):page107_i485:a" )
			)
			( pin "C3P19.2"
				( objectStatus "@baseboard_fab2_lib.baseboard_fab2(sch_1):page107_i485:b" )
			)
			( pin "C3P22.1"
				( objectStatus "@baseboard_fab2_lib.baseboard_fab2(sch_1):page107_i484:a" )
			)
			( pin "C3P22.2"
				( objectStatus "@baseboard_fab2_lib.baseboard_fab2(sch_1):page107_i484:b" )
			)
			( pin "C3P14.1"
				( objectStatus "@baseboard_fab2_lib.baseboard_fab2(sch_1):page107_i483:a" )
			)
			( pin "C3P14.2"
				( objectStatus "@baseboard_fab2_lib.baseboard_fab2(sch_1):page107_i483:b" )
			)
			( pin "R2U19.1"
				( objectStatus "@baseboard_fab2_lib.baseboard_fab2(sch_1):page107_i493:a" )
			)
			( pin "R2U19.2"
				( objectStatus "@baseboard_fab2_lib.baseboard_fab2(sch_1):page107_i493:b" )
			)
			( pin "R2U17.1"
				( objectStatus "@baseboard_fab2_lib.baseboard_fab2(sch_1):page107_i492:a" )
			)
			( pin "R2U17.2"
				( objectStatus "@baseboard_fab2_lib.baseboard_fab2(sch_1):page107_i492:b" )
			)
			( pin "C3P10.1"
				( objectStatus "@baseboard_fab2_lib.baseboard_fab2(sch_1):page107_i482:a" )
			)
			( pin "C3P10.2"
				( objectStatus "@baseboard_fab2_lib.baseboard_fab2(sch_1):page107_i482:b" )
			)
			( pin "R2U21.1"
				( objectStatus "@baseboard_fab2_lib.baseboard_fab2(sch_1):page107_i491:a" )
			)
			( pin "R2U21.2"
				( objectStatus "@baseboard_fab2_lib.baseboard_fab2(sch_1):page107_i491:b" )
			)
			( pin "R2U15.1"
				( objectStatus "@baseboard_fab2_lib.baseboard_fab2(sch_1):page107_i490:a" )
			)
			( pin "R2U15.2"
				( objectStatus "@baseboard_fab2_lib.baseboard_fab2(sch_1):page107_i490:b" )
			)
			( pin "RF13.1"
				( objectStatus "@baseboard_fab2_lib.baseboard_fab2(sch_1):page211_i96:a" )
			)
			( pin "RF13.2"
				( objectStatus "@baseboard_fab2_lib.baseboard_fab2(sch_1):page211_i96:b" )
			)
			( pin "C4G23.1"
				( objectStatus "@baseboard_fab2_lib.baseboard_fab2(sch_1):page221_i2:a" )
			)
			( pin "C4G23.2"
				( objectStatus "@baseboard_fab2_lib.baseboard_fab2(sch_1):page221_i2:b" )
			)
			( pin "C2U20.1"
				( objectStatus "@baseboard_fab2_lib.baseboard_fab2(sch_1):page108_i1:a" )
			)
			( pin "C2U20.2"
				( objectStatus "@baseboard_fab2_lib.baseboard_fab2(sch_1):page108_i1:b" )
			)
			( pin "C2U24.1"
				( objectStatus "@baseboard_fab2_lib.baseboard_fab2(sch_1):page108_i2:a" )
			)
			( pin "C2U24.2"
				( objectStatus "@baseboard_fab2_lib.baseboard_fab2(sch_1):page108_i2:b" )
			)
			( pin "C2U21.1"
				( objectStatus "@baseboard_fab2_lib.baseboard_fab2(sch_1):page108_i5:a" )
			)
			( pin "C2U21.2"
				( objectStatus "@baseboard_fab2_lib.baseboard_fab2(sch_1):page108_i5:b" )
			)
			( pin "C2U25.1"
				( objectStatus "@baseboard_fab2_lib.baseboard_fab2(sch_1):page108_i7:a" )
			)
			( pin "C2U25.2"
				( objectStatus "@baseboard_fab2_lib.baseboard_fab2(sch_1):page108_i7:b" )
			)
			( pin "R2U37.1"
				( objectStatus "@baseboard_fab2_lib.baseboard_fab2(sch_1):page108_i173:a" )
			)
			( pin "R2U37.2"
				( objectStatus "@baseboard_fab2_lib.baseboard_fab2(sch_1):page108_i173:b" )
			)
			( pin "J8G1.1"
				( objectStatus "@baseboard_fab2_lib.baseboard_fab2(sch_1):page108_i258:io1" )
			)
			( pin "J8G1.2"
				( objectStatus "@baseboard_fab2_lib.baseboard_fab2(sch_1):page108_i258:io2" )
			)
			( pin "J8G1.3"
				( objectStatus "@baseboard_fab2_lib.baseboard_fab2(sch_1):page108_i258:io3" )
			)
			( pin "J8G1.4"
				( objectStatus "@baseboard_fab2_lib.baseboard_fab2(sch_1):page108_i258:io4" )
			)
			( pin "J8G1.5"
				( objectStatus "@baseboard_fab2_lib.baseboard_fab2(sch_1):page108_i258:io5" )
			)
			( pin "J8G1.6"
				( objectStatus "@baseboard_fab2_lib.baseboard_fab2(sch_1):page108_i258:io6" )
			)
			( pin "J8G1.7"
				( objectStatus "@baseboard_fab2_lib.baseboard_fab2(sch_1):page108_i258:io7" )
			)
			( pin "J8G1.8"
				( objectStatus "@baseboard_fab2_lib.baseboard_fab2(sch_1):page108_i258:io8" )
			)
			( pin "J8G1.9"
				( objectStatus "@baseboard_fab2_lib.baseboard_fab2(sch_1):page108_i258:io9" )
			)
			( pin "J8G1.10"
				( objectStatus "@baseboard_fab2_lib.baseboard_fab2(sch_1):page108_i258:io10" )
			)
			( pin "J8G1.11"
				( objectStatus "@baseboard_fab2_lib.baseboard_fab2(sch_1):page108_i258:io11" )
			)
			( pin "J8G1.12"
				( objectStatus "@baseboard_fab2_lib.baseboard_fab2(sch_1):page108_i258:io12" )
			)
			( pin "J8G1.13"
				( objectStatus "@baseboard_fab2_lib.baseboard_fab2(sch_1):page108_i258:io13" )
			)
			( pin "J8G1.14"
				( objectStatus "@baseboard_fab2_lib.baseboard_fab2(sch_1):page108_i258:io14" )
			)
			( pin "J8G1.15"
				( objectStatus "@baseboard_fab2_lib.baseboard_fab2(sch_1):page108_i258:io15" )
			)
			( pin "J8G1.16"
				( objectStatus "@baseboard_fab2_lib.baseboard_fab2(sch_1):page108_i258:io16" )
			)
			( pin "J8G1.17"
				( objectStatus "@baseboard_fab2_lib.baseboard_fab2(sch_1):page108_i258:io17" )
			)
			( pin "J8G1.18"
				( objectStatus "@baseboard_fab2_lib.baseboard_fab2(sch_1):page108_i258:io18" )
			)
			( pin "J8G1.19"
				( objectStatus "@baseboard_fab2_lib.baseboard_fab2(sch_1):page108_i258:io19" )
			)
			( pin "J8G1.20"
				( objectStatus "@baseboard_fab2_lib.baseboard_fab2(sch_1):page108_i258:io20" )
			)
			( pin "J8G1.21"
				( objectStatus "@baseboard_fab2_lib.baseboard_fab2(sch_1):page108_i258:io21" )
			)
			( pin "J8G1.22"
				( objectStatus "@baseboard_fab2_lib.baseboard_fab2(sch_1):page108_i258:io22" )
			)
			( pin "J8G1.23"
				( objectStatus "@baseboard_fab2_lib.baseboard_fab2(sch_1):page108_i258:io23" )
			)
			( pin "J8G1.24"
				( objectStatus "@baseboard_fab2_lib.baseboard_fab2(sch_1):page108_i258:io24" )
			)
			( pin "J8G1.25"
				( objectStatus "@baseboard_fab2_lib.baseboard_fab2(sch_1):page108_i258:io25" )
			)
			( pin "J8G1.26"
				( objectStatus "@baseboard_fab2_lib.baseboard_fab2(sch_1):page108_i258:io26" )
			)
			( pin "J8G1.27"
				( objectStatus "@baseboard_fab2_lib.baseboard_fab2(sch_1):page108_i258:io27" )
			)
			( pin "J8G1.28"
				( objectStatus "@baseboard_fab2_lib.baseboard_fab2(sch_1):page108_i258:io28" )
			)
			( pin "J8G1.29"
				( objectStatus "@baseboard_fab2_lib.baseboard_fab2(sch_1):page108_i258:io29" )
			)
			( pin "J8G1.30"
				( objectStatus "@baseboard_fab2_lib.baseboard_fab2(sch_1):page108_i258:io30" )
			)
			( pin "J8G1.31"
				( objectStatus "@baseboard_fab2_lib.baseboard_fab2(sch_1):page108_i258:io31" )
			)
			( pin "J8G1.32"
				( objectStatus "@baseboard_fab2_lib.baseboard_fab2(sch_1):page108_i258:io32" )
			)
			( pin "J8G1.33"
				( objectStatus "@baseboard_fab2_lib.baseboard_fab2(sch_1):page108_i258:io33" )
			)
			( pin "J8G1.34"
				( objectStatus "@baseboard_fab2_lib.baseboard_fab2(sch_1):page108_i258:io34" )
			)
			( pin "J8G1.35"
				( objectStatus "@baseboard_fab2_lib.baseboard_fab2(sch_1):page108_i258:io35" )
			)
			( pin "J8G1.36"
				( objectStatus "@baseboard_fab2_lib.baseboard_fab2(sch_1):page108_i258:io36" )
			)
			( pin "J8G1.37"
				( objectStatus "@baseboard_fab2_lib.baseboard_fab2(sch_1):page108_i258:io37" )
			)
			( pin "J8G1.38"
				( objectStatus "@baseboard_fab2_lib.baseboard_fab2(sch_1):page108_i258:io38" )
			)
			( pin "J8G1.39"
				( objectStatus "@baseboard_fab2_lib.baseboard_fab2(sch_1):page108_i258:io39" )
			)
			( pin "J8G1.40"
				( objectStatus "@baseboard_fab2_lib.baseboard_fab2(sch_1):page108_i258:io40" )
			)
			( pin "J8G1.41"
				( objectStatus "@baseboard_fab2_lib.baseboard_fab2(sch_1):page108_i258:io41" )
			)
			( pin "J8G1.42"
				( objectStatus "@baseboard_fab2_lib.baseboard_fab2(sch_1):page108_i258:io42" )
			)
			( pin "J8G1.43"
				( objectStatus "@baseboard_fab2_lib.baseboard_fab2(sch_1):page108_i258:io43" )
			)
			( pin "J8G1.44"
				( objectStatus "@baseboard_fab2_lib.baseboard_fab2(sch_1):page108_i258:io44" )
			)
			( pin "J8G1.45"
				( objectStatus "@baseboard_fab2_lib.baseboard_fab2(sch_1):page108_i258:io45" )
			)
			( pin "J8G1.46"
				( objectStatus "@baseboard_fab2_lib.baseboard_fab2(sch_1):page108_i258:io46" )
			)
			( pin "J8G1.47"
				( objectStatus "@baseboard_fab2_lib.baseboard_fab2(sch_1):page108_i258:io47" )
			)
			( pin "J8G1.48"
				( objectStatus "@baseboard_fab2_lib.baseboard_fab2(sch_1):page108_i258:io48" )
			)
			( pin "J8G1.49"
				( objectStatus "@baseboard_fab2_lib.baseboard_fab2(sch_1):page108_i258:io49" )
			)
			( pin "J8G1.50"
				( objectStatus "@baseboard_fab2_lib.baseboard_fab2(sch_1):page108_i258:io50" )
			)
			( pin "J8G1.51"
				( objectStatus "@baseboard_fab2_lib.baseboard_fab2(sch_1):page108_i258:io51" )
			)
			( pin "J8G1.52"
				( objectStatus "@baseboard_fab2_lib.baseboard_fab2(sch_1):page108_i258:io52" )
			)
			( pin "J8G1.53"
				( objectStatus "@baseboard_fab2_lib.baseboard_fab2(sch_1):page108_i258:io53" )
			)
			( pin "J8G1.54"
				( objectStatus "@baseboard_fab2_lib.baseboard_fab2(sch_1):page108_i258:io54" )
			)
			( pin "J8G1.55"
				( objectStatus "@baseboard_fab2_lib.baseboard_fab2(sch_1):page108_i258:io55" )
			)
			( pin "J8G1.56"
				( objectStatus "@baseboard_fab2_lib.baseboard_fab2(sch_1):page108_i258:io56" )
			)
			( pin "J8G1.57"
				( objectStatus "@baseboard_fab2_lib.baseboard_fab2(sch_1):page108_i258:io57" )
			)
			( pin "J8G1.58"
				( objectStatus "@baseboard_fab2_lib.baseboard_fab2(sch_1):page108_i258:io58" )
			)
			( pin "J8G1.59"
				( objectStatus "@baseboard_fab2_lib.baseboard_fab2(sch_1):page108_i258:io59" )
			)
			( pin "J8G1.60"
				( objectStatus "@baseboard_fab2_lib.baseboard_fab2(sch_1):page108_i258:io60" )
			)
			( pin "J8G1.61"
				( objectStatus "@baseboard_fab2_lib.baseboard_fab2(sch_1):page108_i258:io61" )
			)
			( pin "J8G1.62"
				( objectStatus "@baseboard_fab2_lib.baseboard_fab2(sch_1):page108_i258:io62" )
			)
			( pin "J8G1.63"
				( objectStatus "@baseboard_fab2_lib.baseboard_fab2(sch_1):page108_i258:io63" )
			)
			( pin "J8G1.64"
				( objectStatus "@baseboard_fab2_lib.baseboard_fab2(sch_1):page108_i258:io64" )
			)
			( pin "J8G1.65"
				( objectStatus "@baseboard_fab2_lib.baseboard_fab2(sch_1):page108_i258:io65" )
			)
			( pin "J8G1.66"
				( objectStatus "@baseboard_fab2_lib.baseboard_fab2(sch_1):page108_i258:io66" )
			)
			( pin "J8G1.67"
				( objectStatus "@baseboard_fab2_lib.baseboard_fab2(sch_1):page108_i258:io67" )
			)
			( pin "J8G1.68"
				( objectStatus "@baseboard_fab2_lib.baseboard_fab2(sch_1):page108_i258:io68" )
			)
			( pin "J8G1.69"
				( objectStatus "@baseboard_fab2_lib.baseboard_fab2(sch_1):page108_i258:io69" )
			)
			( pin "J8G1.70"
				( objectStatus "@baseboard_fab2_lib.baseboard_fab2(sch_1):page108_i258:io70" )
			)
			( pin "J8G1.71"
				( objectStatus "@baseboard_fab2_lib.baseboard_fab2(sch_1):page108_i258:io71" )
			)
			( pin "J8G1.72"
				( objectStatus "@baseboard_fab2_lib.baseboard_fab2(sch_1):page108_i258:io72" )
			)
			( pin "J8G1.73"
				( objectStatus "@baseboard_fab2_lib.baseboard_fab2(sch_1):page108_i258:io73" )
			)
			( pin "J8G1.74"
				( objectStatus "@baseboard_fab2_lib.baseboard_fab2(sch_1):page108_i258:io74" )
			)
			( pin "J8G1.75"
				( objectStatus "@baseboard_fab2_lib.baseboard_fab2(sch_1):page108_i258:io75" )
			)
			( pin "J8G1.76"
				( objectStatus "@baseboard_fab2_lib.baseboard_fab2(sch_1):page108_i258:io76" )
			)
			( pin "J8G1.77"
				( objectStatus "@baseboard_fab2_lib.baseboard_fab2(sch_1):page108_i258:io77" )
			)
			( pin "J8G1.78"
				( objectStatus "@baseboard_fab2_lib.baseboard_fab2(sch_1):page108_i258:io78" )
			)
			( pin "J8G1.79"
				( objectStatus "@baseboard_fab2_lib.baseboard_fab2(sch_1):page108_i258:io79" )
			)
			( pin "J8G1.80"
				( objectStatus "@baseboard_fab2_lib.baseboard_fab2(sch_1):page108_i258:io80" )
			)
			( pin "J8G1.81"
				( objectStatus "@baseboard_fab2_lib.baseboard_fab2(sch_1):page108_i258:io81" )
			)
			( pin "J8G1.82"
				( objectStatus "@baseboard_fab2_lib.baseboard_fab2(sch_1):page108_i258:io82" )
			)
			( pin "J8G1.83"
				( objectStatus "@baseboard_fab2_lib.baseboard_fab2(sch_1):page108_i258:io83" )
			)
			( pin "J8G1.84"
				( objectStatus "@baseboard_fab2_lib.baseboard_fab2(sch_1):page108_i258:io84" )
			)
			( pin "J8G1.85"
				( objectStatus "@baseboard_fab2_lib.baseboard_fab2(sch_1):page108_i258:io85" )
			)
			( pin "J8G1.86"
				( objectStatus "@baseboard_fab2_lib.baseboard_fab2(sch_1):page108_i258:io86" )
			)
			( pin "J8G1.87"
				( objectStatus "@baseboard_fab2_lib.baseboard_fab2(sch_1):page108_i258:io87" )
			)
			( pin "J8G1.88"
				( objectStatus "@baseboard_fab2_lib.baseboard_fab2(sch_1):page108_i258:io88" )
			)
			( pin "J8G1.89"
				( objectStatus "@baseboard_fab2_lib.baseboard_fab2(sch_1):page108_i258:io89" )
			)
			( pin "J8G1.90"
				( objectStatus "@baseboard_fab2_lib.baseboard_fab2(sch_1):page108_i258:io90" )
			)
			( pin "J8G1.91"
				( objectStatus "@baseboard_fab2_lib.baseboard_fab2(sch_1):page108_i258:io91" )
			)
			( pin "J8G1.92"
				( objectStatus "@baseboard_fab2_lib.baseboard_fab2(sch_1):page108_i258:io92" )
			)
			( pin "J8G1.93"
				( objectStatus "@baseboard_fab2_lib.baseboard_fab2(sch_1):page108_i258:io93" )
			)
			( pin "J8G1.94"
				( objectStatus "@baseboard_fab2_lib.baseboard_fab2(sch_1):page108_i258:io94" )
			)
			( pin "J8G1.95"
				( objectStatus "@baseboard_fab2_lib.baseboard_fab2(sch_1):page108_i258:io95" )
			)
			( pin "J8G1.96"
				( objectStatus "@baseboard_fab2_lib.baseboard_fab2(sch_1):page108_i258:io96" )
			)
			( pin "J8G1.97"
				( objectStatus "@baseboard_fab2_lib.baseboard_fab2(sch_1):page108_i258:io97" )
			)
			( pin "J8G1.98"
				( objectStatus "@baseboard_fab2_lib.baseboard_fab2(sch_1):page108_i258:io98" )
			)
			( pin "J8G1.99"
				( objectStatus "@baseboard_fab2_lib.baseboard_fab2(sch_1):page108_i258:io99" )
			)
			( pin "J8G1.100"
				( objectStatus "@baseboard_fab2_lib.baseboard_fab2(sch_1):page108_i258:io100" )
			)
			( pin "J8G1.MH1"
				( objectStatus "@baseboard_fab2_lib.baseboard_fab2(sch_1):page108_i258:mh1" )
			)
			( pin "J8G1.MH2"
				( objectStatus "@baseboard_fab2_lib.baseboard_fab2(sch_1):page108_i258:mh2" )
			)
			( pin "C2U23.1"
				( objectStatus "@baseboard_fab2_lib.baseboard_fab2(sch_1):page108_i315:a" )
			)
			( pin "C2U23.2"
				( objectStatus "@baseboard_fab2_lib.baseboard_fab2(sch_1):page108_i315:b" )
			)
			( pin "C2U22.1"
				( objectStatus "@baseboard_fab2_lib.baseboard_fab2(sch_1):page108_i318:a" )
			)
			( pin "C2U22.2"
				( objectStatus "@baseboard_fab2_lib.baseboard_fab2(sch_1):page108_i318:b" )
			)
			( pin "R2U31.1"
				( objectStatus "@baseboard_fab2_lib.baseboard_fab2(sch_1):page108_i330:a" )
			)
			( pin "R2U31.2"
				( objectStatus "@baseboard_fab2_lib.baseboard_fab2(sch_1):page108_i330:b" )
			)
			( pin "R2U32.1"
				( objectStatus "@baseboard_fab2_lib.baseboard_fab2(sch_1):page108_i339:a" )
			)
			( pin "R2U32.2"
				( objectStatus "@baseboard_fab2_lib.baseboard_fab2(sch_1):page108_i339:b" )
			)
			( pin "R7E22.1"
				( objectStatus "@baseboard_fab2_lib.baseboard_fab2(sch_1):page108_i341:a" )
			)
			( pin "R7E22.2"
				( objectStatus "@baseboard_fab2_lib.baseboard_fab2(sch_1):page108_i341:b" )
			)
			( pin "R7E21.1"
				( objectStatus "@baseboard_fab2_lib.baseboard_fab2(sch_1):page108_i343:a" )
			)
			( pin "R7E21.2"
				( objectStatus "@baseboard_fab2_lib.baseboard_fab2(sch_1):page108_i343:b" )
			)
			( pin "R1L13.1"
				( objectStatus "@baseboard_fab2_lib.baseboard_fab2(sch_1):page111_i6:a" )
			)
			( pin "R1L13.2"
				( objectStatus "@baseboard_fab2_lib.baseboard_fab2(sch_1):page111_i6:b" )
			)
			( pin "C9A2.1"
				( objectStatus "@baseboard_fab2_lib.baseboard_fab2(sch_1):page111_i10:a" )
			)
			( pin "C9A2.2"
				( objectStatus "@baseboard_fab2_lib.baseboard_fab2(sch_1):page111_i10:b" )
			)
			( pin "R9A14.1"
				( objectStatus "@baseboard_fab2_lib.baseboard_fab2(sch_1):page111_i11:a" )
			)
			( pin "R9A14.2"
				( objectStatus "@baseboard_fab2_lib.baseboard_fab2(sch_1):page111_i11:b" )
			)
			( pin "C9A5.1"
				( objectStatus "@baseboard_fab2_lib.baseboard_fab2(sch_1):page111_i12:a" )
			)
			( pin "C9A5.2"
				( objectStatus "@baseboard_fab2_lib.baseboard_fab2(sch_1):page111_i12:b" )
			)
			( pin "R1L23.1"
				( objectStatus "@baseboard_fab2_lib.baseboard_fab2(sch_1):page111_i13:a" )
			)
			( pin "R1L23.2"
				( objectStatus "@baseboard_fab2_lib.baseboard_fab2(sch_1):page111_i13:b" )
			)
			( pin "C1L8.1"
				( objectStatus "@baseboard_fab2_lib.baseboard_fab2(sch_1):page111_i14:a" )
			)
			( pin "C1L8.2"
				( objectStatus "@baseboard_fab2_lib.baseboard_fab2(sch_1):page111_i14:b" )
			)
			( pin "C9A6.1"
				( objectStatus "@baseboard_fab2_lib.baseboard_fab2(sch_1):page111_i25:a" )
			)
			( pin "C9A6.2"
				( objectStatus "@baseboard_fab2_lib.baseboard_fab2(sch_1):page111_i25:b" )
			)
			( pin "J9A3.1"
				( objectStatus "@baseboard_fab2_lib.baseboard_fab2(sch_1):page111_i26:io1" )
			)
			( pin "J9A3.2"
				( objectStatus "@baseboard_fab2_lib.baseboard_fab2(sch_1):page111_i26:io2" )
			)
			( pin "J9A3.3"
				( objectStatus "@baseboard_fab2_lib.baseboard_fab2(sch_1):page111_i26:io3" )
			)
			( pin "J9A3.4"
				( objectStatus "@baseboard_fab2_lib.baseboard_fab2(sch_1):page111_i26:io4" )
			)
			( pin "J9A3.5"
				( objectStatus "@baseboard_fab2_lib.baseboard_fab2(sch_1):page111_i26:io5" )
			)
			( pin "J9A3.6"
				( objectStatus "@baseboard_fab2_lib.baseboard_fab2(sch_1):page111_i26:io6" )
			)
			( pin "J9A3.7"
				( objectStatus "@baseboard_fab2_lib.baseboard_fab2(sch_1):page111_i26:io7" )
			)
			( pin "J9A3.8"
				( objectStatus "@baseboard_fab2_lib.baseboard_fab2(sch_1):page111_i26:io8" )
			)
			( pin "J9A3.9"
				( objectStatus "@baseboard_fab2_lib.baseboard_fab2(sch_1):page111_i26:io9" )
			)
			( pin "J9A3.10"
				( objectStatus "@baseboard_fab2_lib.baseboard_fab2(sch_1):page111_i26:io10" )
			)
			( pin "J9A3.11"
				( objectStatus "@baseboard_fab2_lib.baseboard_fab2(sch_1):page111_i26:io11" )
			)
			( pin "J9A3.12"
				( objectStatus "@baseboard_fab2_lib.baseboard_fab2(sch_1):page111_i26:io12" )
			)
			( pin "J9A3.13"
				( objectStatus "@baseboard_fab2_lib.baseboard_fab2(sch_1):page111_i26:io13" )
			)
			( pin "J9A3.14"
				( objectStatus "@baseboard_fab2_lib.baseboard_fab2(sch_1):page111_i26:io14" )
			)
			( pin "J9A3.15"
				( objectStatus "@baseboard_fab2_lib.baseboard_fab2(sch_1):page111_i26:io15" )
			)
			( pin "J9A3.16"
				( objectStatus "@baseboard_fab2_lib.baseboard_fab2(sch_1):page111_i26:io16" )
			)
			( pin "J9A3.17"
				( objectStatus "@baseboard_fab2_lib.baseboard_fab2(sch_1):page111_i26:io17" )
			)
			( pin "J9A3.18"
				( objectStatus "@baseboard_fab2_lib.baseboard_fab2(sch_1):page111_i26:io18" )
			)
			( pin "J9A3.19"
				( objectStatus "@baseboard_fab2_lib.baseboard_fab2(sch_1):page111_i26:io19" )
			)
			( pin "J9A3.20"
				( objectStatus "@baseboard_fab2_lib.baseboard_fab2(sch_1):page111_i26:io20" )
			)
			( pin "J9A3.21"
				( objectStatus "@baseboard_fab2_lib.baseboard_fab2(sch_1):page111_i26:io21" )
			)
			( pin "J9A3.22"
				( objectStatus "@baseboard_fab2_lib.baseboard_fab2(sch_1):page111_i26:io22" )
			)
			( pin "J9A3.23"
				( objectStatus "@baseboard_fab2_lib.baseboard_fab2(sch_1):page111_i26:io23" )
			)
			( pin "J9A3.24"
				( objectStatus "@baseboard_fab2_lib.baseboard_fab2(sch_1):page111_i26:io24" )
			)
			( pin "J9A3.25"
				( objectStatus "@baseboard_fab2_lib.baseboard_fab2(sch_1):page111_i26:io25" )
			)
			( pin "J9A3.26"
				( objectStatus "@baseboard_fab2_lib.baseboard_fab2(sch_1):page111_i26:io26" )
			)
			( pin "J9A3.27"
				( objectStatus "@baseboard_fab2_lib.baseboard_fab2(sch_1):page111_i26:io27" )
			)
			( pin "J9A3.28"
				( objectStatus "@baseboard_fab2_lib.baseboard_fab2(sch_1):page111_i26:io28" )
			)
			( pin "J9A3.29"
				( objectStatus "@baseboard_fab2_lib.baseboard_fab2(sch_1):page111_i26:io29" )
			)
			( pin "J9A3.30"
				( objectStatus "@baseboard_fab2_lib.baseboard_fab2(sch_1):page111_i26:io30" )
			)
			( pin "J9A3.31"
				( objectStatus "@baseboard_fab2_lib.baseboard_fab2(sch_1):page111_i26:io31" )
			)
			( pin "J9A3.32"
				( objectStatus "@baseboard_fab2_lib.baseboard_fab2(sch_1):page111_i26:io32" )
			)
			( pin "J9A3.33"
				( objectStatus "@baseboard_fab2_lib.baseboard_fab2(sch_1):page111_i26:io33" )
			)
			( pin "J9A3.34"
				( objectStatus "@baseboard_fab2_lib.baseboard_fab2(sch_1):page111_i26:io34" )
			)
			( pin "J9A3.35"
				( objectStatus "@baseboard_fab2_lib.baseboard_fab2(sch_1):page111_i26:io35" )
			)
			( pin "J9A3.36"
				( objectStatus "@baseboard_fab2_lib.baseboard_fab2(sch_1):page111_i26:io36" )
			)
			( pin "J9A3.37"
				( objectStatus "@baseboard_fab2_lib.baseboard_fab2(sch_1):page111_i26:io37" )
			)
			( pin "J9A3.38"
				( objectStatus "@baseboard_fab2_lib.baseboard_fab2(sch_1):page111_i26:io38" )
			)
			( pin "J9A3.39"
				( objectStatus "@baseboard_fab2_lib.baseboard_fab2(sch_1):page111_i26:io39" )
			)
			( pin "J9A3.40"
				( objectStatus "@baseboard_fab2_lib.baseboard_fab2(sch_1):page111_i26:io40" )
			)
			( pin "J9A3.41"
				( objectStatus "@baseboard_fab2_lib.baseboard_fab2(sch_1):page111_i26:io41" )
			)
			( pin "J9A3.42"
				( objectStatus "@baseboard_fab2_lib.baseboard_fab2(sch_1):page111_i26:io42" )
			)
			( pin "J9A3.43"
				( objectStatus "@baseboard_fab2_lib.baseboard_fab2(sch_1):page111_i26:io43" )
			)
			( pin "J9A3.44"
				( objectStatus "@baseboard_fab2_lib.baseboard_fab2(sch_1):page111_i26:io44" )
			)
			( pin "J9A3.45"
				( objectStatus "@baseboard_fab2_lib.baseboard_fab2(sch_1):page111_i26:io45" )
			)
			( pin "J9A3.46"
				( objectStatus "@baseboard_fab2_lib.baseboard_fab2(sch_1):page111_i26:io46" )
			)
			( pin "J9A3.47"
				( objectStatus "@baseboard_fab2_lib.baseboard_fab2(sch_1):page111_i26:io47" )
			)
			( pin "J9A3.48"
				( objectStatus "@baseboard_fab2_lib.baseboard_fab2(sch_1):page111_i26:io48" )
			)
			( pin "J9A3.49"
				( objectStatus "@baseboard_fab2_lib.baseboard_fab2(sch_1):page111_i26:io49" )
			)
			( pin "J9A3.50"
				( objectStatus "@baseboard_fab2_lib.baseboard_fab2(sch_1):page111_i26:io50" )
			)
			( pin "J9A3.51"
				( objectStatus "@baseboard_fab2_lib.baseboard_fab2(sch_1):page111_i26:io51" )
			)
			( pin "J9A3.52"
				( objectStatus "@baseboard_fab2_lib.baseboard_fab2(sch_1):page111_i26:io52" )
			)
			( pin "J9A3.53"
				( objectStatus "@baseboard_fab2_lib.baseboard_fab2(sch_1):page111_i26:io53" )
			)
			( pin "J9A3.54"
				( objectStatus "@baseboard_fab2_lib.baseboard_fab2(sch_1):page111_i26:io54" )
			)
			( pin "J9A3.55"
				( objectStatus "@baseboard_fab2_lib.baseboard_fab2(sch_1):page111_i26:io55" )
			)
			( pin "J9A3.56"
				( objectStatus "@baseboard_fab2_lib.baseboard_fab2(sch_1):page111_i26:io56" )
			)
			( pin "J9A3.57"
				( objectStatus "@baseboard_fab2_lib.baseboard_fab2(sch_1):page111_i26:io57" )
			)
			( pin "J9A3.58"
				( objectStatus "@baseboard_fab2_lib.baseboard_fab2(sch_1):page111_i26:io58" )
			)
			( pin "J9A3.59"
				( objectStatus "@baseboard_fab2_lib.baseboard_fab2(sch_1):page111_i26:io59" )
			)
			( pin "J9A3.60"
				( objectStatus "@baseboard_fab2_lib.baseboard_fab2(sch_1):page111_i26:io60" )
			)
			( pin "C1L5.1"
				( objectStatus "@baseboard_fab2_lib.baseboard_fab2(sch_1):page111_i30:a" )
			)
			( pin "C1L5.2"
				( objectStatus "@baseboard_fab2_lib.baseboard_fab2(sch_1):page111_i30:b" )
			)
			( pin "R2P2.1"
				( objectStatus "@baseboard_fab2_lib.baseboard_fab2(sch_1):page111_i37:a" )
			)
			( pin "R2P2.2"
				( objectStatus "@baseboard_fab2_lib.baseboard_fab2(sch_1):page111_i37:b" )
			)
			( pin "R9A4.1"
				( objectStatus "@baseboard_fab2_lib.baseboard_fab2(sch_1):page111_i55:a" )
			)
			( pin "R9A4.2"
				( objectStatus "@baseboard_fab2_lib.baseboard_fab2(sch_1):page111_i55:b" )
			)
			( pin "R1L17.1"
				( objectStatus "@baseboard_fab2_lib.baseboard_fab2(sch_1):page111_i56:a" )
			)
			( pin "R1L17.2"
				( objectStatus "@baseboard_fab2_lib.baseboard_fab2(sch_1):page111_i56:b" )
			)
			( pin "R9A17.1"
				( objectStatus "@baseboard_fab2_lib.baseboard_fab2(sch_1):page111_i57:a" )
			)
			( pin "R9A17.2"
				( objectStatus "@baseboard_fab2_lib.baseboard_fab2(sch_1):page111_i57:b" )
			)
			( pin "C9A4.1"
				( objectStatus "@baseboard_fab2_lib.baseboard_fab2(sch_1):page111_i59:a" )
			)
			( pin "C9A4.2"
				( objectStatus "@baseboard_fab2_lib.baseboard_fab2(sch_1):page111_i59:b" )
			)
			( pin "R9A15.1"
				( objectStatus "@baseboard_fab2_lib.baseboard_fab2(sch_1):page111_i60:a" )
			)
			( pin "R9A15.2"
				( objectStatus "@baseboard_fab2_lib.baseboard_fab2(sch_1):page111_i60:b" )
			)
			( pin "R1L29.1"
				( objectStatus "@baseboard_fab2_lib.baseboard_fab2(sch_1):page111_i68:a" )
			)
			( pin "R1L29.2"
				( objectStatus "@baseboard_fab2_lib.baseboard_fab2(sch_1):page111_i68:b" )
			)
			( pin "R9A3.1"
				( objectStatus "@baseboard_fab2_lib.baseboard_fab2(sch_1):page111_i74:a" )
			)
			( pin "R9A3.2"
				( objectStatus "@baseboard_fab2_lib.baseboard_fab2(sch_1):page111_i74:b" )
			)
			( pin "R9A2.1"
				( objectStatus "@baseboard_fab2_lib.baseboard_fab2(sch_1):page111_i83:a" )
			)
			( pin "R9A2.2"
				( objectStatus "@baseboard_fab2_lib.baseboard_fab2(sch_1):page111_i83:b" )
			)
			( pin "U1L4.2"
				( objectStatus "@baseboard_fab2_lib.baseboard_fab2(sch_1):page111_i85:a" )
			)
			( pin "U1L4.4"
				( objectStatus "@baseboard_fab2_lib.baseboard_fab2(sch_1):page111_i85:y" )
			)
			( pin "C1L11.1"
				( objectStatus "@baseboard_fab2_lib.baseboard_fab2(sch_1):page111_i87:a" )
			)
			( pin "C1L11.2"
				( objectStatus "@baseboard_fab2_lib.baseboard_fab2(sch_1):page111_i87:b" )
			)
			( pin "R8E2.1"
				( objectStatus "@baseboard_fab2_lib.baseboard_fab2(sch_1):page111_i89:a" )
			)
			( pin "R8E2.2"
				( objectStatus "@baseboard_fab2_lib.baseboard_fab2(sch_1):page111_i89:b" )
			)
			( pin "Q9A1.2"
				( objectStatus "@baseboard_fab2_lib.baseboard_fab2(sch_1):page111_i93:b(0)" )
			)
			( pin "Q9A1.6"
				( objectStatus "@baseboard_fab2_lib.baseboard_fab2(sch_1):page111_i93:c(0)" )
			)
			( pin "Q9A1.1"
				( objectStatus "@baseboard_fab2_lib.baseboard_fab2(sch_1):page111_i93:e(0)" )
			)
			( pin "Q9A1.5"
				( objectStatus "@baseboard_fab2_lib.baseboard_fab2(sch_1):page111_i94:b(0)" )
			)
			( pin "Q9A1.3"
				( objectStatus "@baseboard_fab2_lib.baseboard_fab2(sch_1):page111_i94:c(0)" )
			)
			( pin "Q9A1.4"
				( objectStatus "@baseboard_fab2_lib.baseboard_fab2(sch_1):page111_i94:e(0)" )
			)
			( pin "R9A1.1"
				( objectStatus "@baseboard_fab2_lib.baseboard_fab2(sch_1):page111_i95:a" )
			)
			( pin "R9A1.2"
				( objectStatus "@baseboard_fab2_lib.baseboard_fab2(sch_1):page111_i95:b" )
			)
			( pin "U1M7.4"
				( objectStatus "@baseboard_fab2_lib.baseboard_fab2(sch_1):page112_i40:a" )
			)
			( pin "U1M7.3"
				( objectStatus "@baseboard_fab2_lib.baseboard_fab2(sch_1):page112_i40:b0" )
			)
			( pin "U1M7.1"
				( objectStatus "@baseboard_fab2_lib.baseboard_fab2(sch_1):page112_i40:b1" )
			)
			( pin "U1M7.2"
				( objectStatus "@baseboard_fab2_lib.baseboard_fab2(sch_1):page112_i40:gnd" )
			)
			( pin "U1M7.6"
				( objectStatus "@baseboard_fab2_lib.baseboard_fab2(sch_1):page112_i40:s" )
			)
			( pin "U1M7.5"
				( objectStatus "@baseboard_fab2_lib.baseboard_fab2(sch_1):page112_i40:vcc" )
			)
			( pin "C1M36.1"
				( objectStatus "@baseboard_fab2_lib.baseboard_fab2(sch_1):page112_i42:a" )
			)
			( pin "C1M36.2"
				( objectStatus "@baseboard_fab2_lib.baseboard_fab2(sch_1):page112_i42:b" )
			)
			( pin "C1M37.1"
				( objectStatus "@baseboard_fab2_lib.baseboard_fab2(sch_1):page112_i47:a" )
			)
			( pin "C1M37.2"
				( objectStatus "@baseboard_fab2_lib.baseboard_fab2(sch_1):page112_i47:b" )
			)
			( pin "R6P46.1"
				( objectStatus "@baseboard_fab2_lib.baseboard_fab2(sch_1):page112_i49:a" )
			)
			( pin "R6P46.2"
				( objectStatus "@baseboard_fab2_lib.baseboard_fab2(sch_1):page112_i49:b" )
			)
			( pin "R7P30.1"
				( objectStatus "@baseboard_fab2_lib.baseboard_fab2(sch_1):page112_i50:a" )
			)
			( pin "R7P30.2"
				( objectStatus "@baseboard_fab2_lib.baseboard_fab2(sch_1):page112_i50:b" )
			)
			( pin "R1M3.1"
				( objectStatus "@baseboard_fab2_lib.baseboard_fab2(sch_1):page112_i51:a" )
			)
			( pin "R1M3.2"
				( objectStatus "@baseboard_fab2_lib.baseboard_fab2(sch_1):page112_i51:b" )
			)
			( pin "R4P15.1"
				( objectStatus "@baseboard_fab2_lib.baseboard_fab2(sch_1):page112_i53:a" )
			)
			( pin "R4P15.2"
				( objectStatus "@baseboard_fab2_lib.baseboard_fab2(sch_1):page112_i53:b" )
			)
			( pin "R1M4.1"
				( objectStatus "@baseboard_fab2_lib.baseboard_fab2(sch_1):page112_i54:a" )
			)
			( pin "R1M4.2"
				( objectStatus "@baseboard_fab2_lib.baseboard_fab2(sch_1):page112_i54:b" )
			)
			( pin "R6T7.1"
				( objectStatus "@baseboard_fab2_lib.baseboard_fab2(sch_1):page112_i55:a" )
			)
			( pin "R6T7.2"
				( objectStatus "@baseboard_fab2_lib.baseboard_fab2(sch_1):page112_i55:b" )
			)
			( pin "R6T6.1"
				( objectStatus "@baseboard_fab2_lib.baseboard_fab2(sch_1):page112_i56:a" )
			)
			( pin "R6T6.2"
				( objectStatus "@baseboard_fab2_lib.baseboard_fab2(sch_1):page112_i56:b" )
			)
			( pin "R4P12.1"
				( objectStatus "@baseboard_fab2_lib.baseboard_fab2(sch_1):page112_i57:a" )
			)
			( pin "R4P12.2"
				( objectStatus "@baseboard_fab2_lib.baseboard_fab2(sch_1):page112_i57:b" )
			)
			( pin "R4P23.1"
				( objectStatus "@baseboard_fab2_lib.baseboard_fab2(sch_1):page112_i58:a" )
			)
			( pin "R4P23.2"
				( objectStatus "@baseboard_fab2_lib.baseboard_fab2(sch_1):page112_i58:b" )
			)
			( pin "R4P24.1"
				( objectStatus "@baseboard_fab2_lib.baseboard_fab2(sch_1):page112_i59:a" )
			)
			( pin "R4P24.2"
				( objectStatus "@baseboard_fab2_lib.baseboard_fab2(sch_1):page112_i59:b" )
			)
			( pin "R1L15.1"
				( objectStatus "@baseboard_fab2_lib.baseboard_fab2(sch_1):page112_i60:a" )
			)
			( pin "R1L15.2"
				( objectStatus "@baseboard_fab2_lib.baseboard_fab2(sch_1):page112_i60:b" )
			)
			( pin "R7P29.1"
				( objectStatus "@baseboard_fab2_lib.baseboard_fab2(sch_1):page112_i61:a" )
			)
			( pin "R7P29.2"
				( objectStatus "@baseboard_fab2_lib.baseboard_fab2(sch_1):page112_i61:b" )
			)
			( pin "R6T5.1"
				( objectStatus "@baseboard_fab2_lib.baseboard_fab2(sch_1):page112_i62:a" )
			)
			( pin "R6T5.2"
				( objectStatus "@baseboard_fab2_lib.baseboard_fab2(sch_1):page112_i62:b" )
			)
			( pin "R1L39.1"
				( objectStatus "@baseboard_fab2_lib.baseboard_fab2(sch_1):page112_i76:a" )
			)
			( pin "R1L39.2"
				( objectStatus "@baseboard_fab2_lib.baseboard_fab2(sch_1):page112_i76:b" )
			)
			( pin "R1L41.1"
				( objectStatus "@baseboard_fab2_lib.baseboard_fab2(sch_1):page112_i77:a" )
			)
			( pin "R1L41.2"
				( objectStatus "@baseboard_fab2_lib.baseboard_fab2(sch_1):page112_i77:b" )
			)
			( pin "R9A11.1"
				( objectStatus "@baseboard_fab2_lib.baseboard_fab2(sch_1):page112_i78:a" )
			)
			( pin "R9A11.2"
				( objectStatus "@baseboard_fab2_lib.baseboard_fab2(sch_1):page112_i78:b" )
			)
			( pin "R8A13.1"
				( objectStatus "@baseboard_fab2_lib.baseboard_fab2(sch_1):page112_i79:a" )
			)
			( pin "R8A13.2"
				( objectStatus "@baseboard_fab2_lib.baseboard_fab2(sch_1):page112_i79:b" )
			)
			( pin "R8A14.1"
				( objectStatus "@baseboard_fab2_lib.baseboard_fab2(sch_1):page112_i80:a" )
			)
			( pin "R8A14.2"
				( objectStatus "@baseboard_fab2_lib.baseboard_fab2(sch_1):page112_i80:b" )
			)
			( pin "R3M10.1"
				( objectStatus "@baseboard_fab2_lib.baseboard_fab2(sch_1):page112_i85:a" )
			)
			( pin "R3M10.2"
				( objectStatus "@baseboard_fab2_lib.baseboard_fab2(sch_1):page112_i85:b" )
			)
			( pin "R8B2.1"
				( objectStatus "@baseboard_fab2_lib.baseboard_fab2(sch_1):page112_i94:a" )
			)
			( pin "R8B2.2"
				( objectStatus "@baseboard_fab2_lib.baseboard_fab2(sch_1):page112_i94:b" )
			)
			( pin "R8B1.1"
				( objectStatus "@baseboard_fab2_lib.baseboard_fab2(sch_1):page112_i95:a" )
			)
			( pin "R8B1.2"
				( objectStatus "@baseboard_fab2_lib.baseboard_fab2(sch_1):page112_i95:b" )
			)
			( pin "U1L1.12"
				( objectStatus "@baseboard_fab2_lib.baseboard_fab2(sch_1):page112_i108:a(0)" )
			)
			( pin "U1L1.9"
				( objectStatus "@baseboard_fab2_lib.baseboard_fab2(sch_1):page112_i108:a(1)" )
			)
			( pin "U1L1.5"
				( objectStatus "@baseboard_fab2_lib.baseboard_fab2(sch_1):page112_i108:a(2)" )
			)
			( pin "U1L1.2"
				( objectStatus "@baseboard_fab2_lib.baseboard_fab2(sch_1):page112_i108:a(3)" )
			)
			( pin "U1L1.11"
				( objectStatus "@baseboard_fab2_lib.baseboard_fab2(sch_1):page112_i108:b(0)" )
			)
			( pin "U1L1.8"
				( objectStatus "@baseboard_fab2_lib.baseboard_fab2(sch_1):page112_i108:b(1)" )
			)
			( pin "U1L1.6"
				( objectStatus "@baseboard_fab2_lib.baseboard_fab2(sch_1):page112_i108:b(2)" )
			)
			( pin "U1L1.3"
				( objectStatus "@baseboard_fab2_lib.baseboard_fab2(sch_1):page112_i108:b(3)" )
			)
			( pin "U1L1.13"
				( objectStatus "@baseboard_fab2_lib.baseboard_fab2(sch_1):page112_i108:oe(0)" )
			)
			( pin "U1L1.10"
				( objectStatus "@baseboard_fab2_lib.baseboard_fab2(sch_1):page112_i108:oe(1)" )
			)
			( pin "U1L1.4"
				( objectStatus "@baseboard_fab2_lib.baseboard_fab2(sch_1):page112_i108:oe(2)" )
			)
			( pin "U1L1.1"
				( objectStatus "@baseboard_fab2_lib.baseboard_fab2(sch_1):page112_i108:oe(3)" )
			)
			( pin "U1L5.12"
				( objectStatus "@baseboard_fab2_lib.baseboard_fab2(sch_1):page112_i109:a(0)" )
			)
			( pin "U1L5.9"
				( objectStatus "@baseboard_fab2_lib.baseboard_fab2(sch_1):page112_i109:a(1)" )
			)
			( pin "U1L5.5"
				( objectStatus "@baseboard_fab2_lib.baseboard_fab2(sch_1):page112_i109:a(2)" )
			)
			( pin "U1L5.2"
				( objectStatus "@baseboard_fab2_lib.baseboard_fab2(sch_1):page112_i109:a(3)" )
			)
			( pin "U1L5.11"
				( objectStatus "@baseboard_fab2_lib.baseboard_fab2(sch_1):page112_i109:b(0)" )
			)
			( pin "U1L5.8"
				( objectStatus "@baseboard_fab2_lib.baseboard_fab2(sch_1):page112_i109:b(1)" )
			)
			( pin "U1L5.6"
				( objectStatus "@baseboard_fab2_lib.baseboard_fab2(sch_1):page112_i109:b(2)" )
			)
			( pin "U1L5.3"
				( objectStatus "@baseboard_fab2_lib.baseboard_fab2(sch_1):page112_i109:b(3)" )
			)
			( pin "U1L5.13"
				( objectStatus "@baseboard_fab2_lib.baseboard_fab2(sch_1):page112_i109:oe(0)" )
			)
			( pin "U1L5.10"
				( objectStatus "@baseboard_fab2_lib.baseboard_fab2(sch_1):page112_i109:oe(1)" )
			)
			( pin "U1L5.4"
				( objectStatus "@baseboard_fab2_lib.baseboard_fab2(sch_1):page112_i109:oe(2)" )
			)
			( pin "U1L5.1"
				( objectStatus "@baseboard_fab2_lib.baseboard_fab2(sch_1):page112_i109:oe(3)" )
			)
			( pin "R6T9.1"
				( objectStatus "@baseboard_fab2_lib.baseboard_fab2(sch_1):page112_i120:a" )
			)
			( pin "R6T9.2"
				( objectStatus "@baseboard_fab2_lib.baseboard_fab2(sch_1):page112_i120:b" )
			)
			( pin "R6T8.1"
				( objectStatus "@baseboard_fab2_lib.baseboard_fab2(sch_1):page112_i121:a" )
			)
			( pin "R6T8.2"
				( objectStatus "@baseboard_fab2_lib.baseboard_fab2(sch_1):page112_i121:b" )
			)
			( pin "U1M4.2"
				( objectStatus "@baseboard_fab2_lib.baseboard_fab2(sch_1):page112_i127:a" )
			)
			( pin "U1M4.4"
				( objectStatus "@baseboard_fab2_lib.baseboard_fab2(sch_1):page112_i127:b" )
			)
			( pin "U1M4.1"
				( objectStatus "@baseboard_fab2_lib.baseboard_fab2(sch_1):page112_i127:oe_n" )
			)
			( pin "C1M30.1"
				( objectStatus "@baseboard_fab2_lib.baseboard_fab2(sch_1):page112_i131:a" )
			)
			( pin "C1M30.2"
				( objectStatus "@baseboard_fab2_lib.baseboard_fab2(sch_1):page112_i131:b" )
			)
			( pin "C1L1.1"
				( objectStatus "@baseboard_fab2_lib.baseboard_fab2(sch_1):page112_i136:a" )
			)
			( pin "C1L1.2"
				( objectStatus "@baseboard_fab2_lib.baseboard_fab2(sch_1):page112_i136:b" )
			)
			( pin "C1L19.1"
				( objectStatus "@baseboard_fab2_lib.baseboard_fab2(sch_1):page112_i140:a" )
			)
			( pin "C1L19.2"
				( objectStatus "@baseboard_fab2_lib.baseboard_fab2(sch_1):page112_i140:b" )
			)
			( pin "U1M2.4"
				( objectStatus "@baseboard_fab2_lib.baseboard_fab2(sch_1):page113_i107:a" )
			)
			( pin "U1M2.3"
				( objectStatus "@baseboard_fab2_lib.baseboard_fab2(sch_1):page113_i107:b0" )
			)
			( pin "U1M2.1"
				( objectStatus "@baseboard_fab2_lib.baseboard_fab2(sch_1):page113_i107:b1" )
			)
			( pin "U1M2.2"
				( objectStatus "@baseboard_fab2_lib.baseboard_fab2(sch_1):page113_i107:gnd" )
			)
			( pin "U1M2.6"
				( objectStatus "@baseboard_fab2_lib.baseboard_fab2(sch_1):page113_i107:s" )
			)
			( pin "U1M2.5"
				( objectStatus "@baseboard_fab2_lib.baseboard_fab2(sch_1):page113_i107:vcc" )
			)
			( pin "C1M31.1"
				( objectStatus "@baseboard_fab2_lib.baseboard_fab2(sch_1):page113_i116:a" )
			)
			( pin "C1M31.2"
				( objectStatus "@baseboard_fab2_lib.baseboard_fab2(sch_1):page113_i116:b" )
			)
			( pin "C1M32.1"
				( objectStatus "@baseboard_fab2_lib.baseboard_fab2(sch_1):page113_i117:a" )
			)
			( pin "C1M32.2"
				( objectStatus "@baseboard_fab2_lib.baseboard_fab2(sch_1):page113_i117:b" )
			)
			( pin "C1M28.1"
				( objectStatus "@baseboard_fab2_lib.baseboard_fab2(sch_1):page113_i119:a" )
			)
			( pin "C1M28.2"
				( objectStatus "@baseboard_fab2_lib.baseboard_fab2(sch_1):page113_i119:b" )
			)
			( pin "U1M6.2"
				( objectStatus "@baseboard_fab2_lib.baseboard_fab2(sch_1):page113_i127:a" )
			)
			( pin "U1M6.4"
				( objectStatus "@baseboard_fab2_lib.baseboard_fab2(sch_1):page113_i127:b" )
			)
			( pin "U1M6.1"
				( objectStatus "@baseboard_fab2_lib.baseboard_fab2(sch_1):page113_i127:oe_n" )
			)
			( pin "C1M29.1"
				( objectStatus "@baseboard_fab2_lib.baseboard_fab2(sch_1):page113_i147:a" )
			)
			( pin "C1M29.2"
				( objectStatus "@baseboard_fab2_lib.baseboard_fab2(sch_1):page113_i147:b" )
			)
			( pin "R9B14.1"
				( objectStatus "@baseboard_fab2_lib.baseboard_fab2(sch_1):page113_i168:a" )
			)
			( pin "R9B14.2"
				( objectStatus "@baseboard_fab2_lib.baseboard_fab2(sch_1):page113_i168:b" )
			)
			( pin "J9B4.1"
				( objectStatus "@baseboard_fab2_lib.baseboard_fab2(sch_1):page113_i175:io1" )
			)
			( pin "J9B4.2"
				( objectStatus "@baseboard_fab2_lib.baseboard_fab2(sch_1):page113_i175:io2" )
			)
			( pin "J9B4.3"
				( objectStatus "@baseboard_fab2_lib.baseboard_fab2(sch_1):page113_i175:io3" )
			)
			( pin "J9B4.4"
				( objectStatus "@baseboard_fab2_lib.baseboard_fab2(sch_1):page113_i175:io4" )
			)
			( pin "J9B4.5"
				( objectStatus "@baseboard_fab2_lib.baseboard_fab2(sch_1):page113_i175:io5" )
			)
			( pin "J9B4.6"
				( objectStatus "@baseboard_fab2_lib.baseboard_fab2(sch_1):page113_i175:io6" )
			)
			( pin "J9B4.7"
				( objectStatus "@baseboard_fab2_lib.baseboard_fab2(sch_1):page113_i175:io7" )
			)
			( pin "J9B4.8"
				( objectStatus "@baseboard_fab2_lib.baseboard_fab2(sch_1):page113_i175:io8" )
			)
			( pin "J9B4.9"
				( objectStatus "@baseboard_fab2_lib.baseboard_fab2(sch_1):page113_i175:io9" )
			)
			( pin "J9B4.10"
				( objectStatus "@baseboard_fab2_lib.baseboard_fab2(sch_1):page113_i175:io10" )
			)
			( pin "R9B9.1"
				( objectStatus "@baseboard_fab2_lib.baseboard_fab2(sch_1):page113_i179:a" )
			)
			( pin "R9B9.2"
				( objectStatus "@baseboard_fab2_lib.baseboard_fab2(sch_1):page113_i179:b" )
			)
			( pin "R9B10.1"
				( objectStatus "@baseboard_fab2_lib.baseboard_fab2(sch_1):page113_i180:a" )
			)
			( pin "R9B10.2"
				( objectStatus "@baseboard_fab2_lib.baseboard_fab2(sch_1):page113_i180:b" )
			)
			( pin "U9A5.2"
				( objectStatus "@baseboard_fab2_lib.baseboard_fab2(sch_1):page113_i185:a" )
			)
			( pin "U9A5.4"
				( objectStatus "@baseboard_fab2_lib.baseboard_fab2(sch_1):page113_i185:b" )
			)
			( pin "U9A5.1"
				( objectStatus "@baseboard_fab2_lib.baseboard_fab2(sch_1):page113_i185:oe_n" )
			)
			( pin "U6M1.2"
				( objectStatus "@baseboard_fab2_lib.baseboard_fab2(sch_1):page113_i190:a" )
			)
			( pin "U6M1.4"
				( objectStatus "@baseboard_fab2_lib.baseboard_fab2(sch_1):page113_i190:b" )
			)
			( pin "U6M1.1"
				( objectStatus "@baseboard_fab2_lib.baseboard_fab2(sch_1):page113_i190:oe_n" )
			)
			( pin "R1M22.1"
				( objectStatus "@baseboard_fab2_lib.baseboard_fab2(sch_1):page113_i195:a" )
			)
			( pin "R1M22.2"
				( objectStatus "@baseboard_fab2_lib.baseboard_fab2(sch_1):page113_i195:b" )
			)
			( pin "U1M5.2"
				( objectStatus "@baseboard_fab2_lib.baseboard_fab2(sch_1):page113_i196:a" )
			)
			( pin "U1M5.4"
				( objectStatus "@baseboard_fab2_lib.baseboard_fab2(sch_1):page113_i196:b" )
			)
			( pin "U1M5.1"
				( objectStatus "@baseboard_fab2_lib.baseboard_fab2(sch_1):page113_i196:oe_n" )
			)
			( pin "R1M23.1"
				( objectStatus "@baseboard_fab2_lib.baseboard_fab2(sch_1):page113_i199:a" )
			)
			( pin "R1M23.2"
				( objectStatus "@baseboard_fab2_lib.baseboard_fab2(sch_1):page113_i199:b" )
			)
			( pin "R1M19.1"
				( objectStatus "@baseboard_fab2_lib.baseboard_fab2(sch_1):page113_i202:a" )
			)
			( pin "R1M19.2"
				( objectStatus "@baseboard_fab2_lib.baseboard_fab2(sch_1):page113_i202:b" )
			)
			( pin "R9B12.1"
				( objectStatus "@baseboard_fab2_lib.baseboard_fab2(sch_1):page113_i203:a" )
			)
			( pin "R9B12.2"
				( objectStatus "@baseboard_fab2_lib.baseboard_fab2(sch_1):page113_i203:b" )
			)
			( pin "R1M20.1"
				( objectStatus "@baseboard_fab2_lib.baseboard_fab2(sch_1):page113_i204:a" )
			)
			( pin "R1M20.2"
				( objectStatus "@baseboard_fab2_lib.baseboard_fab2(sch_1):page113_i204:b" )
			)
			( pin "R1M21.1"
				( objectStatus "@baseboard_fab2_lib.baseboard_fab2(sch_1):page113_i205:a" )
			)
			( pin "R1M21.2"
				( objectStatus "@baseboard_fab2_lib.baseboard_fab2(sch_1):page113_i205:b" )
			)
			( pin "U4R1.2"
				( objectStatus "@baseboard_fab2_lib.baseboard_fab2(sch_1):page113_i206:a" )
			)
			( pin "U4R1.4"
				( objectStatus "@baseboard_fab2_lib.baseboard_fab2(sch_1):page113_i206:b" )
			)
			( pin "U4R1.1"
				( objectStatus "@baseboard_fab2_lib.baseboard_fab2(sch_1):page113_i206:oe_n" )
			)
			( pin "R9B11.1"
				( objectStatus "@baseboard_fab2_lib.baseboard_fab2(sch_1):page113_i239:a" )
			)
			( pin "R9B11.2"
				( objectStatus "@baseboard_fab2_lib.baseboard_fab2(sch_1):page113_i239:b" )
			)
			( pin "R9B13.1"
				( objectStatus "@baseboard_fab2_lib.baseboard_fab2(sch_1):page113_i240:a" )
			)
			( pin "R9B13.2"
				( objectStatus "@baseboard_fab2_lib.baseboard_fab2(sch_1):page113_i240:b" )
			)
			( pin "C4R2.1"
				( objectStatus "@baseboard_fab2_lib.baseboard_fab2(sch_1):page113_i246:a" )
			)
			( pin "C4R2.2"
				( objectStatus "@baseboard_fab2_lib.baseboard_fab2(sch_1):page113_i246:b" )
			)
			( pin "C1M33.1"
				( objectStatus "@baseboard_fab2_lib.baseboard_fab2(sch_1):page113_i248:a" )
			)
			( pin "C1M33.2"
				( objectStatus "@baseboard_fab2_lib.baseboard_fab2(sch_1):page113_i248:b" )
			)
			( pin "C6M6.1"
				( objectStatus "@baseboard_fab2_lib.baseboard_fab2(sch_1):page113_i250:a" )
			)
			( pin "C6M6.2"
				( objectStatus "@baseboard_fab2_lib.baseboard_fab2(sch_1):page113_i250:b" )
			)
			( pin "U2M1.4"
				( objectStatus "@baseboard_fab2_lib.baseboard_fab2(sch_1):page113_i255:a" )
			)
			( pin "U2M1.3"
				( objectStatus "@baseboard_fab2_lib.baseboard_fab2(sch_1):page113_i255:b0" )
			)
			( pin "U2M1.1"
				( objectStatus "@baseboard_fab2_lib.baseboard_fab2(sch_1):page113_i255:b1" )
			)
			( pin "U2M1.2"
				( objectStatus "@baseboard_fab2_lib.baseboard_fab2(sch_1):page113_i255:gnd" )
			)
			( pin "U2M1.6"
				( objectStatus "@baseboard_fab2_lib.baseboard_fab2(sch_1):page113_i255:s" )
			)
			( pin "U2M1.5"
				( objectStatus "@baseboard_fab2_lib.baseboard_fab2(sch_1):page113_i255:vcc" )
			)
			( pin "C1M34.1"
				( objectStatus "@baseboard_fab2_lib.baseboard_fab2(sch_1):page113_i265:a" )
			)
			( pin "C1M34.2"
				( objectStatus "@baseboard_fab2_lib.baseboard_fab2(sch_1):page113_i265:b" )
			)
			( pin "C1M35.1"
				( objectStatus "@baseboard_fab2_lib.baseboard_fab2(sch_1):page113_i266:a" )
			)
			( pin "C1M35.2"
				( objectStatus "@baseboard_fab2_lib.baseboard_fab2(sch_1):page113_i266:b" )
			)
			( pin "C1L20.1"
				( objectStatus "@baseboard_fab2_lib.baseboard_fab2(sch_1):page113_i267:a" )
			)
			( pin "C1L20.2"
				( objectStatus "@baseboard_fab2_lib.baseboard_fab2(sch_1):page113_i267:b" )
			)
			( pin "U7C1.A39"
				( objectStatus "@baseboard_fab2_lib.baseboard_fab2(sch_1):page114_i40:clkout_itpxdpn" )
			)
			( pin "U7C1.C39"
				( objectStatus "@baseboard_fab2_lib.baseboard_fab2(sch_1):page114_i40:clkout_itpxdpp" )
			)
			( pin "U7C1.A32"
				( objectStatus "@baseboard_fab2_lib.baseboard_fab2(sch_1):page114_i40:clkout_nssccap0n" )
			)
			( pin "U7C1.C32"
				( objectStatus "@baseboard_fab2_lib.baseboard_fab2(sch_1):page114_i40:clkout_nssccap0p" )
			)
			( pin "U7C1.B38"
				( objectStatus "@baseboard_fab2_lib.baseboard_fab2(sch_1):page114_i40:clkout_nssccap1n" )
			)
			( pin "U7C1.D38"
				( objectStatus "@baseboard_fab2_lib.baseboard_fab2(sch_1):page114_i40:clkout_nssccap1p" )
			)
			( pin "U7C1.B29"
				( objectStatus "@baseboard_fab2_lib.baseboard_fab2(sch_1):page114_i40:clkout_plat0n" )
			)
			( pin "U7C1.D29"
				( objectStatus "@baseboard_fab2_lib.baseboard_fab2(sch_1):page114_i40:clkout_plat0p" )
			)
			( pin "U7C1.B40"
				( objectStatus "@baseboard_fab2_lib.baseboard_fab2(sch_1):page114_i40:clkout_plat1n" )
			)
			( pin "U7C1.D40"
				( objectStatus "@baseboard_fab2_lib.baseboard_fab2(sch_1):page114_i40:clkout_plat1p" )
			)
			( pin "U7C1.K38"
				( objectStatus "@baseboard_fab2_lib.baseboard_fab2(sch_1):page114_i40:clkout_srcn(0)" )
			)
			( pin "U7C1.K35"
				( objectStatus "@baseboard_fab2_lib.baseboard_fab2(sch_1):page114_i40:clkout_srcn(1)" )
			)
			( pin "U7C1.J33"
				( objectStatus "@baseboard_fab2_lib.baseboard_fab2(sch_1):page114_i40:clkout_srcn(2)" )
			)
			( pin "U7C1.K42"
				( objectStatus "@baseboard_fab2_lib.baseboard_fab2(sch_1):page114_i40:clkout_srcn(3)" )
			)
			( pin "U7C1.A28"
				( objectStatus "@baseboard_fab2_lib.baseboard_fab2(sch_1):page114_i40:clkout_srcn(4)" )
			)
			( pin "U7C1.J40"
				( objectStatus "@baseboard_fab2_lib.baseboard_fab2(sch_1):page114_i40:clkout_srcn(5)" )
			)
			( pin "U7C1.D33"
				( objectStatus "@baseboard_fab2_lib.baseboard_fab2(sch_1):page114_i40:clkout_srcn(6)" )
			)
			( pin "U7C1.H31"
				( objectStatus "@baseboard_fab2_lib.baseboard_fab2(sch_1):page114_i40:clkout_srcn(7)" )
			)
			( pin "U7C1.D31"
				( objectStatus "@baseboard_fab2_lib.baseboard_fab2(sch_1):page114_i40:clkout_srcn(8)" )
			)
			( pin "U7C1.J26"
				( objectStatus "@baseboard_fab2_lib.baseboard_fab2(sch_1):page114_i40:clkout_srcn(9)" )
			)
			( pin "U7C1.B23"
				( objectStatus "@baseboard_fab2_lib.baseboard_fab2(sch_1):page114_i40:clkout_srcn(10)" )
			)
			( pin "U7C1.B21"
				( objectStatus "@baseboard_fab2_lib.baseboard_fab2(sch_1):page114_i40:clkout_srcn(11)" )
			)
			( pin "U7C1.K24"
				( objectStatus "@baseboard_fab2_lib.baseboard_fab2(sch_1):page114_i40:clkout_srcn(12)" )
			)
			( pin "U7C1.C24"
				( objectStatus "@baseboard_fab2_lib.baseboard_fab2(sch_1):page114_i40:clkout_srcn(13)" )
			)
			( pin "U7C1.C20"
				( objectStatus "@baseboard_fab2_lib.baseboard_fab2(sch_1):page114_i40:clkout_srcn(14)" )
			)
			( pin "U7C1.K27"
				( objectStatus "@baseboard_fab2_lib.baseboard_fab2(sch_1):page114_i40:clkout_srcn(15)" )
			)
			( pin "U7C1.H38"
				( objectStatus "@baseboard_fab2_lib.baseboard_fab2(sch_1):page114_i40:clkout_srcp(0)" )
			)
			( pin "U7C1.H35"
				( objectStatus "@baseboard_fab2_lib.baseboard_fab2(sch_1):page114_i40:clkout_srcp(1)" )
			)
			( pin "U7C1.G33"
				( objectStatus "@baseboard_fab2_lib.baseboard_fab2(sch_1):page114_i40:clkout_srcp(2)" )
			)
			( pin "U7C1.H42"
				( objectStatus "@baseboard_fab2_lib.baseboard_fab2(sch_1):page114_i40:clkout_srcp(3)" )
			)
			( pin "U7C1.C28"
				( objectStatus "@baseboard_fab2_lib.baseboard_fab2(sch_1):page114_i40:clkout_srcp(4)" )
			)
			( pin "U7C1.G40"
				( objectStatus "@baseboard_fab2_lib.baseboard_fab2(sch_1):page114_i40:clkout_srcp(5)" )
			)
			( pin "U7C1.B33"
				( objectStatus "@baseboard_fab2_lib.baseboard_fab2(sch_1):page114_i40:clkout_srcp(6)" )
			)
			( pin "U7C1.K31"
				( objectStatus "@baseboard_fab2_lib.baseboard_fab2(sch_1):page114_i40:clkout_srcp(7)" )
			)
			( pin "U7C1.B31"
				( objectStatus "@baseboard_fab2_lib.baseboard_fab2(sch_1):page114_i40:clkout_srcp(8)" )
			)
			( pin "U7C1.G26"
				( objectStatus "@baseboard_fab2_lib.baseboard_fab2(sch_1):page114_i40:clkout_srcp(9)" )
			)
			( pin "U7C1.D23"
				( objectStatus "@baseboard_fab2_lib.baseboard_fab2(sch_1):page114_i40:clkout_srcp(10)" )
			)
			( pin "U7C1.D21"
				( objectStatus "@baseboard_fab2_lib.baseboard_fab2(sch_1):page114_i40:clkout_srcp(11)" )
			)
			( pin "U7C1.H24"
				( objectStatus "@baseboard_fab2_lib.baseboard_fab2(sch_1):page114_i40:clkout_srcp(12)" )
			)
			( pin "U7C1.A24"
				( objectStatus "@baseboard_fab2_lib.baseboard_fab2(sch_1):page114_i40:clkout_srcp(13)" )
			)
			( pin "U7C1.A20"
				( objectStatus "@baseboard_fab2_lib.baseboard_fab2(sch_1):page114_i40:clkout_srcp(14)" )
			)
			( pin "U7C1.H27"
				( objectStatus "@baseboard_fab2_lib.baseboard_fab2(sch_1):page114_i40:clkout_srcp(15)" )
			)
			( pin "U7C1.BW50"
				( objectStatus "@baseboard_fab2_lib.baseboard_fab2(sch_1):page114_i40:clockse_bmcclk" )
			)
			( pin "U7C1.BY51"
				( objectStatus "@baseboard_fab2_lib.baseboard_fab2(sch_1):page114_i40:clockse_pmsyncclk1" )
			)
			( pin "U7C1.BV51"
				( objectStatus "@baseboard_fab2_lib.baseboard_fab2(sch_1):page114_i40:clockse_pmsyncclk2" )
			)
			( pin "U7C1.C26"
				( objectStatus "@baseboard_fab2_lib.baseboard_fab2(sch_1):page114_i40:rsvd(64)" )
			)
			( pin "U7C1.A26"
				( objectStatus "@baseboard_fab2_lib.baseboard_fab2(sch_1):page114_i40:rsvd(65)" )
			)
			( pin "U7C1.K17"
				( objectStatus "@baseboard_fab2_lib.baseboard_fab2(sch_1):page114_i40:rtcx1" )
			)
			( pin "U7C1.H17"
				( objectStatus "@baseboard_fab2_lib.baseboard_fab2(sch_1):page114_i40:rtcx2" )
			)
			( pin "U7C1.G44"
				( objectStatus "@baseboard_fab2_lib.baseboard_fab2(sch_1):page114_i40:xclk_biasref" )
			)
			( pin "U7C1.B35"
				( objectStatus "@baseboard_fab2_lib.baseboard_fab2(sch_1):page114_i40:xtal_in" )
			)
			( pin "U7C1.D35"
				( objectStatus "@baseboard_fab2_lib.baseboard_fab2(sch_1):page114_i40:xtal_out" )
			)
			( pin "C3N38.1"
				( objectStatus "@baseboard_fab2_lib.baseboard_fab2(sch_1):page212_i146:a" )
			)
			( pin "C3N38.2"
				( objectStatus "@baseboard_fab2_lib.baseboard_fab2(sch_1):page212_i146:b" )
			)
			( pin "C7C5.1"
				( objectStatus "@baseboard_fab2_lib.baseboard_fab2(sch_1):page114_i47:a" )
			)
			( pin "C7C5.2"
				( objectStatus "@baseboard_fab2_lib.baseboard_fab2(sch_1):page114_i47:b" )
			)
			( pin "R7C1.1"
				( objectStatus "@baseboard_fab2_lib.baseboard_fab2(sch_1):page114_i48:a" )
			)
			( pin "R7C1.2"
				( objectStatus "@baseboard_fab2_lib.baseboard_fab2(sch_1):page114_i48:b" )
			)
			( pin "Y7C1.1"
				( objectStatus "@baseboard_fab2_lib.baseboard_fab2(sch_1):page114_i49:a" )
			)
			( pin "Y7C1.3"
				( objectStatus "@baseboard_fab2_lib.baseboard_fab2(sch_1):page114_i49:b" )
			)
			( pin "C7C4.1"
				( objectStatus "@baseboard_fab2_lib.baseboard_fab2(sch_1):page114_i50:a" )
			)
			( pin "C7C4.2"
				( objectStatus "@baseboard_fab2_lib.baseboard_fab2(sch_1):page114_i50:b" )
			)
			( pin "R7C6.1"
				( objectStatus "@baseboard_fab2_lib.baseboard_fab2(sch_1):page114_i54:a" )
			)
			( pin "R7C6.2"
				( objectStatus "@baseboard_fab2_lib.baseboard_fab2(sch_1):page114_i54:b" )
			)
			( pin "Y7C2.1"
				( objectStatus "@baseboard_fab2_lib.baseboard_fab2(sch_1):page114_i55:a" )
			)
			( pin "Y7C2.2"
				( objectStatus "@baseboard_fab2_lib.baseboard_fab2(sch_1):page114_i55:b" )
			)
			( pin "C3N26.1"
				( objectStatus "@baseboard_fab2_lib.baseboard_fab2(sch_1):page212_i145:a" )
			)
			( pin "C3N26.2"
				( objectStatus "@baseboard_fab2_lib.baseboard_fab2(sch_1):page212_i145:b" )
			)
			( pin "R8B20.1"
				( objectStatus "@baseboard_fab2_lib.baseboard_fab2(sch_1):page114_i110:a" )
			)
			( pin "R8B20.2"
				( objectStatus "@baseboard_fab2_lib.baseboard_fab2(sch_1):page114_i110:b" )
			)
			( pin "R8B21.1"
				( objectStatus "@baseboard_fab2_lib.baseboard_fab2(sch_1):page114_i124:a" )
			)
			( pin "R8B21.2"
				( objectStatus "@baseboard_fab2_lib.baseboard_fab2(sch_1):page114_i124:b" )
			)
			( pin "R3N1.1"
				( objectStatus "@baseboard_fab2_lib.baseboard_fab2(sch_1):page114_i149:a" )
			)
			( pin "R3N1.2"
				( objectStatus "@baseboard_fab2_lib.baseboard_fab2(sch_1):page114_i149:b" )
			)
			( pin "U7C1.BN68"
				( objectStatus "@baseboard_fab2_lib.baseboard_fab2(sch_1):page115_i74:rsvd(55)" )
			)
			( pin "U7C1.BN70"
				( objectStatus "@baseboard_fab2_lib.baseboard_fab2(sch_1):page115_i74:usb2_comp" )
			)
			( pin "U7C1.BR67"
				( objectStatus "@baseboard_fab2_lib.baseboard_fab2(sch_1):page115_i74:usb2_vbus" )
			)
			( pin "U7C1.BY60"
				( objectStatus "@baseboard_fab2_lib.baseboard_fab2(sch_1):page115_i74:usb2n_1" )
			)
			( pin "U7C1.CA61"
				( objectStatus "@baseboard_fab2_lib.baseboard_fab2(sch_1):page115_i74:usb2n_2" )
			)
			( pin "U7C1.CA59"
				( objectStatus "@baseboard_fab2_lib.baseboard_fab2(sch_1):page115_i74:usb2n_3" )
			)
			( pin "U7C1.BY62"
				( objectStatus "@baseboard_fab2_lib.baseboard_fab2(sch_1):page115_i74:usb2n_4" )
			)
			( pin "U7C1.BY58"
				( objectStatus "@baseboard_fab2_lib.baseboard_fab2(sch_1):page115_i74:usb2n_5" )
			)
			( pin "U7C1.CA63"
				( objectStatus "@baseboard_fab2_lib.baseboard_fab2(sch_1):page115_i74:usb2n_6" )
			)
			( pin "U7C1.CA57"
				( objectStatus "@baseboard_fab2_lib.baseboard_fab2(sch_1):page115_i74:usb2n_7" )
			)
			( pin "U7C1.BY64"
				( objectStatus "@baseboard_fab2_lib.baseboard_fab2(sch_1):page115_i74:usb2n_8" )
			)
			( pin "U7C1.BY55"
				( objectStatus "@baseboard_fab2_lib.baseboard_fab2(sch_1):page115_i74:usb2n_9" )
			)
			( pin "U7C1.BW65"
				( objectStatus "@baseboard_fab2_lib.baseboard_fab2(sch_1):page115_i74:usb2n_10" )
			)
			( pin "U7C1.CA54"
				( objectStatus "@baseboard_fab2_lib.baseboard_fab2(sch_1):page115_i74:usb2n_11" )
			)
			( pin "U7C1.BW67"
				( objectStatus "@baseboard_fab2_lib.baseboard_fab2(sch_1):page115_i74:usb2n_12" )
			)
			( pin "U7C1.BY53"
				( objectStatus "@baseboard_fab2_lib.baseboard_fab2(sch_1):page115_i74:usb2n_13" )
			)
			( pin "U7C1.BW68"
				( objectStatus "@baseboard_fab2_lib.baseboard_fab2(sch_1):page115_i74:usb2n_14" )
			)
			( pin "U7C1.BV60"
				( objectStatus "@baseboard_fab2_lib.baseboard_fab2(sch_1):page115_i74:usb2p_1" )
			)
			( pin "U7C1.BW61"
				( objectStatus "@baseboard_fab2_lib.baseboard_fab2(sch_1):page115_i74:usb2p_2" )
			)
			( pin "U7C1.BW59"
				( objectStatus "@baseboard_fab2_lib.baseboard_fab2(sch_1):page115_i74:usb2p_3" )
			)
			( pin "U7C1.BV62"
				( objectStatus "@baseboard_fab2_lib.baseboard_fab2(sch_1):page115_i74:usb2p_4" )
			)
			( pin "U7C1.BV58"
				( objectStatus "@baseboard_fab2_lib.baseboard_fab2(sch_1):page115_i74:usb2p_5" )
			)
			( pin "U7C1.BW63"
				( objectStatus "@baseboard_fab2_lib.baseboard_fab2(sch_1):page115_i74:usb2p_6" )
			)
			( pin "U7C1.BW57"
				( objectStatus "@baseboard_fab2_lib.baseboard_fab2(sch_1):page115_i74:usb2p_7" )
			)
			( pin "U7C1.BV64"
				( objectStatus "@baseboard_fab2_lib.baseboard_fab2(sch_1):page115_i74:usb2p_8" )
			)
			( pin "U7C1.BV55"
				( objectStatus "@baseboard_fab2_lib.baseboard_fab2(sch_1):page115_i74:usb2p_9" )
			)
			( pin "U7C1.BU65"
				( objectStatus "@baseboard_fab2_lib.baseboard_fab2(sch_1):page115_i74:usb2p_10" )
			)
			( pin "U7C1.BW54"
				( objectStatus "@baseboard_fab2_lib.baseboard_fab2(sch_1):page115_i74:usb2p_11" )
			)
			( pin "U7C1.BV66"
				( objectStatus "@baseboard_fab2_lib.baseboard_fab2(sch_1):page115_i74:usb2p_12" )
			)
			( pin "U7C1.BV53"
				( objectStatus "@baseboard_fab2_lib.baseboard_fab2(sch_1):page115_i74:usb2p_13" )
			)
			( pin "U7C1.BU67"
				( objectStatus "@baseboard_fab2_lib.baseboard_fab2(sch_1):page115_i74:usb2p_14" )
			)
			( pin "U7C1.BK71"
				( objectStatus "@baseboard_fab2_lib.baseboard_fab2(sch_1):page115_i74:usb3_1_rxn" )
			)
			( pin "U7C1.BK69"
				( objectStatus "@baseboard_fab2_lib.baseboard_fab2(sch_1):page115_i74:usb3_1_rxp" )
			)
			( pin "U7C1.BL52"
				( objectStatus "@baseboard_fab2_lib.baseboard_fab2(sch_1):page115_i74:usb3_1_txn" )
			)
			( pin "U7C1.BK54"
				( objectStatus "@baseboard_fab2_lib.baseboard_fab2(sch_1):page115_i74:usb3_1_txp" )
			)
			( pin "U7C1.BJ72"
				( objectStatus "@baseboard_fab2_lib.baseboard_fab2(sch_1):page115_i74:usb3_2_rxn" )
			)
			( pin "U7C1.BJ70"
				( objectStatus "@baseboard_fab2_lib.baseboard_fab2(sch_1):page115_i74:usb3_2_rxp" )
			)
			( pin "U7C1.BL56"
				( objectStatus "@baseboard_fab2_lib.baseboard_fab2(sch_1):page115_i74:usb3_2_txn" )
			)
			( pin "U7C1.BJ56"
				( objectStatus "@baseboard_fab2_lib.baseboard_fab2(sch_1):page115_i74:usb3_2_txp" )
			)
			( pin "U7C1.BH71"
				( objectStatus "@baseboard_fab2_lib.baseboard_fab2(sch_1):page115_i74:usb3_3_rxn" )
			)
			( pin "U7C1.BH69"
				( objectStatus "@baseboard_fab2_lib.baseboard_fab2(sch_1):page115_i74:usb3_3_rxp" )
			)
			( pin "U7C1.BM54"
				( objectStatus "@baseboard_fab2_lib.baseboard_fab2(sch_1):page115_i74:usb3_3_txn" )
			)
			( pin "U7C1.BN56"
				( objectStatus "@baseboard_fab2_lib.baseboard_fab2(sch_1):page115_i74:usb3_3_txp" )
			)
			( pin "U7C1.BF72"
				( objectStatus "@baseboard_fab2_lib.baseboard_fab2(sch_1):page115_i74:usb3_4_rxn" )
			)
			( pin "U7C1.BF70"
				( objectStatus "@baseboard_fab2_lib.baseboard_fab2(sch_1):page115_i74:usb3_4_rxp" )
			)
			( pin "U7C1.BH58"
				( objectStatus "@baseboard_fab2_lib.baseboard_fab2(sch_1):page115_i74:usb3_4_txn" )
			)
			( pin "U7C1.BG56"
				( objectStatus "@baseboard_fab2_lib.baseboard_fab2(sch_1):page115_i74:usb3_4_txp" )
			)
			( pin "U7C1.BE71"
				( objectStatus "@baseboard_fab2_lib.baseboard_fab2(sch_1):page115_i74:usb3_5_rxn" )
			)
			( pin "U7C1.BE69"
				( objectStatus "@baseboard_fab2_lib.baseboard_fab2(sch_1):page115_i74:usb3_5_rxp" )
			)
			( pin "U7C1.BK58"
				( objectStatus "@baseboard_fab2_lib.baseboard_fab2(sch_1):page115_i74:usb3_5_txn" )
			)
			( pin "U7C1.BJ59"
				( objectStatus "@baseboard_fab2_lib.baseboard_fab2(sch_1):page115_i74:usb3_5_txp" )
			)
			( pin "U7C1.BD72"
				( objectStatus "@baseboard_fab2_lib.baseboard_fab2(sch_1):page115_i74:usb3_6_rxn" )
			)
			( pin "U7C1.BD70"
				( objectStatus "@baseboard_fab2_lib.baseboard_fab2(sch_1):page115_i74:usb3_6_rxp" )
			)
			( pin "U7C1.BL59"
				( objectStatus "@baseboard_fab2_lib.baseboard_fab2(sch_1):page115_i74:usb3_6_txn" )
			)
			( pin "U7C1.BM61"
				( objectStatus "@baseboard_fab2_lib.baseboard_fab2(sch_1):page115_i74:usb3_6_txp" )
			)
			( pin "R8B9.1"
				( objectStatus "@baseboard_fab2_lib.baseboard_fab2(sch_1):page115_i90:a" )
			)
			( pin "R8B9.2"
				( objectStatus "@baseboard_fab2_lib.baseboard_fab2(sch_1):page115_i90:b" )
			)
			( pin "R8B32.1"
				( objectStatus "@baseboard_fab2_lib.baseboard_fab2(sch_1):page115_i114:a" )
			)
			( pin "R8B32.2"
				( objectStatus "@baseboard_fab2_lib.baseboard_fab2(sch_1):page115_i114:b" )
			)
			( pin "R3M11.1"
				( objectStatus "@baseboard_fab2_lib.baseboard_fab2(sch_1):page116_i108:a" )
			)
			( pin "R3M11.2"
				( objectStatus "@baseboard_fab2_lib.baseboard_fab2(sch_1):page116_i108:b" )
			)
			( pin "R3M12.1"
				( objectStatus "@baseboard_fab2_lib.baseboard_fab2(sch_1):page116_i181:a" )
			)
			( pin "R3M12.2"
				( objectStatus "@baseboard_fab2_lib.baseboard_fab2(sch_1):page116_i181:b" )
			)
			( pin "C25W21.1"
				( objectStatus "@baseboard_fab2_lib.baseboard_fab2(sch_1):page145_i159:a" )
			)
			( pin "C25W21.2"
				( objectStatus "@baseboard_fab2_lib.baseboard_fab2(sch_1):page145_i159:b" )
			)
			( pin "C25W20.1"
				( objectStatus "@baseboard_fab2_lib.baseboard_fab2(sch_1):page145_i158:a" )
			)
			( pin "C25W20.2"
				( objectStatus "@baseboard_fab2_lib.baseboard_fab2(sch_1):page145_i158:b" )
			)
			( pin "U7C1.D66"
				( objectStatus "@baseboard_fab2_lib.baseboard_fab2(sch_1):page116_i220:extclkn" )
			)
			( pin "U7C1.E67"
				( objectStatus "@baseboard_fab2_lib.baseboard_fab2(sch_1):page116_i220:extclkp" )
			)
			( pin "U7C1.AN70"
				( objectStatus "@baseboard_fab2_lib.baseboard_fab2(sch_1):page116_i220:pcie4_gbe_rxn" )
			)
			( pin "U7C1.AN72"
				( objectStatus "@baseboard_fab2_lib.baseboard_fab2(sch_1):page116_i220:pcie4_gbe_rxp" )
			)
			( pin "U7C1.BG66"
				( objectStatus "@baseboard_fab2_lib.baseboard_fab2(sch_1):page116_i220:pcie4_gbe_txn" )
			)
			( pin "U7C1.BJ66"
				( objectStatus "@baseboard_fab2_lib.baseboard_fab2(sch_1):page116_i220:pcie4_gbe_txp" )
			)
			( pin "U7C1.AM69"
				( objectStatus "@baseboard_fab2_lib.baseboard_fab2(sch_1):page116_i220:pcie5_gbe_rxn" )
			)
			( pin "U7C1.AM71"
				( objectStatus "@baseboard_fab2_lib.baseboard_fab2(sch_1):page116_i220:pcie5_gbe_rxp" )
			)
			( pin "U7C1.BH65"
				( objectStatus "@baseboard_fab2_lib.baseboard_fab2(sch_1):page116_i220:pcie5_gbe_txn" )
			)
			( pin "U7C1.BJ63"
				( objectStatus "@baseboard_fab2_lib.baseboard_fab2(sch_1):page116_i220:pcie5_gbe_txp" )
			)
			( pin "U7C1.BB63"
				( objectStatus "@baseboard_fab2_lib.baseboard_fab2(sch_1):page116_i220:pcie6_ssata0_rxn" )
			)
			( pin "U7C1.BD61"
				( objectStatus "@baseboard_fab2_lib.baseboard_fab2(sch_1):page116_i220:pcie6_ssata0_rxp" )
			)
			( pin "U7C1.AJ70"
				( objectStatus "@baseboard_fab2_lib.baseboard_fab2(sch_1):page116_i220:pcie6_ssata0_txn" )
			)
			( pin "U7C1.AJ72"
				( objectStatus "@baseboard_fab2_lib.baseboard_fab2(sch_1):page116_i220:pcie6_ssata0_txp" )
			)
			( pin "U7C1.AY59"
				( objectStatus "@baseboard_fab2_lib.baseboard_fab2(sch_1):page116_i220:pcie7_ssata1_rxn" )
			)
			( pin "U7C1.BA61"
				( objectStatus "@baseboard_fab2_lib.baseboard_fab2(sch_1):page116_i220:pcie7_ssata1_rxp" )
			)
			( pin "U7C1.AH69"
				( objectStatus "@baseboard_fab2_lib.baseboard_fab2(sch_1):page116_i220:pcie7_ssata1_txn" )
			)
			( pin "U7C1.AH71"
				( objectStatus "@baseboard_fab2_lib.baseboard_fab2(sch_1):page116_i220:pcie7_ssata1_txp" )
			)
			( pin "U7C1.BA65"
				( objectStatus "@baseboard_fab2_lib.baseboard_fab2(sch_1):page116_i220:pcie8_ssata2_gbe_rxn" )
			)
			( pin "U7C1.BD65"
				( objectStatus "@baseboard_fab2_lib.baseboard_fab2(sch_1):page116_i220:pcie8_ssata2_gbe_rxp" )
			)
			( pin "U7C1.AF70"
				( objectStatus "@baseboard_fab2_lib.baseboard_fab2(sch_1):page116_i220:pcie8_ssata2_gbe_txn" )
			)
			( pin "U7C1.AF72"
				( objectStatus "@baseboard_fab2_lib.baseboard_fab2(sch_1):page116_i220:pcie8_ssata2_gbe_txp" )
			)
			( pin "U7C1.AW65"
				( objectStatus "@baseboard_fab2_lib.baseboard_fab2(sch_1):page116_i220:pcie9_ssata3_rxn" )
			)
			( pin "U7C1.AY66"
				( objectStatus "@baseboard_fab2_lib.baseboard_fab2(sch_1):page116_i220:pcie9_ssata3_rxp" )
			)
			( pin "U7C1.AE69"
				( objectStatus "@baseboard_fab2_lib.baseboard_fab2(sch_1):page116_i220:pcie9_ssata3_txn" )
			)
			( pin "U7C1.AE71"
				( objectStatus "@baseboard_fab2_lib.baseboard_fab2(sch_1):page116_i220:pcie9_ssata3_txp" )
			)
			( pin "U7C1.AV63"
				( objectStatus "@baseboard_fab2_lib.baseboard_fab2(sch_1):page116_i220:pcie10_ssata4_rxn" )
			)
			( pin "U7C1.AU65"
				( objectStatus "@baseboard_fab2_lib.baseboard_fab2(sch_1):page116_i220:pcie10_ssata4_rxp" )
			)
			( pin "U7C1.AD70"
				( objectStatus "@baseboard_fab2_lib.baseboard_fab2(sch_1):page116_i220:pcie10_ssata4_txn" )
			)
			( pin "U7C1.AD72"
				( objectStatus "@baseboard_fab2_lib.baseboard_fab2(sch_1):page116_i220:pcie10_ssata4_txp" )
			)
			( pin "U7C1.AT66"
				( objectStatus "@baseboard_fab2_lib.baseboard_fab2(sch_1):page116_i220:pcie11_ssata5_gbe_rxn" )
			)
			( pin "U7C1.AV66"
				( objectStatus "@baseboard_fab2_lib.baseboard_fab2(sch_1):page116_i220:pcie11_ssata5_gbe_rxp" )
			)
			( pin "U7C1.AC69"
				( objectStatus "@baseboard_fab2_lib.baseboard_fab2(sch_1):page116_i220:pcie11_ssata5_gbe_txn" )
			)
			( pin "U7C1.AC71"
				( objectStatus "@baseboard_fab2_lib.baseboard_fab2(sch_1):page116_i220:pcie11_ssata5_gbe_txp" )
			)
			( pin "U7C1.AR61"
				( objectStatus "@baseboard_fab2_lib.baseboard_fab2(sch_1):page116_i220:pcie12_up0_sata0_rxn" )
			)
			( pin "U7C1.AT63"
				( objectStatus "@baseboard_fab2_lib.baseboard_fab2(sch_1):page116_i220:pcie12_up0_sata0_rxp" )
			)
			( pin "U7C1.W69"
				( objectStatus "@baseboard_fab2_lib.baseboard_fab2(sch_1):page116_i220:pcie12_up0_sata0_txn" )
			)
			( pin "U7C1.W71"
				( objectStatus "@baseboard_fab2_lib.baseboard_fab2(sch_1):page116_i220:pcie12_up0_sata0_txp" )
			)
			( pin "U7C1.AL66"
				( objectStatus "@baseboard_fab2_lib.baseboard_fab2(sch_1):page116_i220:pcie13_up1_sata1_rxn" )
			)
			( pin "U7C1.AN65"
				( objectStatus "@baseboard_fab2_lib.baseboard_fab2(sch_1):page116_i220:pcie13_up1_sata1_rxp" )
			)
			( pin "U7C1.V70"
				( objectStatus "@baseboard_fab2_lib.baseboard_fab2(sch_1):page116_i220:pcie13_up1_sata1_txn" )
			)
			( pin "U7C1.V72"
				( objectStatus "@baseboard_fab2_lib.baseboard_fab2(sch_1):page116_i220:pcie13_up1_sata1_txp" )
			)
			( pin "U7C1.AK65"
				( objectStatus "@baseboard_fab2_lib.baseboard_fab2(sch_1):page116_i220:pcie14_up2_sata2_rxn" )
			)
			( pin "U7C1.AJ63"
				( objectStatus "@baseboard_fab2_lib.baseboard_fab2(sch_1):page116_i220:pcie14_up2_sata2_rxp" )
			)
			( pin "U7C1.T69"
				( objectStatus "@baseboard_fab2_lib.baseboard_fab2(sch_1):page116_i220:pcie14_up2_sata2_txn" )
			)
			( pin "U7C1.T71"
				( objectStatus "@baseboard_fab2_lib.baseboard_fab2(sch_1):page116_i220:pcie14_up2_sata2_txp" )
			)
			( pin "U7C1.AP63"
				( objectStatus "@baseboard_fab2_lib.baseboard_fab2(sch_1):page116_i220:pcie15_up3_sata3_rxn" )
			)
			( pin "U7C1.AL63"
				( objectStatus "@baseboard_fab2_lib.baseboard_fab2(sch_1):page116_i220:pcie15_up3_sata3_rxp" )
			)
			( pin "U7C1.R70"
				( objectStatus "@baseboard_fab2_lib.baseboard_fab2(sch_1):page116_i220:pcie15_up3_sata3_txn" )
			)
			( pin "U7C1.R72"
				( objectStatus "@baseboard_fab2_lib.baseboard_fab2(sch_1):page116_i220:pcie15_up3_sata3_txp" )
			)
			( pin "U7C1.AF65"
				( objectStatus "@baseboard_fab2_lib.baseboard_fab2(sch_1):page116_i220:pcie16_up4_sata4_rxn" )
			)
			( pin "U7C1.AH65"
				( objectStatus "@baseboard_fab2_lib.baseboard_fab2(sch_1):page116_i220:pcie16_up4_sata4_rxp" )
			)
			( pin "U7C1.P69"
				( objectStatus "@baseboard_fab2_lib.baseboard_fab2(sch_1):page116_i220:pcie16_up4_sata4_txn" )
			)
			( pin "U7C1.P71"
				( objectStatus "@baseboard_fab2_lib.baseboard_fab2(sch_1):page116_i220:pcie16_up4_sata4_txp" )
			)
			( pin "U7C1.AH61"
				( objectStatus "@baseboard_fab2_lib.baseboard_fab2(sch_1):page116_i220:pcie17_up5_sata5_rxn" )
			)
			( pin "U7C1.AG63"
				( objectStatus "@baseboard_fab2_lib.baseboard_fab2(sch_1):page116_i220:pcie17_up5_sata5_rxp" )
			)
			( pin "U7C1.N70"
				( objectStatus "@baseboard_fab2_lib.baseboard_fab2(sch_1):page116_i220:pcie17_up5_sata5_txn" )
			)
			( pin "U7C1.N72"
				( objectStatus "@baseboard_fab2_lib.baseboard_fab2(sch_1):page116_i220:pcie17_up5_sata5_txp" )
			)
			( pin "U7C1.AP59"
				( objectStatus "@baseboard_fab2_lib.baseboard_fab2(sch_1):page116_i220:pcie18_up6_sata6_rxn" )
			)
			( pin "U7C1.AN61"
				( objectStatus "@baseboard_fab2_lib.baseboard_fab2(sch_1):page116_i220:pcie18_up6_sata6_rxp" )
			)
			( pin "U7C1.M69"
				( objectStatus "@baseboard_fab2_lib.baseboard_fab2(sch_1):page116_i220:pcie18_up6_sata6_txn" )
			)
			( pin "U7C1.M71"
				( objectStatus "@baseboard_fab2_lib.baseboard_fab2(sch_1):page116_i220:pcie18_up6_sata6_txp" )
			)
			( pin "U7C1.AA61"
				( objectStatus "@baseboard_fab2_lib.baseboard_fab2(sch_1):page116_i220:pcie19_up7_sata7_rxn" )
			)
			( pin "U7C1.AD61"
				( objectStatus "@baseboard_fab2_lib.baseboard_fab2(sch_1):page116_i220:pcie19_up7_sata7_rxp" )
			)
			( pin "U7C1.L70"
				( objectStatus "@baseboard_fab2_lib.baseboard_fab2(sch_1):page116_i220:pcie19_up7_sata7_txn" )
			)
			( pin "U7C1.L72"
				( objectStatus "@baseboard_fab2_lib.baseboard_fab2(sch_1):page116_i220:pcie19_up7_sata7_txp" )
			)
			( pin "U7C1.BD58"
				( objectStatus "@baseboard_fab2_lib.baseboard_fab2(sch_1):page116_i220:pcie_rcompn" )
			)
			( pin "U7C1.BB56"
				( objectStatus "@baseboard_fab2_lib.baseboard_fab2(sch_1):page116_i220:pcie_rcompp" )
			)
			( pin "U7C1.AF58"
				( objectStatus "@baseboard_fab2_lib.baseboard_fab2(sch_1):page116_i220:pcieup_rcompn" )
			)
			( pin "U7C1.AH58"
				( objectStatus "@baseboard_fab2_lib.baseboard_fab2(sch_1):page116_i220:pcieup_rcompp" )
			)
			( pin "U7C1.AP69"
				( objectStatus "@baseboard_fab2_lib.baseboard_fab2(sch_1):page116_i220:rsvd(47)" )
			)
			( pin "U7C1.AP71"
				( objectStatus "@baseboard_fab2_lib.baseboard_fab2(sch_1):page116_i220:rsvd(48)" )
			)
			( pin "U7C1.G67"
				( objectStatus "@baseboard_fab2_lib.baseboard_fab2(sch_1):page116_i220:rsvd(49)" )
			)
			( pin "U7C1.H69"
				( objectStatus "@baseboard_fab2_lib.baseboard_fab2(sch_1):page116_i220:rsvd(50)" )
			)
			( pin "U7C1.AA69"
				( objectStatus "@baseboard_fab2_lib.baseboard_fab2(sch_1):page116_i220:rsvd(51)" )
			)
			( pin "U7C1.AA71"
				( objectStatus "@baseboard_fab2_lib.baseboard_fab2(sch_1):page116_i220:rsvd(52)" )
			)
			( pin "U7C1.BA71"
				( objectStatus "@baseboard_fab2_lib.baseboard_fab2(sch_1):page116_i220:usb3_7_pcie0_rxn" )
			)
			( pin "U7C1.BA69"
				( objectStatus "@baseboard_fab2_lib.baseboard_fab2(sch_1):page116_i220:usb3_7_pcie0_rxp" )
			)
			( pin "U7C1.BR61"
				( objectStatus "@baseboard_fab2_lib.baseboard_fab2(sch_1):page116_i220:usb3_7_pcie0_txn" )
			)
			( pin "U7C1.BN63"
				( objectStatus "@baseboard_fab2_lib.baseboard_fab2(sch_1):page116_i220:usb3_7_pcie0_txp" )
			)
			( pin "U7C1.AY72"
				( objectStatus "@baseboard_fab2_lib.baseboard_fab2(sch_1):page116_i220:usb3_8_pcie1_rxn" )
			)
			( pin "U7C1.AY70"
				( objectStatus "@baseboard_fab2_lib.baseboard_fab2(sch_1):page116_i220:usb3_8_pcie1_rxp" )
			)
			( pin "U7C1.BM65"
				( objectStatus "@baseboard_fab2_lib.baseboard_fab2(sch_1):page116_i220:usb3_8_pcie1_txn" )
			)
			( pin "U7C1.BR65"
				( objectStatus "@baseboard_fab2_lib.baseboard_fab2(sch_1):page116_i220:usb3_8_pcie1_txp" )
			)
			( pin "U7C1.AW71"
				( objectStatus "@baseboard_fab2_lib.baseboard_fab2(sch_1):page116_i220:usb3_9_pcie2_rxn" )
			)
			( pin "U7C1.AW69"
				( objectStatus "@baseboard_fab2_lib.baseboard_fab2(sch_1):page116_i220:usb3_9_pcie2_rxp" )
			)
			( pin "U7C1.BK65"
				( objectStatus "@baseboard_fab2_lib.baseboard_fab2(sch_1):page116_i220:usb3_9_pcie2_txn" )
			)
			( pin "U7C1.BL66"
				( objectStatus "@baseboard_fab2_lib.baseboard_fab2(sch_1):page116_i220:usb3_9_pcie2_txp" )
			)
			( pin "U7C1.AV72"
				( objectStatus "@baseboard_fab2_lib.baseboard_fab2(sch_1):page116_i220:usb3_10_pcie3_gbe_rxn" )
			)
			( pin "U7C1.AV70"
				( objectStatus "@baseboard_fab2_lib.baseboard_fab2(sch_1):page116_i220:usb3_10_pcie3_gbe_rxp" )
			)
			( pin "U7C1.BH61"
				( objectStatus "@baseboard_fab2_lib.baseboard_fab2(sch_1):page116_i220:usb3_10_pcie3_gbe_txn" )
			)
			( pin "U7C1.BK61"
				( objectStatus "@baseboard_fab2_lib.baseboard_fab2(sch_1):page116_i220:usb3_10_pcie3_gbe_txp" )
			)
			( pin "R7B8.1"
				( objectStatus "@baseboard_fab2_lib.baseboard_fab2(sch_1):page116_i229:a" )
			)
			( pin "R7B8.2"
				( objectStatus "@baseboard_fab2_lib.baseboard_fab2(sch_1):page116_i229:b" )
			)
			( pin "R7B7.1"
				( objectStatus "@baseboard_fab2_lib.baseboard_fab2(sch_1):page116_i230:a" )
			)
			( pin "R7B7.2"
				( objectStatus "@baseboard_fab2_lib.baseboard_fab2(sch_1):page116_i230:b" )
			)
			( pin "R3M9.1"
				( objectStatus "@baseboard_fab2_lib.baseboard_fab2(sch_1):page116_i234:a" )
			)
			( pin "R3M9.2"
				( objectStatus "@baseboard_fab2_lib.baseboard_fab2(sch_1):page116_i234:b" )
			)
			( pin "R3M8.1"
				( objectStatus "@baseboard_fab2_lib.baseboard_fab2(sch_1):page116_i235:a" )
			)
			( pin "R3M8.2"
				( objectStatus "@baseboard_fab2_lib.baseboard_fab2(sch_1):page116_i235:b" )
			)
			( pin "U7C1.D42"
				( objectStatus "@baseboard_fab2_lib.baseboard_fab2(sch_1):page117_i9:dmi_rxn(0)" )
			)
			( pin "U7C1.C43"
				( objectStatus "@baseboard_fab2_lib.baseboard_fab2(sch_1):page117_i9:dmi_rxn(1)" )
			)
			( pin "U7C1.D44"
				( objectStatus "@baseboard_fab2_lib.baseboard_fab2(sch_1):page117_i9:dmi_rxn(2)" )
			)
			( pin "U7C1.C45"
				( objectStatus "@baseboard_fab2_lib.baseboard_fab2(sch_1):page117_i9:dmi_rxn(3)" )
			)
			( pin "U7C1.B42"
				( objectStatus "@baseboard_fab2_lib.baseboard_fab2(sch_1):page117_i9:dmi_rxp(0)" )
			)
			( pin "U7C1.A43"
				( objectStatus "@baseboard_fab2_lib.baseboard_fab2(sch_1):page117_i9:dmi_rxp(1)" )
			)
			( pin "U7C1.B44"
				( objectStatus "@baseboard_fab2_lib.baseboard_fab2(sch_1):page117_i9:dmi_rxp(2)" )
			)
			( pin "U7C1.A45"
				( objectStatus "@baseboard_fab2_lib.baseboard_fab2(sch_1):page117_i9:dmi_rxp(3)" )
			)
			( pin "U7C1.H46"
				( objectStatus "@baseboard_fab2_lib.baseboard_fab2(sch_1):page117_i9:dmi_txn(0)" )
			)
			( pin "U7C1.J48"
				( objectStatus "@baseboard_fab2_lib.baseboard_fab2(sch_1):page117_i9:dmi_txn(1)" )
			)
			( pin "U7C1.K50"
				( objectStatus "@baseboard_fab2_lib.baseboard_fab2(sch_1):page117_i9:dmi_txn(2)" )
			)
			( pin "U7C1.P52"
				( objectStatus "@baseboard_fab2_lib.baseboard_fab2(sch_1):page117_i9:dmi_txn(3)" )
			)
			( pin "U7C1.K46"
				( objectStatus "@baseboard_fab2_lib.baseboard_fab2(sch_1):page117_i9:dmi_txp(0)" )
			)
			( pin "U7C1.H50"
				( objectStatus "@baseboard_fab2_lib.baseboard_fab2(sch_1):page117_i9:dmi_txp(1)" )
			)
			( pin "U7C1.M52"
				( objectStatus "@baseboard_fab2_lib.baseboard_fab2(sch_1):page117_i9:dmi_txp(2)" )
			)
			( pin "U7C1.N54"
				( objectStatus "@baseboard_fab2_lib.baseboard_fab2(sch_1):page117_i9:dmi_txp(3)" )
			)
			( pin "U7C1.C48"
				( objectStatus "@baseboard_fab2_lib.baseboard_fab2(sch_1):page117_i9:pcieup_0_rxn" )
			)
			( pin "U7C1.A48"
				( objectStatus "@baseboard_fab2_lib.baseboard_fab2(sch_1):page117_i9:pcieup_0_rxp" )
			)
			( pin "U7C1.J52"
				( objectStatus "@baseboard_fab2_lib.baseboard_fab2(sch_1):page117_i9:pcieup_0_txn" )
			)
			( pin "U7C1.G52"
				( objectStatus "@baseboard_fab2_lib.baseboard_fab2(sch_1):page117_i9:pcieup_0_txp" )
			)
			( pin "U7C1.D49"
				( objectStatus "@baseboard_fab2_lib.baseboard_fab2(sch_1):page117_i9:pcieup_1_rxn" )
			)
			( pin "U7C1.B49"
				( objectStatus "@baseboard_fab2_lib.baseboard_fab2(sch_1):page117_i9:pcieup_1_rxp" )
			)
			( pin "U7C1.P56"
				( objectStatus "@baseboard_fab2_lib.baseboard_fab2(sch_1):page117_i9:pcieup_1_txn" )
			)
			( pin "U7C1.M56"
				( objectStatus "@baseboard_fab2_lib.baseboard_fab2(sch_1):page117_i9:pcieup_1_txp" )
			)
			( pin "U7C1.C50"
				( objectStatus "@baseboard_fab2_lib.baseboard_fab2(sch_1):page117_i9:pcieup_2_rxn" )
			)
			( pin "U7C1.A50"
				( objectStatus "@baseboard_fab2_lib.baseboard_fab2(sch_1):page117_i9:pcieup_2_rxp" )
			)
			( pin "U7C1.H54"
				( objectStatus "@baseboard_fab2_lib.baseboard_fab2(sch_1):page117_i9:pcieup_2_txn" )
			)
			( pin "U7C1.G56"
				( objectStatus "@baseboard_fab2_lib.baseboard_fab2(sch_1):page117_i9:pcieup_2_txp" )
			)
			( pin "U7C1.D51"
				( objectStatus "@baseboard_fab2_lib.baseboard_fab2(sch_1):page117_i9:pcieup_3_rxn" )
			)
			( pin "U7C1.B51"
				( objectStatus "@baseboard_fab2_lib.baseboard_fab2(sch_1):page117_i9:pcieup_3_rxp" )
			)
			( pin "U7C1.J56"
				( objectStatus "@baseboard_fab2_lib.baseboard_fab2(sch_1):page117_i9:pcieup_3_txn" )
			)
			( pin "U7C1.K58"
				( objectStatus "@baseboard_fab2_lib.baseboard_fab2(sch_1):page117_i9:pcieup_3_txp" )
			)
			( pin "U7C1.C52"
				( objectStatus "@baseboard_fab2_lib.baseboard_fab2(sch_1):page117_i9:pcieup_4_rxn" )
			)
			( pin "U7C1.A52"
				( objectStatus "@baseboard_fab2_lib.baseboard_fab2(sch_1):page117_i9:pcieup_4_rxp" )
			)
			( pin "U7C1.N58"
				( objectStatus "@baseboard_fab2_lib.baseboard_fab2(sch_1):page117_i9:pcieup_4_txn" )
			)
			( pin "U7C1.M59"
				( objectStatus "@baseboard_fab2_lib.baseboard_fab2(sch_1):page117_i9:pcieup_4_txp" )
			)
			( pin "U7C1.D53"
				( objectStatus "@baseboard_fab2_lib.baseboard_fab2(sch_1):page117_i9:pcieup_5_rxn" )
			)
			( pin "U7C1.B53"
				( objectStatus "@baseboard_fab2_lib.baseboard_fab2(sch_1):page117_i9:pcieup_5_rxp" )
			)
			( pin "U7C1.N61"
				( objectStatus "@baseboard_fab2_lib.baseboard_fab2(sch_1):page117_i9:pcieup_5_txn" )
			)
			( pin "U7C1.K61"
				( objectStatus "@baseboard_fab2_lib.baseboard_fab2(sch_1):page117_i9:pcieup_5_txp" )
			)
			( pin "U7C1.C54"
				( objectStatus "@baseboard_fab2_lib.baseboard_fab2(sch_1):page117_i9:pcieup_6_rxn" )
			)
			( pin "U7C1.A54"
				( objectStatus "@baseboard_fab2_lib.baseboard_fab2(sch_1):page117_i9:pcieup_6_rxp" )
			)
			( pin "U7C1.H61"
				( objectStatus "@baseboard_fab2_lib.baseboard_fab2(sch_1):page117_i9:pcieup_6_txn" )
			)
			( pin "U7C1.J63"
				( objectStatus "@baseboard_fab2_lib.baseboard_fab2(sch_1):page117_i9:pcieup_6_txp" )
			)
			( pin "U7C1.D55"
				( objectStatus "@baseboard_fab2_lib.baseboard_fab2(sch_1):page117_i9:pcieup_7_rxn" )
			)
			( pin "U7C1.B55"
				( objectStatus "@baseboard_fab2_lib.baseboard_fab2(sch_1):page117_i9:pcieup_7_rxp" )
			)
			( pin "U7C1.P59"
				( objectStatus "@baseboard_fab2_lib.baseboard_fab2(sch_1):page117_i9:pcieup_7_txn" )
			)
			( pin "U7C1.R61"
				( objectStatus "@baseboard_fab2_lib.baseboard_fab2(sch_1):page117_i9:pcieup_7_txp" )
			)
			( pin "U7C1.C57"
				( objectStatus "@baseboard_fab2_lib.baseboard_fab2(sch_1):page117_i9:pcieup_8_rxn" )
			)
			( pin "U7C1.A57"
				( objectStatus "@baseboard_fab2_lib.baseboard_fab2(sch_1):page117_i9:pcieup_8_rxp" )
			)
			( pin "U7C1.K65"
				( objectStatus "@baseboard_fab2_lib.baseboard_fab2(sch_1):page117_i9:pcieup_8_txn" )
			)
			( pin "U7C1.M63"
				( objectStatus "@baseboard_fab2_lib.baseboard_fab2(sch_1):page117_i9:pcieup_8_txp" )
			)
			( pin "U7C1.D58"
				( objectStatus "@baseboard_fab2_lib.baseboard_fab2(sch_1):page117_i9:pcieup_9_rxn" )
			)
			( pin "U7C1.B58"
				( objectStatus "@baseboard_fab2_lib.baseboard_fab2(sch_1):page117_i9:pcieup_9_rxp" )
			)
			( pin "U7C1.J66"
				( objectStatus "@baseboard_fab2_lib.baseboard_fab2(sch_1):page117_i9:pcieup_9_txn" )
			)
			( pin "U7C1.M66"
				( objectStatus "@baseboard_fab2_lib.baseboard_fab2(sch_1):page117_i9:pcieup_9_txp" )
			)
			( pin "U7C1.C59"
				( objectStatus "@baseboard_fab2_lib.baseboard_fab2(sch_1):page117_i9:pcieup_10_rxn" )
			)
			( pin "U7C1.A59"
				( objectStatus "@baseboard_fab2_lib.baseboard_fab2(sch_1):page117_i9:pcieup_10_rxp" )
			)
			( pin "U7C1.N65"
				( objectStatus "@baseboard_fab2_lib.baseboard_fab2(sch_1):page117_i9:pcieup_10_txn" )
			)
			( pin "U7C1.P66"
				( objectStatus "@baseboard_fab2_lib.baseboard_fab2(sch_1):page117_i9:pcieup_10_txp" )
			)
			( pin "U7C1.D60"
				( objectStatus "@baseboard_fab2_lib.baseboard_fab2(sch_1):page117_i9:pcieup_11_rxn" )
			)
			( pin "U7C1.B60"
				( objectStatus "@baseboard_fab2_lib.baseboard_fab2(sch_1):page117_i9:pcieup_11_rxp" )
			)
			( pin "U7C1.T59"
				( objectStatus "@baseboard_fab2_lib.baseboard_fab2(sch_1):page117_i9:pcieup_11_txn" )
			)
			( pin "U7C1.V59"
				( objectStatus "@baseboard_fab2_lib.baseboard_fab2(sch_1):page117_i9:pcieup_11_txp" )
			)
			( pin "U7C1.C61"
				( objectStatus "@baseboard_fab2_lib.baseboard_fab2(sch_1):page117_i9:pcieup_12_rxn" )
			)
			( pin "U7C1.A61"
				( objectStatus "@baseboard_fab2_lib.baseboard_fab2(sch_1):page117_i9:pcieup_12_rxp" )
			)
			( pin "U7C1.R65"
				( objectStatus "@baseboard_fab2_lib.baseboard_fab2(sch_1):page117_i9:pcieup_12_txn" )
			)
			( pin "U7C1.U65"
				( objectStatus "@baseboard_fab2_lib.baseboard_fab2(sch_1):page117_i9:pcieup_12_txp" )
			)
			( pin "U7C1.D62"
				( objectStatus "@baseboard_fab2_lib.baseboard_fab2(sch_1):page117_i9:pcieup_13_rxn" )
			)
			( pin "U7C1.B62"
				( objectStatus "@baseboard_fab2_lib.baseboard_fab2(sch_1):page117_i9:pcieup_13_rxp" )
			)
			( pin "U7C1.T63"
				( objectStatus "@baseboard_fab2_lib.baseboard_fab2(sch_1):page117_i9:pcieup_13_txn" )
			)
			( pin "U7C1.U61"
				( objectStatus "@baseboard_fab2_lib.baseboard_fab2(sch_1):page117_i9:pcieup_13_txp" )
			)
			( pin "U7C1.C63"
				( objectStatus "@baseboard_fab2_lib.baseboard_fab2(sch_1):page117_i9:pcieup_14_rxn" )
			)
			( pin "U7C1.A63"
				( objectStatus "@baseboard_fab2_lib.baseboard_fab2(sch_1):page117_i9:pcieup_14_rxp" )
			)
			( pin "U7C1.W65"
				( objectStatus "@baseboard_fab2_lib.baseboard_fab2(sch_1):page117_i9:pcieup_14_txn" )
			)
			( pin "U7C1.V63"
				( objectStatus "@baseboard_fab2_lib.baseboard_fab2(sch_1):page117_i9:pcieup_14_txp" )
			)
			( pin "U7C1.D64"
				( objectStatus "@baseboard_fab2_lib.baseboard_fab2(sch_1):page117_i9:pcieup_15_rxn" )
			)
			( pin "U7C1.B64"
				( objectStatus "@baseboard_fab2_lib.baseboard_fab2(sch_1):page117_i9:pcieup_15_rxp" )
			)
			( pin "U7C1.Y66"
				( objectStatus "@baseboard_fab2_lib.baseboard_fab2(sch_1):page117_i9:pcieup_15_txn" )
			)
			( pin "U7C1.AA65"
				( objectStatus "@baseboard_fab2_lib.baseboard_fab2(sch_1):page117_i9:pcieup_15_txp" )
			)
			( pin "R3N9.1"
				( objectStatus "@baseboard_fab2_lib.baseboard_fab2(sch_1):page118_i66:a" )
			)
			( pin "R3N9.2"
				( objectStatus "@baseboard_fab2_lib.baseboard_fab2(sch_1):page118_i66:b" )
			)
			( pin "R3N14.1"
				( objectStatus "@baseboard_fab2_lib.baseboard_fab2(sch_1):page118_i67:a" )
			)
			( pin "R3N14.2"
				( objectStatus "@baseboard_fab2_lib.baseboard_fab2(sch_1):page118_i67:b" )
			)
			( pin "R3N13.1"
				( objectStatus "@baseboard_fab2_lib.baseboard_fab2(sch_1):page118_i71:a" )
			)
			( pin "R3N13.2"
				( objectStatus "@baseboard_fab2_lib.baseboard_fab2(sch_1):page118_i71:b" )
			)
			( pin "U7C1.AT56"
				( objectStatus "@baseboard_fab2_lib.baseboard_fab2(sch_1):page118_i73:cpu_trst_n" )
			)
			( pin "U7C1.K13"
				( objectStatus "@baseboard_fab2_lib.baseboard_fab2(sch_1):page118_i73:dsw_pwrok" )
			)
			( pin "U7C1.G15"
				( objectStatus "@baseboard_fab2_lib.baseboard_fab2(sch_1):page118_i73:gpd0" )
			)
			( pin "U7C1.H13"
				( objectStatus "@baseboard_fab2_lib.baseboard_fab2(sch_1):page118_i73:gpd1_acpresent" )
			)
			( pin "U7C1.M11"
				( objectStatus "@baseboard_fab2_lib.baseboard_fab2(sch_1):page118_i73:gpd2_gbe_wake_n" )
			)
			( pin "U7C1.C15"
				( objectStatus "@baseboard_fab2_lib.baseboard_fab2(sch_1):page118_i73:gpd3_pwrbtn_n" )
			)
			( pin "U7C1.D14"
				( objectStatus "@baseboard_fab2_lib.baseboard_fab2(sch_1):page118_i73:gpd4_slp_s3_n" )
			)
			( pin "U7C1.B16"
				( objectStatus "@baseboard_fab2_lib.baseboard_fab2(sch_1):page118_i73:gpd5_slp_s4_n" )
			)
			( pin "U7C1.G11"
				( objectStatus "@baseboard_fab2_lib.baseboard_fab2(sch_1):page118_i73:gpd6_slp_a_n" )
			)
			( pin "U7C1.H9"
				( objectStatus "@baseboard_fab2_lib.baseboard_fab2(sch_1):page118_i73:gpd7" )
			)
			( pin "U7C1.C13"
				( objectStatus "@baseboard_fab2_lib.baseboard_fab2(sch_1):page118_i73:gpd8_susclk" )
			)
			( pin "U7C1.A15"
				( objectStatus "@baseboard_fab2_lib.baseboard_fab2(sch_1):page118_i73:gpd9" )
			)
			( pin "U7C1.B14"
				( objectStatus "@baseboard_fab2_lib.baseboard_fab2(sch_1):page118_i73:gpd10_slp_s5_n" )
			)
			( pin "U7C1.A13"
				( objectStatus "@baseboard_fab2_lib.baseboard_fab2(sch_1):page118_i73:gpd11_gbephy" )
			)
			( pin "U7C1.AR54"
				( objectStatus "@baseboard_fab2_lib.baseboard_fab2(sch_1):page118_i73:itp_pmode" )
			)
			( pin "U7C1.AL56"
				( objectStatus "@baseboard_fab2_lib.baseboard_fab2(sch_1):page118_i73:jtag_tck" )
			)
			( pin "U7C1.AN54"
				( objectStatus "@baseboard_fab2_lib.baseboard_fab2(sch_1):page118_i73:jtag_tdi" )
			)
			( pin "U7C1.AP56"
				( objectStatus "@baseboard_fab2_lib.baseboard_fab2(sch_1):page118_i73:jtag_tdo" )
			)
			( pin "U7C1.AH54"
				( objectStatus "@baseboard_fab2_lib.baseboard_fab2(sch_1):page118_i73:jtag_tms" )
			)
			( pin "U7C1.AF54"
				( objectStatus "@baseboard_fab2_lib.baseboard_fab2(sch_1):page118_i73:jtagx" )
			)
			( pin "U7C1.BB29"
				( objectStatus "@baseboard_fab2_lib.baseboard_fab2(sch_1):page118_i73:lan_rbias_0" )
			)
			( pin "U7C1.BD42"
				( objectStatus "@baseboard_fab2_lib.baseboard_fab2(sch_1):page118_i73:lan_rbias_1" )
			)
			( pin "U7C1.BH31"
				( objectStatus "@baseboard_fab2_lib.baseboard_fab2(sch_1):page118_i73:lan_rx_p0n" )
			)
			( pin "U7C1.BF31"
				( objectStatus "@baseboard_fab2_lib.baseboard_fab2(sch_1):page118_i73:lan_rx_p0p" )
			)
			( pin "U7C1.BG29"
				( objectStatus "@baseboard_fab2_lib.baseboard_fab2(sch_1):page118_i73:lan_rx_p1n" )
			)
			( pin "U7C1.BJ29"
				( objectStatus "@baseboard_fab2_lib.baseboard_fab2(sch_1):page118_i73:lan_rx_p1p" )
			)
			( pin "U7C1.BJ37"
				( objectStatus "@baseboard_fab2_lib.baseboard_fab2(sch_1):page118_i73:lan_rx_p2n" )
			)
			( pin "U7C1.BG37"
				( objectStatus "@baseboard_fab2_lib.baseboard_fab2(sch_1):page118_i73:lan_rx_p2p" )
			)
			( pin "U7C1.BF35"
				( objectStatus "@baseboard_fab2_lib.baseboard_fab2(sch_1):page118_i73:lan_rx_p3n" )
			)
			( pin "U7C1.BH35"
				( objectStatus "@baseboard_fab2_lib.baseboard_fab2(sch_1):page118_i73:lan_rx_p3p" )
			)
			( pin "U7C1.BM27"
				( objectStatus "@baseboard_fab2_lib.baseboard_fab2(sch_1):page118_i73:lan_tx_p0n" )
			)
			( pin "U7C1.BR27"
				( objectStatus "@baseboard_fab2_lib.baseboard_fab2(sch_1):page118_i73:lan_tx_p0p" )
			)
			( pin "U7C1.BM24"
				( objectStatus "@baseboard_fab2_lib.baseboard_fab2(sch_1):page118_i73:lan_tx_p1n" )
			)
			( pin "U7C1.BR24"
				( objectStatus "@baseboard_fab2_lib.baseboard_fab2(sch_1):page118_i73:lan_tx_p1p" )
			)
			( pin "U7C1.BM35"
				( objectStatus "@baseboard_fab2_lib.baseboard_fab2(sch_1):page118_i73:lan_tx_p2n" )
			)
			( pin "U7C1.BR35"
				( objectStatus "@baseboard_fab2_lib.baseboard_fab2(sch_1):page118_i73:lan_tx_p2p" )
			)
			( pin "U7C1.BR31"
				( objectStatus "@baseboard_fab2_lib.baseboard_fab2(sch_1):page118_i73:lan_tx_p3n" )
			)
			( pin "U7C1.BM31"
				( objectStatus "@baseboard_fab2_lib.baseboard_fab2(sch_1):page118_i73:lan_tx_p3p" )
			)
			( pin "U7C1.BV16"
				( objectStatus "@baseboard_fab2_lib.baseboard_fab2(sch_1):page118_i73:lan_xtal_in" )
			)
			( pin "U7C1.BY16"
				( objectStatus "@baseboard_fab2_lib.baseboard_fab2(sch_1):page118_i73:lan_xtal_out" )
			)
			( pin "U7C1.R17"
				( objectStatus "@baseboard_fab2_lib.baseboard_fab2(sch_1):page118_i73:pch_pwrok" )
			)
			( pin "U7C1.U9"
				( objectStatus "@baseboard_fab2_lib.baseboard_fab2(sch_1):page118_i73:peci" )
			)
			( pin "U7C1.U17"
				( objectStatus "@baseboard_fab2_lib.baseboard_fab2(sch_1):page118_i73:pltrst_cpu_n" )
			)
			( pin "U7C1.U13"
				( objectStatus "@baseboard_fab2_lib.baseboard_fab2(sch_1):page118_i73:pm_sync" )
			)
			( pin "U7C1.V7"
				( objectStatus "@baseboard_fab2_lib.baseboard_fab2(sch_1):page118_i73:pm_sync2" )
			)
			( pin "U7C1.AD54"
				( objectStatus "@baseboard_fab2_lib.baseboard_fab2(sch_1):page118_i73:prdy_n" )
			)
			( pin "U7C1.U54"
				( objectStatus "@baseboard_fab2_lib.baseboard_fab2(sch_1):page118_i73:preq_n" )
			)
			( pin "U7C1.R9"
				( objectStatus "@baseboard_fab2_lib.baseboard_fab2(sch_1):page118_i73:proc_pwrgd" )
			)
			( pin "U7C1.P15"
				( objectStatus "@baseboard_fab2_lib.baseboard_fab2(sch_1):page118_i73:rsmrst_n" )
			)
			( pin "U7C1.AA54"
				( objectStatus "@baseboard_fab2_lib.baseboard_fab2(sch_1):page118_i73:rsvd(32)" )
			)
			( pin "U7C1.V56"
				( objectStatus "@baseboard_fab2_lib.baseboard_fab2(sch_1):page118_i73:rsvd(33)" )
			)
			( pin "U7C1.Y56"
				( objectStatus "@baseboard_fab2_lib.baseboard_fab2(sch_1):page118_i73:rsvd(34)" )
			)
			( pin "U7C1.W54"
				( objectStatus "@baseboard_fab2_lib.baseboard_fab2(sch_1):page118_i73:rsvd(35)" )
			)
			( pin "U7C1.AK54"
				( objectStatus "@baseboard_fab2_lib.baseboard_fab2(sch_1):page118_i73:rsvd(36)" )
			)
			( pin "U7C1.BN29"
				( objectStatus "@baseboard_fab2_lib.baseboard_fab2(sch_1):page118_i73:rsvd(37)" )
			)
			( pin "U7C1.BL29"
				( objectStatus "@baseboard_fab2_lib.baseboard_fab2(sch_1):page118_i73:rsvd(38)" )
			)
			( pin "U7C1.BL26"
				( objectStatus "@baseboard_fab2_lib.baseboard_fab2(sch_1):page118_i73:rsvd(39)" )
			)
			( pin "U7C1.BN26"
				( objectStatus "@baseboard_fab2_lib.baseboard_fab2(sch_1):page118_i73:rsvd(40)" )
			)
			( pin "U7C1.BJ40"
				( objectStatus "@baseboard_fab2_lib.baseboard_fab2(sch_1):page118_i73:rsvd(41)" )
			)
			( pin "U7C1.BG40"
				( objectStatus "@baseboard_fab2_lib.baseboard_fab2(sch_1):page118_i73:rsvd(42)" )
			)
			( pin "U7C1.BL33"
				( objectStatus "@baseboard_fab2_lib.baseboard_fab2(sch_1):page118_i73:rsvd(43)" )
			)
			( pin "U7C1.BN33"
				( objectStatus "@baseboard_fab2_lib.baseboard_fab2(sch_1):page118_i73:rsvd(44)" )
			)
			( pin "U7C1.P22"
				( objectStatus "@baseboard_fab2_lib.baseboard_fab2(sch_1):page118_i73:rsvd(45)" )
			)
			( pin "U7C1.P26"
				( objectStatus "@baseboard_fab2_lib.baseboard_fab2(sch_1):page118_i73:rsvd(53)" )
			)
			( pin "U7C1.R24"
				( objectStatus "@baseboard_fab2_lib.baseboard_fab2(sch_1):page118_i73:rsvd(54)" )
			)
			( pin "U7C1.M15"
				( objectStatus "@baseboard_fab2_lib.baseboard_fab2(sch_1):page118_i73:slp_gbe_n" )
			)
			( pin "U7C1.P7"
				( objectStatus "@baseboard_fab2_lib.baseboard_fab2(sch_1):page118_i73:slp_sus_n" )
			)
			( pin "U7C1.BY19"
				( objectStatus "@baseboard_fab2_lib.baseboard_fab2(sch_1):page118_i73:sys_pwrok" )
			)
			( pin "U7C1.BV19"
				( objectStatus "@baseboard_fab2_lib.baseboard_fab2(sch_1):page118_i73:sys_reset_n" )
			)
			( pin "U7C1.V15"
				( objectStatus "@baseboard_fab2_lib.baseboard_fab2(sch_1):page118_i73:thrmtrip_n" )
			)
			( pin "U7C1.M7"
				( objectStatus "@baseboard_fab2_lib.baseboard_fab2(sch_1):page118_i73:trigger_in" )
			)
			( pin "U7C1.R13"
				( objectStatus "@baseboard_fab2_lib.baseboard_fab2(sch_1):page118_i73:trigger_out" )
			)
			( pin "U7C1.K9"
				( objectStatus "@baseboard_fab2_lib.baseboard_fab2(sch_1):page118_i73:wake_n" )
			)
			( pin "Y8C1.1"
				( objectStatus "@baseboard_fab2_lib.baseboard_fab2(sch_1):page118_i76:a" )
			)
			( pin "Y8C1.3"
				( objectStatus "@baseboard_fab2_lib.baseboard_fab2(sch_1):page118_i76:b" )
			)
			( pin "R2N4.1"
				( objectStatus "@baseboard_fab2_lib.baseboard_fab2(sch_1):page118_i96:a" )
			)
			( pin "R2N4.2"
				( objectStatus "@baseboard_fab2_lib.baseboard_fab2(sch_1):page118_i96:b" )
			)
			( pin "R2M6.1"
				( objectStatus "@baseboard_fab2_lib.baseboard_fab2(sch_1):page118_i99:a" )
			)
			( pin "R2M6.2"
				( objectStatus "@baseboard_fab2_lib.baseboard_fab2(sch_1):page118_i99:b" )
			)
			( pin "R8C24.1"
				( objectStatus "@baseboard_fab2_lib.baseboard_fab2(sch_1):page118_i120:a" )
			)
			( pin "R8C24.2"
				( objectStatus "@baseboard_fab2_lib.baseboard_fab2(sch_1):page118_i120:b" )
			)
			( pin "R8C23.1"
				( objectStatus "@baseboard_fab2_lib.baseboard_fab2(sch_1):page118_i125:a" )
			)
			( pin "R8C23.2"
				( objectStatus "@baseboard_fab2_lib.baseboard_fab2(sch_1):page118_i125:b" )
			)
			( pin "R2N6.1"
				( objectStatus "@baseboard_fab2_lib.baseboard_fab2(sch_1):page118_i128:a" )
			)
			( pin "R2N6.2"
				( objectStatus "@baseboard_fab2_lib.baseboard_fab2(sch_1):page118_i128:b" )
			)
			( pin "R7D23.1"
				( objectStatus "@baseboard_fab2_lib.baseboard_fab2(sch_1):page118_i131:a" )
			)
			( pin "R7D23.2"
				( objectStatus "@baseboard_fab2_lib.baseboard_fab2(sch_1):page118_i131:b" )
			)
			( pin "C7D1.1"
				( objectStatus "@baseboard_fab2_lib.baseboard_fab2(sch_1):page118_i136:a" )
			)
			( pin "C7D1.2"
				( objectStatus "@baseboard_fab2_lib.baseboard_fab2(sch_1):page118_i136:b" )
			)
			( pin "U7D1.2"
				( objectStatus "@baseboard_fab2_lib.baseboard_fab2(sch_1):page118_i142:a" )
			)
			( pin "U7D1.4"
				( objectStatus "@baseboard_fab2_lib.baseboard_fab2(sch_1):page118_i142:b" )
			)
			( pin "U7D1.1"
				( objectStatus "@baseboard_fab2_lib.baseboard_fab2(sch_1):page118_i142:oe_n" )
			)
			( pin "R7C23.1"
				( objectStatus "@baseboard_fab2_lib.baseboard_fab2(sch_1):page118_i144:a" )
			)
			( pin "R7C23.2"
				( objectStatus "@baseboard_fab2_lib.baseboard_fab2(sch_1):page118_i144:b" )
			)
			( pin "U7C1.N3"
				( objectStatus "@baseboard_fab2_lib.baseboard_fab2(sch_1):page119_i115:gpp_a0_rcin_n_espi_alert1_n" )
			)
			( pin "U7C1.Y3"
				( objectStatus "@baseboard_fab2_lib.baseboard_fab2(sch_1):page119_i115:gpp_a1_lad0_espi_io0" )
			)
			( pin "U7C1.N1"
				( objectStatus "@baseboard_fab2_lib.baseboard_fab2(sch_1):page119_i115:gpp_a2_lad1_espi_io1" )
			)
			( pin "U7C1.W2"
				( objectStatus "@baseboard_fab2_lib.baseboard_fab2(sch_1):page119_i115:gpp_a3_lad2_espi_io2" )
			)
			( pin "U7C1.Y1"
				( objectStatus "@baseboard_fab2_lib.baseboard_fab2(sch_1):page119_i115:gpp_a4_lad3_espi_io3" )
			)
			( pin "U7C1.P4"
				( objectStatus "@baseboard_fab2_lib.baseboard_fab2(sch_1):page119_i115:gpp_a5_lframe_n_espi_cs0_n" )
			)
			( pin "U7C1.P2"
				( objectStatus "@baseboard_fab2_lib.baseboard_fab2(sch_1):page119_i115:gpp_a6_serirq_espi_cs1_n" )
			)
			( pin "U7C1.AA2"
				( objectStatus "@baseboard_fab2_lib.baseboard_fab2(sch_1):page119_i115:gpp_a7_pirqa_n_espi_alert0_n" )
			)
			( pin "U7C1.AB1"
				( objectStatus "@baseboard_fab2_lib.baseboard_fab2(sch_1):page119_i115:gpp_a8_clkrun_n" )
			)
			( pin "U7C1.R3"
				( objectStatus "@baseboard_fab2_lib.baseboard_fab2(sch_1):page119_i115:gpp_a9_clkout_lpc0_espi_clk" )
			)
			( pin "U7C1.AA4"
				( objectStatus "@baseboard_fab2_lib.baseboard_fab2(sch_1):page119_i115:gpp_a10_clkout_lpc1" )
			)
			( pin "U7C1.AC2"
				( objectStatus "@baseboard_fab2_lib.baseboard_fab2(sch_1):page119_i115:gpp_a11_pme_n" )
			)
			( pin "U7C1.R1"
				( objectStatus "@baseboard_fab2_lib.baseboard_fab2(sch_1):page119_i115:gpp_a12_bmbusy_n_sxexithldoff_n" )
			)
			( pin "U7C1.T4"
				( objectStatus "@baseboard_fab2_lib.baseboard_fab2(sch_1):page119_i115:gpp_a13_suswarn_n_suspwrdnack" )
			)
			( pin "U7C1.AB3"
				( objectStatus "@baseboard_fab2_lib.baseboard_fab2(sch_1):page119_i115:gpp_a14_espi_reset_n" )
			)
			( pin "U7C1.AC4"
				( objectStatus "@baseboard_fab2_lib.baseboard_fab2(sch_1):page119_i115:gpp_a15_susack_n" )
			)
			( pin "U7C1.T2"
				( objectStatus "@baseboard_fab2_lib.baseboard_fab2(sch_1):page119_i115:gpp_a16_clkout_lpc2" )
			)
			( pin "U7C1.AD1"
				( objectStatus "@baseboard_fab2_lib.baseboard_fab2(sch_1):page119_i115:gpp_a17" )
			)
			( pin "U7C1.AD3"
				( objectStatus "@baseboard_fab2_lib.baseboard_fab2(sch_1):page119_i115:gpp_a18" )
			)
			( pin "U7C1.V3"
				( objectStatus "@baseboard_fab2_lib.baseboard_fab2(sch_1):page119_i115:gpp_a19" )
			)
			( pin "U7C1.W4"
				( objectStatus "@baseboard_fab2_lib.baseboard_fab2(sch_1):page119_i115:gpp_a20" )
			)
			( pin "U7C1.AE2"
				( objectStatus "@baseboard_fab2_lib.baseboard_fab2(sch_1):page119_i115:gpp_a21" )
			)
			( pin "U7C1.AE4"
				( objectStatus "@baseboard_fab2_lib.baseboard_fab2(sch_1):page119_i115:gpp_a22" )
			)
			( pin "U7C1.V1"
				( objectStatus "@baseboard_fab2_lib.baseboard_fab2(sch_1):page119_i115:gpp_a23" )
			)
			( pin "U7C1.BL7"
				( objectStatus "@baseboard_fab2_lib.baseboard_fab2(sch_1):page119_i115:gpp_b0_core_vid0" )
			)
			( pin "U7C1.BH9"
				( objectStatus "@baseboard_fab2_lib.baseboard_fab2(sch_1):page119_i115:gpp_b1_core_vid1" )
			)
			( pin "U7C1.BN15"
				( objectStatus "@baseboard_fab2_lib.baseboard_fab2(sch_1):page119_i115:gpp_b2" )
			)
			( pin "U7C1.BR9"
				( objectStatus "@baseboard_fab2_lib.baseboard_fab2(sch_1):page119_i115:gpp_b3_cpu_gp2" )
			)
			( pin "U7C1.BN7"
				( objectStatus "@baseboard_fab2_lib.baseboard_fab2(sch_1):page119_i115:gpp_b4_cpu_gp3" )
			)
			( pin "U7C1.BK17"
				( objectStatus "@baseboard_fab2_lib.baseboard_fab2(sch_1):page119_i115:gpp_b5_srcclkreq0_n" )
			)
			( pin "U7C1.BG18"
				( objectStatus "@baseboard_fab2_lib.baseboard_fab2(sch_1):page119_i115:gpp_b6_srcclkreq1_n" )
			)
			( pin "U7C1.BR13"
				( objectStatus "@baseboard_fab2_lib.baseboard_fab2(sch_1):page119_i115:gpp_b7_srcclkreq2_n" )
			)
			( pin "U7C1.BN11"
				( objectStatus "@baseboard_fab2_lib.baseboard_fab2(sch_1):page119_i115:gpp_b8_srcclkreq3_n" )
			)
			( pin "U7C1.BH20"
				( objectStatus "@baseboard_fab2_lib.baseboard_fab2(sch_1):page119_i115:gpp_b9_srcclkreq4_n" )
			)
			( pin "U7C1.BL11"
				( objectStatus "@baseboard_fab2_lib.baseboard_fab2(sch_1):page119_i115:gpp_b10_srcclkreq5_n" )
			)
			( pin "U7C1.BK9"
				( objectStatus "@baseboard_fab2_lib.baseboard_fab2(sch_1):page119_i115:gpp_b11" )
			)
			( pin "U7C1.BL18"
				( objectStatus "@baseboard_fab2_lib.baseboard_fab2(sch_1):page119_i115:gpp_b12_glb_rst_warn_n" )
			)
			( pin "U7C1.BN18"
				( objectStatus "@baseboard_fab2_lib.baseboard_fab2(sch_1):page119_i115:gpp_b13_pltrst_n" )
			)
			( pin "U7C1.BH13"
				( objectStatus "@baseboard_fab2_lib.baseboard_fab2(sch_1):page119_i115:gpp_b14_spkr" )
			)
			( pin "U7C1.BK13"
				( objectStatus "@baseboard_fab2_lib.baseboard_fab2(sch_1):page119_i115:gpp_b15" )
			)
			( pin "U7C1.BG22"
				( objectStatus "@baseboard_fab2_lib.baseboard_fab2(sch_1):page119_i115:gpp_b16" )
			)
			( pin "U7C1.BG15"
				( objectStatus "@baseboard_fab2_lib.baseboard_fab2(sch_1):page119_i115:gpp_b17" )
			)
			( pin "U7C1.BL15"
				( objectStatus "@baseboard_fab2_lib.baseboard_fab2(sch_1):page119_i115:gpp_b18" )
			)
			( pin "U7C1.BK20"
				( objectStatus "@baseboard_fab2_lib.baseboard_fab2(sch_1):page119_i115:gpp_b19" )
			)
			( pin "U7C1.BJ22"
				( objectStatus "@baseboard_fab2_lib.baseboard_fab2(sch_1):page119_i115:gpp_b20" )
			)
			( pin "U7C1.BH17"
				( objectStatus "@baseboard_fab2_lib.baseboard_fab2(sch_1):page119_i115:gpp_b21" )
			)
			( pin "U7C1.BR17"
				( objectStatus "@baseboard_fab2_lib.baseboard_fab2(sch_1):page119_i115:gpp_b22" )
			)
			( pin "U7C1.BM20"
				( objectStatus "@baseboard_fab2_lib.baseboard_fab2(sch_1):page119_i115:gpp_b23_meie_sml1alrt_n_phot_n" )
			)
			( pin "U7C1.BW28"
				( objectStatus "@baseboard_fab2_lib.baseboard_fab2(sch_1):page119_i115:gpp_c0_smbclk" )
			)
			( pin "U7C1.BV27"
				( objectStatus "@baseboard_fab2_lib.baseboard_fab2(sch_1):page119_i115:gpp_c1_smbdata" )
			)
			( pin "U7C1.BY27"
				( objectStatus "@baseboard_fab2_lib.baseboard_fab2(sch_1):page119_i115:gpp_c2_smbalert_n" )
			)
			( pin "U7C1.BV29"
				( objectStatus "@baseboard_fab2_lib.baseboard_fab2(sch_1):page119_i115:gpp_c3_sml0clk_ie" )
			)
			( pin "U7C1.BW30"
				( objectStatus "@baseboard_fab2_lib.baseboard_fab2(sch_1):page119_i115:gpp_c4_sml0data_ie" )
			)
			( pin "U7C1.BW34"
				( objectStatus "@baseboard_fab2_lib.baseboard_fab2(sch_1):page119_i115:gpp_c5_sml0alert_ie_n" )
			)
			( pin "U7C1.CA28"
				( objectStatus "@baseboard_fab2_lib.baseboard_fab2(sch_1):page119_i115:gpp_c6_sml1clk_ie" )
			)
			( pin "U7C1.BV35"
				( objectStatus "@baseboard_fab2_lib.baseboard_fab2(sch_1):page119_i115:gpp_c7_sml1data_ie" )
			)
			( pin "U7C1.BW32"
				( objectStatus "@baseboard_fab2_lib.baseboard_fab2(sch_1):page119_i115:gpp_c8" )
			)
			( pin "U7C1.BY29"
				( objectStatus "@baseboard_fab2_lib.baseboard_fab2(sch_1):page119_i115:gpp_c9" )
			)
			( pin "U7C1.BV31"
				( objectStatus "@baseboard_fab2_lib.baseboard_fab2(sch_1):page119_i115:gpp_c10" )
			)
			( pin "U7C1.BV33"
				( objectStatus "@baseboard_fab2_lib.baseboard_fab2(sch_1):page119_i115:gpp_c11" )
			)
			( pin "U7C1.CA30"
				( objectStatus "@baseboard_fab2_lib.baseboard_fab2(sch_1):page119_i115:gpp_c12" )
			)
			( pin "U7C1.BV38"
				( objectStatus "@baseboard_fab2_lib.baseboard_fab2(sch_1):page119_i115:gpp_c13" )
			)
			( pin "U7C1.BY38"
				( objectStatus "@baseboard_fab2_lib.baseboard_fab2(sch_1):page119_i115:gpp_c14" )
			)
			( pin "U7C1.CA32"
				( objectStatus "@baseboard_fab2_lib.baseboard_fab2(sch_1):page119_i115:gpp_c15" )
			)
			( pin "U7C1.BW37"
				( objectStatus "@baseboard_fab2_lib.baseboard_fab2(sch_1):page119_i115:gpp_c16" )
			)
			( pin "U7C1.BY31"
				( objectStatus "@baseboard_fab2_lib.baseboard_fab2(sch_1):page119_i115:gpp_c17" )
			)
			( pin "U7C1.BY35"
				( objectStatus "@baseboard_fab2_lib.baseboard_fab2(sch_1):page119_i115:gpp_c18" )
			)
			( pin "U7C1.BW39"
				( objectStatus "@baseboard_fab2_lib.baseboard_fab2(sch_1):page119_i115:gpp_c19" )
			)
			( pin "U7C1.CA39"
				( objectStatus "@baseboard_fab2_lib.baseboard_fab2(sch_1):page119_i115:gpp_c20" )
			)
			( pin "U7C1.BY33"
				( objectStatus "@baseboard_fab2_lib.baseboard_fab2(sch_1):page119_i115:gpp_c21" )
			)
			( pin "U7C1.CA34"
				( objectStatus "@baseboard_fab2_lib.baseboard_fab2(sch_1):page119_i115:gpp_c22" )
			)
			( pin "U7C1.CA37"
				( objectStatus "@baseboard_fab2_lib.baseboard_fab2(sch_1):page119_i115:gpp_c23" )
			)
			( pin "U7C1.BR42"
				( objectStatus "@baseboard_fab2_lib.baseboard_fab2(sch_1):page119_i115:gpp_d0" )
			)
			( pin "U7C1.BK46"
				( objectStatus "@baseboard_fab2_lib.baseboard_fab2(sch_1):page119_i115:gpp_d1" )
			)
			( pin "U7C1.BJ44"
				( objectStatus "@baseboard_fab2_lib.baseboard_fab2(sch_1):page119_i115:gpp_d2" )
			)
			( pin "U7C1.BW45"
				( objectStatus "@baseboard_fab2_lib.baseboard_fab2(sch_1):page119_i115:gpp_d3" )
			)
			( pin "U7C1.BM42"
				( objectStatus "@baseboard_fab2_lib.baseboard_fab2(sch_1):page119_i115:gpp_d4" )
			)
			( pin "U7C1.BM38"
				( objectStatus "@baseboard_fab2_lib.baseboard_fab2(sch_1):page119_i115:gpp_d5" )
			)
			( pin "U7C1.BW41"
				( objectStatus "@baseboard_fab2_lib.baseboard_fab2(sch_1):page119_i115:gpp_d6" )
			)
			( pin "U7C1.CA45"
				( objectStatus "@baseboard_fab2_lib.baseboard_fab2(sch_1):page119_i115:gpp_d7" )
			)
			( pin "U7C1.BR38"
				( objectStatus "@baseboard_fab2_lib.baseboard_fab2(sch_1):page119_i115:gpp_d8" )
			)
			( pin "U7C1.BY42"
				( objectStatus "@baseboard_fab2_lib.baseboard_fab2(sch_1):page119_i115:gpp_d9_ssata_devslp3" )
			)
			( pin "U7C1.BV47"
				( objectStatus "@baseboard_fab2_lib.baseboard_fab2(sch_1):page119_i115:gpp_d10_ssata_devslp4" )
			)
			( pin "U7C1.BY47"
				( objectStatus "@baseboard_fab2_lib.baseboard_fab2(sch_1):page119_i115:gpp_d11_ssata_devslp5" )
			)
			( pin "U7C1.BN40"
				( objectStatus "@baseboard_fab2_lib.baseboard_fab2(sch_1):page119_i115:gpp_d12_ssata_sdataout1" )
			)
			( pin "U7C1.BY44"
				( objectStatus "@baseboard_fab2_lib.baseboard_fab2(sch_1):page119_i115:gpp_d13_sml0bclk_ie" )
			)
			( pin "U7C1.BL44"
				( objectStatus "@baseboard_fab2_lib.baseboard_fab2(sch_1):page119_i115:gpp_d14_sml0bdata_ie" )
			)
			( pin "U7C1.BW43"
				( objectStatus "@baseboard_fab2_lib.baseboard_fab2(sch_1):page119_i115:gpp_d15_ssata_sdataout0" )
			)
			( pin "U7C1.BV42"
				( objectStatus "@baseboard_fab2_lib.baseboard_fab2(sch_1):page119_i115:gpp_d16_sml0balert_ie_n" )
			)
			( pin "U7C1.BW48"
				( objectStatus "@baseboard_fab2_lib.baseboard_fab2(sch_1):page119_i115:gpp_d17" )
			)
			( pin "U7C1.CA41"
				( objectStatus "@baseboard_fab2_lib.baseboard_fab2(sch_1):page119_i115:gpp_d18" )
			)
			( pin "U7C1.CA43"
				( objectStatus "@baseboard_fab2_lib.baseboard_fab2(sch_1):page119_i115:gpp_d19" )
			)
			( pin "U7C1.CA48"
				( objectStatus "@baseboard_fab2_lib.baseboard_fab2(sch_1):page119_i115:gpp_d20" )
			)
			( pin "U7C1.BV44"
				( objectStatus "@baseboard_fab2_lib.baseboard_fab2(sch_1):page119_i115:gpp_d21_ie_uart_rx" )
			)
			( pin "U7C1.BR46"
				( objectStatus "@baseboard_fab2_lib.baseboard_fab2(sch_1):page119_i115:gpp_d22_ie_uart_tx" )
			)
			( pin "U7C1.BN44"
				( objectStatus "@baseboard_fab2_lib.baseboard_fab2(sch_1):page119_i115:gpp_d23" )
			)
			( pin "R2M3.1"
				( objectStatus "@baseboard_fab2_lib.baseboard_fab2(sch_1):page119_i172:a" )
			)
			( pin "R2M3.2"
				( objectStatus "@baseboard_fab2_lib.baseboard_fab2(sch_1):page119_i172:b" )
			)
			( pin "R2N1.1"
				( objectStatus "@baseboard_fab2_lib.baseboard_fab2(sch_1):page119_i173:a" )
			)
			( pin "R2N1.2"
				( objectStatus "@baseboard_fab2_lib.baseboard_fab2(sch_1):page119_i173:b" )
			)
			( pin "R2M7.1"
				( objectStatus "@baseboard_fab2_lib.baseboard_fab2(sch_1):page119_i174:a" )
			)
			( pin "R2M7.2"
				( objectStatus "@baseboard_fab2_lib.baseboard_fab2(sch_1):page119_i174:b" )
			)
			( pin "Q9A2.6"
				( objectStatus "@baseboard_fab2_lib.baseboard_fab2(sch_1):page119_i175:drain(0)" )
			)
			( pin "Q9A2.2"
				( objectStatus "@baseboard_fab2_lib.baseboard_fab2(sch_1):page119_i175:gate(0)" )
			)
			( pin "Q9A2.1"
				( objectStatus "@baseboard_fab2_lib.baseboard_fab2(sch_1):page119_i175:source(0)" )
			)
			( pin "R9A20.1"
				( objectStatus "@baseboard_fab2_lib.baseboard_fab2(sch_1):page119_i178:a" )
			)
			( pin "R9A20.2"
				( objectStatus "@baseboard_fab2_lib.baseboard_fab2(sch_1):page119_i178:b" )
			)
			( pin "DS9A5.1"
				( objectStatus "@baseboard_fab2_lib.baseboard_fab2(sch_1):page119_i179:a" )
			)
			( pin "DS9A5.2"
				( objectStatus "@baseboard_fab2_lib.baseboard_fab2(sch_1):page119_i179:c" )
			)
			( pin "Q9A2.3"
				( objectStatus "@baseboard_fab2_lib.baseboard_fab2(sch_1):page119_i180:drain(0)" )
			)
			( pin "Q9A2.5"
				( objectStatus "@baseboard_fab2_lib.baseboard_fab2(sch_1):page119_i180:gate(0)" )
			)
			( pin "Q9A2.4"
				( objectStatus "@baseboard_fab2_lib.baseboard_fab2(sch_1):page119_i180:source(0)" )
			)
			( pin "R9A18.1"
				( objectStatus "@baseboard_fab2_lib.baseboard_fab2(sch_1):page119_i183:a" )
			)
			( pin "R9A18.2"
				( objectStatus "@baseboard_fab2_lib.baseboard_fab2(sch_1):page119_i183:b" )
			)
			( pin "R9A21.1"
				( objectStatus "@baseboard_fab2_lib.baseboard_fab2(sch_1):page119_i186:a" )
			)
			( pin "R9A21.2"
				( objectStatus "@baseboard_fab2_lib.baseboard_fab2(sch_1):page119_i186:b" )
			)
			( pin "R7C26.1"
				( objectStatus "@baseboard_fab2_lib.baseboard_fab2(sch_1):page119_i189:a" )
			)
			( pin "R7C26.2"
				( objectStatus "@baseboard_fab2_lib.baseboard_fab2(sch_1):page119_i189:b" )
			)
			( pin "R2U48.1"
				( objectStatus "@baseboard_fab2_lib.baseboard_fab2(sch_1):page119_i213:a" )
			)
			( pin "R2U48.2"
				( objectStatus "@baseboard_fab2_lib.baseboard_fab2(sch_1):page119_i213:b" )
			)
			( pin "R7W17.1"
				( objectStatus "@baseboard_fab2_lib.baseboard_fab2(sch_1):page119_i229:a" )
			)
			( pin "R7W17.2"
				( objectStatus "@baseboard_fab2_lib.baseboard_fab2(sch_1):page119_i229:b" )
			)
			( pin "U7C1.BY25"
				( objectStatus "@baseboard_fab2_lib.baseboard_fab2(sch_1):page120_i147:gpio_rcomp_3p3" )
			)
			( pin "U7C1.BH50"
				( objectStatus "@baseboard_fab2_lib.baseboard_fab2(sch_1):page120_i147:gpp_e0_sataxpcie0_satagp0" )
			)
			( pin "U7C1.AY52"
				( objectStatus "@baseboard_fab2_lib.baseboard_fab2(sch_1):page120_i147:gpp_e1_sataxpcie1_satagp1" )
			)
			( pin "U7C1.BG52"
				( objectStatus "@baseboard_fab2_lib.baseboard_fab2(sch_1):page120_i147:gpp_e2_sataxpcie2_satagp2" )
			)
			( pin "U7C1.BE52"
				( objectStatus "@baseboard_fab2_lib.baseboard_fab2(sch_1):page120_i147:gpp_e3_cpu_gp0" )
			)
			( pin "U7C1.AV52"
				( objectStatus "@baseboard_fab2_lib.baseboard_fab2(sch_1):page120_i147:gpp_e4_sata_devslp0" )
			)
			( pin "U7C1.AT52"
				( objectStatus "@baseboard_fab2_lib.baseboard_fab2(sch_1):page120_i147:gpp_e5_sata_devslp1" )
			)
			( pin "U7C1.BB52"
				( objectStatus "@baseboard_fab2_lib.baseboard_fab2(sch_1):page120_i147:gpp_e6_sata_devslp2" )
			)
			( pin "U7C1.BJ48"
				( objectStatus "@baseboard_fab2_lib.baseboard_fab2(sch_1):page120_i147:gpp_e7_cpu_gp1" )
			)
			( pin "U7C1.AV56"
				( objectStatus "@baseboard_fab2_lib.baseboard_fab2(sch_1):page120_i147:gpp_e8_sata_led_n" )
			)
			( pin "U7C1.BL48"
				( objectStatus "@baseboard_fab2_lib.baseboard_fab2(sch_1):page120_i147:gpp_e9_usb2_oc0_n" )
			)
			( pin "U7C1.BN48"
				( objectStatus "@baseboard_fab2_lib.baseboard_fab2(sch_1):page120_i147:gpp_e10_usb2_oc1_n" )
			)
			( pin "U7C1.AW54"
				( objectStatus "@baseboard_fab2_lib.baseboard_fab2(sch_1):page120_i147:gpp_e11_usb2_oc2_n" )
			)
			( pin "U7C1.AU58"
				( objectStatus "@baseboard_fab2_lib.baseboard_fab2(sch_1):page120_i147:gpp_e12_usb2_oc3_n" )
			)
			( pin "U7C1.AG7"
				( objectStatus "@baseboard_fab2_lib.baseboard_fab2(sch_1):page120_i147:gpp_f0_sataxpcie3_satagp3" )
			)
			( pin "U7C1.AK9"
				( objectStatus "@baseboard_fab2_lib.baseboard_fab2(sch_1):page120_i147:gpp_f1_sataxpcie4_satagp4" )
			)
			( pin "U7C1.AK20"
				( objectStatus "@baseboard_fab2_lib.baseboard_fab2(sch_1):page120_i147:gpp_f2_sataxpcie5_satagp5" )
			)
			( pin "U7C1.AK13"
				( objectStatus "@baseboard_fab2_lib.baseboard_fab2(sch_1):page120_i147:gpp_f3_sataxpcie6_satagp6" )
			)
			( pin "U7C1.AH13"
				( objectStatus "@baseboard_fab2_lib.baseboard_fab2(sch_1):page120_i147:gpp_f4_sataxpcie7_satagp7" )
			)
			( pin "U7C1.AH17"
				( objectStatus "@baseboard_fab2_lib.baseboard_fab2(sch_1):page120_i147:gpp_f5_sata_devslp3" )
			)
			( pin "U7C1.AL18"
				( objectStatus "@baseboard_fab2_lib.baseboard_fab2(sch_1):page120_i147:gpp_f6_sata_devslp4" )
			)
			( pin "U7C1.AK17"
				( objectStatus "@baseboard_fab2_lib.baseboard_fab2(sch_1):page120_i147:gpp_f7_sata_devslp5" )
			)
			( pin "U7C1.AH9"
				( objectStatus "@baseboard_fab2_lib.baseboard_fab2(sch_1):page120_i147:gpp_f8_sata_devslp6" )
			)
			( pin "U7C1.AR20"
				( objectStatus "@baseboard_fab2_lib.baseboard_fab2(sch_1):page120_i147:gpp_f9_sata_devslp7" )
			)
			( pin "U7C1.AL7"
				( objectStatus "@baseboard_fab2_lib.baseboard_fab2(sch_1):page120_i147:gpp_f10_sata_sclock" )
			)
			( pin "U7C1.AR9"
				( objectStatus "@baseboard_fab2_lib.baseboard_fab2(sch_1):page120_i147:gpp_f11_sata_sload" )
			)
			( pin "U7C1.AP7"
				( objectStatus "@baseboard_fab2_lib.baseboard_fab2(sch_1):page120_i147:gpp_f12_sata_sdataout1" )
			)
			( pin "U7C1.AP11"
				( objectStatus "@baseboard_fab2_lib.baseboard_fab2(sch_1):page120_i147:gpp_f13_sata_sdataout0" )
			)
			( pin "U7C1.AL11"
				( objectStatus "@baseboard_fab2_lib.baseboard_fab2(sch_1):page120_i147:gpp_f14_ssata_led_n" )
			)
			( pin "U7C1.AR13"
				( objectStatus "@baseboard_fab2_lib.baseboard_fab2(sch_1):page120_i147:gpp_f15_usb2_oc4_n" )
			)
			( pin "U7C1.AU13"
				( objectStatus "@baseboard_fab2_lib.baseboard_fab2(sch_1):page120_i147:gpp_f16_usb2_oc5_n" )
			)
			( pin "U7C1.AP15"
				( objectStatus "@baseboard_fab2_lib.baseboard_fab2(sch_1):page120_i147:gpp_f17_usb2_oc6_n" )
			)
			( pin "U7C1.AL15"
				( objectStatus "@baseboard_fab2_lib.baseboard_fab2(sch_1):page120_i147:gpp_f18_usb2_oc7_n" )
			)
			( pin "U7C1.AU9"
				( objectStatus "@baseboard_fab2_lib.baseboard_fab2(sch_1):page120_i147:gpp_f19_lan_smbclk" )
			)
			( pin "U7C1.AU20"
				( objectStatus "@baseboard_fab2_lib.baseboard_fab2(sch_1):page120_i147:gpp_f20_lan_smbdata" )
			)
			( pin "U7C1.AR17"
				( objectStatus "@baseboard_fab2_lib.baseboard_fab2(sch_1):page120_i147:gpp_f21_lan_smbalrt_n" )
			)
			( pin "U7C1.AP18"
				( objectStatus "@baseboard_fab2_lib.baseboard_fab2(sch_1):page120_i147:gpp_f22_ssata_sclock" )
			)
			( pin "U7C1.AU17"
				( objectStatus "@baseboard_fab2_lib.baseboard_fab2(sch_1):page120_i147:gpp_f23_ssata_sload" )
			)
			( pin "U7C1.AY11"
				( objectStatus "@baseboard_fab2_lib.baseboard_fab2(sch_1):page120_i147:gpp_g0_fantach0_fantach0ie" )
			)
			( pin "U7C1.AV15"
				( objectStatus "@baseboard_fab2_lib.baseboard_fab2(sch_1):page120_i147:gpp_g1_fantach1_fantach1ie" )
			)
			( pin "U7C1.BE22"
				( objectStatus "@baseboard_fab2_lib.baseboard_fab2(sch_1):page120_i147:gpp_g2_fantach2_fantach2ie" )
			)
			( pin "U7C1.AY7"
				( objectStatus "@baseboard_fab2_lib.baseboard_fab2(sch_1):page120_i147:gpp_g3_fantach3_fantach3ie" )
			)
			( pin "U7C1.BA9"
				( objectStatus "@baseboard_fab2_lib.baseboard_fab2(sch_1):page120_i147:gpp_g4_fantach4_fantach4ie" )
			)
			( pin "U7C1.AW20"
				( objectStatus "@baseboard_fab2_lib.baseboard_fab2(sch_1):page120_i147:gpp_g5_fantach5_fantach5ie" )
			)
			( pin "U7C1.AV18"
				( objectStatus "@baseboard_fab2_lib.baseboard_fab2(sch_1):page120_i147:gpp_g6_fantach6_fantach6ie" )
			)
			( pin "U7C1.AY15"
				( objectStatus "@baseboard_fab2_lib.baseboard_fab2(sch_1):page120_i147:gpp_g7_fantach7_fantach7ie" )
			)
			( pin "U7C1.BG11"
				( objectStatus "@baseboard_fab2_lib.baseboard_fab2(sch_1):page120_i147:gpp_g8_fanpwm0_fanpwm0ie" )
			)
			( pin "U7C1.AV11"
				( objectStatus "@baseboard_fab2_lib.baseboard_fab2(sch_1):page120_i147:gpp_g9_fanpwm1_fampwm1ie" )
			)
			( pin "U7C1.BE11"
				( objectStatus "@baseboard_fab2_lib.baseboard_fab2(sch_1):page120_i147:gpp_g10_fanpwm2_fanpwm2ie" )
			)
			( pin "U7C1.BA20"
				( objectStatus "@baseboard_fab2_lib.baseboard_fab2(sch_1):page120_i147:gpp_g11_fanpwm3_fanpmw3ie" )
			)
			( pin "U7C1.BD13"
				( objectStatus "@baseboard_fab2_lib.baseboard_fab2(sch_1):page120_i147:gpp_g12" )
			)
			( pin "U7C1.AY18"
				( objectStatus "@baseboard_fab2_lib.baseboard_fab2(sch_1):page120_i147:gpp_g13" )
			)
			( pin "U7C1.AV7"
				( objectStatus "@baseboard_fab2_lib.baseboard_fab2(sch_1):page120_i147:gpp_g14" )
			)
			( pin "U7C1.BE18"
				( objectStatus "@baseboard_fab2_lib.baseboard_fab2(sch_1):page120_i147:gpp_g15" )
			)
			( pin "U7C1.BD17"
				( objectStatus "@baseboard_fab2_lib.baseboard_fab2(sch_1):page120_i147:gpp_g16" )
			)
			( pin "U7C1.BD9"
				( objectStatus "@baseboard_fab2_lib.baseboard_fab2(sch_1):page120_i147:gpp_g17_adr_complete" )
			)
			( pin "U7C1.BE7"
				( objectStatus "@baseboard_fab2_lib.baseboard_fab2(sch_1):page120_i147:gpp_g18_nmi_n" )
			)
			( pin "U7C1.BE15"
				( objectStatus "@baseboard_fab2_lib.baseboard_fab2(sch_1):page120_i147:gpp_g19_smi_n" )
			)
			( pin "U7C1.BA17"
				( objectStatus "@baseboard_fab2_lib.baseboard_fab2(sch_1):page120_i147:gpp_g20_ssata_devslp0" )
			)
			( pin "U7C1.BG7"
				( objectStatus "@baseboard_fab2_lib.baseboard_fab2(sch_1):page120_i147:gpp_g21_ssata_devslp1" )
			)
			( pin "U7C1.BD20"
				( objectStatus "@baseboard_fab2_lib.baseboard_fab2(sch_1):page120_i147:gpp_g22_ssata_devslp2" )
			)
			( pin "U7C1.BA13"
				( objectStatus "@baseboard_fab2_lib.baseboard_fab2(sch_1):page120_i147:gpp_g23_ssataxpcie0_ssatagp0" )
			)
			( pin "U7C1.AT4"
				( objectStatus "@baseboard_fab2_lib.baseboard_fab2(sch_1):page120_i147:gpp_h0_srcclkreq6_n" )
			)
			( pin "U7C1.AW4"
				( objectStatus "@baseboard_fab2_lib.baseboard_fab2(sch_1):page120_i147:gpp_h1_srcclkreq7_n" )
			)
			( pin "U7C1.AV3"
				( objectStatus "@baseboard_fab2_lib.baseboard_fab2(sch_1):page120_i147:gpp_h2_srcclkreq8_n" )
			)
			( pin "U7C1.AR1"
				( objectStatus "@baseboard_fab2_lib.baseboard_fab2(sch_1):page120_i147:gpp_h3_srcclkreq9_n" )
			)
			( pin "U7C1.AT2"
				( objectStatus "@baseboard_fab2_lib.baseboard_fab2(sch_1):page120_i147:gpp_h4_srcclkreq10_n" )
			)
			( pin "U7C1.AY3"
				( objectStatus "@baseboard_fab2_lib.baseboard_fab2(sch_1):page120_i147:gpp_h5_srcclkreq11_n" )
			)
			( pin "U7C1.AW2"
				( objectStatus "@baseboard_fab2_lib.baseboard_fab2(sch_1):page120_i147:gpp_h6_srcclkreq12_n" )
			)
			( pin "U7C1.AV1"
				( objectStatus "@baseboard_fab2_lib.baseboard_fab2(sch_1):page120_i147:gpp_h7_srcclkreq13_n" )
			)
			( pin "U7C1.AR3"
				( objectStatus "@baseboard_fab2_lib.baseboard_fab2(sch_1):page120_i147:gpp_h8_srcclkreq14_n" )
			)
			( pin "U7C1.BE2"
				( objectStatus "@baseboard_fab2_lib.baseboard_fab2(sch_1):page120_i147:gpp_h9_srcclkreq15_n" )
			)
			( pin "U7C1.BA4"
				( objectStatus "@baseboard_fab2_lib.baseboard_fab2(sch_1):page120_i147:gpp_h10_sml2clk_ie" )
			)
			( pin "U7C1.BD1"
				( objectStatus "@baseboard_fab2_lib.baseboard_fab2(sch_1):page120_i147:gpp_h11_sml2data_ie" )
			)
			( pin "U7C1.BB1"
				( objectStatus "@baseboard_fab2_lib.baseboard_fab2(sch_1):page120_i147:gpp_h12_sml2alert_n_ie_n" )
			)
			( pin "U7C1.AY1"
				( objectStatus "@baseboard_fab2_lib.baseboard_fab2(sch_1):page120_i147:gpp_h13_sml3clk_ie" )
			)
			( pin "U7C1.BC2"
				( objectStatus "@baseboard_fab2_lib.baseboard_fab2(sch_1):page120_i147:gpp_h14_sml3data_ie" )
			)
			( pin "U7C1.BB3"
				( objectStatus "@baseboard_fab2_lib.baseboard_fab2(sch_1):page120_i147:gpp_h15_sml3alert_n_ie_n" )
			)
			( pin "U7C1.BF1"
				( objectStatus "@baseboard_fab2_lib.baseboard_fab2(sch_1):page120_i147:gpp_h16_sml4clk_ie" )
			)
			( pin "U7C1.BE4"
				( objectStatus "@baseboard_fab2_lib.baseboard_fab2(sch_1):page120_i147:gpp_h17_sml4data_ie" )
			)
			( pin "U7C1.BC4"
				( objectStatus "@baseboard_fab2_lib.baseboard_fab2(sch_1):page120_i147:gpp_h18_sml4alert_n_ie_n" )
			)
			( pin "U7C1.BD3"
				( objectStatus "@baseboard_fab2_lib.baseboard_fab2(sch_1):page120_i147:gpp_h19_ssataxpcie1_ssatagp1" )
			)
			( pin "U7C1.BF3"
				( objectStatus "@baseboard_fab2_lib.baseboard_fab2(sch_1):page120_i147:gpp_h20_ssataxpcie2_ssatagp2" )
			)
			( pin "U7C1.BA2"
				( objectStatus "@baseboard_fab2_lib.baseboard_fab2(sch_1):page120_i147:gpp_h21_ssataxpcie3_ssatagp3" )
			)
			( pin "U7C1.BH2"
				( objectStatus "@baseboard_fab2_lib.baseboard_fab2(sch_1):page120_i147:gpp_h22_ssataxpcie4_ssatagp4" )
			)
			( pin "U7C1.BH4"
				( objectStatus "@baseboard_fab2_lib.baseboard_fab2(sch_1):page120_i147:gpp_h23_ssataxpcie5_ssatagp5" )
			)
			( pin "U7C1.CA20"
				( objectStatus "@baseboard_fab2_lib.baseboard_fab2(sch_1):page120_i147:gpp_i0_lan_tdo" )
			)
			( pin "U7C1.BV21"
				( objectStatus "@baseboard_fab2_lib.baseboard_fab2(sch_1):page120_i147:gpp_i1_lan_tck" )
			)
			( pin "U7C1.CA22"
				( objectStatus "@baseboard_fab2_lib.baseboard_fab2(sch_1):page120_i147:gpp_i2_lan_tms" )
			)
			( pin "U7C1.BY23"
				( objectStatus "@baseboard_fab2_lib.baseboard_fab2(sch_1):page120_i147:gpp_i3_lan_tdi" )
			)
			( pin "U7C1.BW20"
				( objectStatus "@baseboard_fab2_lib.baseboard_fab2(sch_1):page120_i147:gpp_i4_do_reset_in_n" )
			)
			( pin "U7C1.BW24"
				( objectStatus "@baseboard_fab2_lib.baseboard_fab2(sch_1):page120_i147:gpp_i5_do_reset_out_n" )
			)
			( pin "U7C1.BV23"
				( objectStatus "@baseboard_fab2_lib.baseboard_fab2(sch_1):page120_i147:gpp_i6_reset_done" )
			)
			( pin "U7C1.CA24"
				( objectStatus "@baseboard_fab2_lib.baseboard_fab2(sch_1):page120_i147:gpp_i7_lan_trst_n" )
			)
			( pin "U7C1.BW22"
				( objectStatus "@baseboard_fab2_lib.baseboard_fab2(sch_1):page120_i147:gpp_i8_pci_dis_n" )
			)
			( pin "U7C1.BY21"
				( objectStatus "@baseboard_fab2_lib.baseboard_fab2(sch_1):page120_i147:gpp_i9_lan_dis_n" )
			)
			( pin "U7C1.BV25"
				( objectStatus "@baseboard_fab2_lib.baseboard_fab2(sch_1):page120_i147:gpp_i10" )
			)
			( pin "U7C1.BL1"
				( objectStatus "@baseboard_fab2_lib.baseboard_fab2(sch_1):page120_i147:gpp_j0_lan_led_p0_0" )
			)
			( pin "U7C1.BK4"
				( objectStatus "@baseboard_fab2_lib.baseboard_fab2(sch_1):page120_i147:gpp_j1_lan_led_p0_1" )
			)
			( pin "U7C1.BP4"
				( objectStatus "@baseboard_fab2_lib.baseboard_fab2(sch_1):page120_i147:gpp_j2_lan_led_p1_0" )
			)
			( pin "U7C1.BK2"
				( objectStatus "@baseboard_fab2_lib.baseboard_fab2(sch_1):page120_i147:gpp_j3_lan_led_p1_1" )
			)
			( pin "U7C1.BL3"
				( objectStatus "@baseboard_fab2_lib.baseboard_fab2(sch_1):page120_i147:gpp_j4_lan_led_p2_0" )
			)
			( pin "U7C1.BU6"
				( objectStatus "@baseboard_fab2_lib.baseboard_fab2(sch_1):page120_i147:gpp_j5_lan_led_p2_1" )
			)
			( pin "U7C1.CA13"
				( objectStatus "@baseboard_fab2_lib.baseboard_fab2(sch_1):page120_i147:gpp_j6_lan_led_p3_0" )
			)
			( pin "U7C1.BM2"
				( objectStatus "@baseboard_fab2_lib.baseboard_fab2(sch_1):page120_i147:gpp_j7_lan_led_p3_1" )
			)
			( pin "U7C1.BM4"
				( objectStatus "@baseboard_fab2_lib.baseboard_fab2(sch_1):page120_i147:gpp_j8_lan_i2c_scl_mdc_p0" )
			)
			( pin "U7C1.BN3"
				( objectStatus "@baseboard_fab2_lib.baseboard_fab2(sch_1):page120_i147:gpp_j9_lan_i2c_sda_mdio_p0" )
			)
			( pin "U7C1.BW5"
				( objectStatus "@baseboard_fab2_lib.baseboard_fab2(sch_1):page120_i147:gpp_j10_lan_i2c_scl_mdc_p1" )
			)
			( pin "U7C1.BV8"
				( objectStatus "@baseboard_fab2_lib.baseboard_fab2(sch_1):page120_i147:gpp_j11_lan_i2c_sda_mdio_p1" )
			)
			( pin "U7C1.BT5"
				( objectStatus "@baseboard_fab2_lib.baseboard_fab2(sch_1):page120_i147:gpp_j12_lan_i2c_scl_mdc_p2" )
			)
			( pin "U7C1.BW11"
				( objectStatus "@baseboard_fab2_lib.baseboard_fab2(sch_1):page120_i147:gpp_j13_lan_i2c_sda_mdio_p2" )
			)
			( pin "U7C1.BW6"
				( objectStatus "@baseboard_fab2_lib.baseboard_fab2(sch_1):page120_i147:gpp_j14_lan_i2c_scl_mdc_p3" )
			)
			( pin "U7C1.BW9"
				( objectStatus "@baseboard_fab2_lib.baseboard_fab2(sch_1):page120_i147:gpp_j15_lan_i2c_sda_mdio_p3" )
			)
			( pin "U7C1.BV10"
				( objectStatus "@baseboard_fab2_lib.baseboard_fab2(sch_1):page120_i147:gpp_j16_lan_sdp_p0_0" )
			)
			( pin "U7C1.CA11"
				( objectStatus "@baseboard_fab2_lib.baseboard_fab2(sch_1):page120_i147:gpp_j17_lan_sdp_p0_1" )
			)
			( pin "U7C1.BY10"
				( objectStatus "@baseboard_fab2_lib.baseboard_fab2(sch_1):page120_i147:gpp_j18_lan_sdp_p1_0" )
			)
			( pin "U7C1.BY14"
				( objectStatus "@baseboard_fab2_lib.baseboard_fab2(sch_1):page120_i147:gpp_j19_lan_sdp_p1_1" )
			)
			( pin "U7C1.BW13"
				( objectStatus "@baseboard_fab2_lib.baseboard_fab2(sch_1):page120_i147:gpp_j20_lan_sdp_p2_0" )
			)
			( pin "U7C1.BV12"
				( objectStatus "@baseboard_fab2_lib.baseboard_fab2(sch_1):page120_i147:gpp_j21_lan_sdp_p2_1" )
			)
			( pin "U7C1.BY12"
				( objectStatus "@baseboard_fab2_lib.baseboard_fab2(sch_1):page120_i147:gpp_j22_lan_sdp_p3_0" )
			)
			( pin "U7C1.BV14"
				( objectStatus "@baseboard_fab2_lib.baseboard_fab2(sch_1):page120_i147:gpp_j23_lan_sdp_p3_1" )
			)
			( pin "R7W16.1"
				( objectStatus "@baseboard_fab2_lib.baseboard_fab2(sch_1):page120_i276:a" )
			)
			( pin "R7W16.2"
				( objectStatus "@baseboard_fab2_lib.baseboard_fab2(sch_1):page120_i276:b" )
			)
			( pin "R2M1.1"
				( objectStatus "@baseboard_fab2_lib.baseboard_fab2(sch_1):page120_i218:a" )
			)
			( pin "R2M1.2"
				( objectStatus "@baseboard_fab2_lib.baseboard_fab2(sch_1):page120_i218:b" )
			)
			( pin "R2N26.1"
				( objectStatus "@baseboard_fab2_lib.baseboard_fab2(sch_1):page120_i219:a" )
			)
			( pin "R2N26.2"
				( objectStatus "@baseboard_fab2_lib.baseboard_fab2(sch_1):page120_i219:b" )
			)
			( pin "R7C15.1"
				( objectStatus "@baseboard_fab2_lib.baseboard_fab2(sch_1):page121_i31:a" )
			)
			( pin "R7C15.2"
				( objectStatus "@baseboard_fab2_lib.baseboard_fab2(sch_1):page121_i31:b" )
			)
			( pin "R7C16.1"
				( objectStatus "@baseboard_fab2_lib.baseboard_fab2(sch_1):page121_i33:a" )
			)
			( pin "R7C16.2"
				( objectStatus "@baseboard_fab2_lib.baseboard_fab2(sch_1):page121_i33:b" )
			)
			( pin "U7C1.C70"
				( objectStatus "@baseboard_fab2_lib.baseboard_fab2(sch_1):page121_i34:cgc_dut_detect_n" )
			)
			( pin "U7C1.AM4"
				( objectStatus "@baseboard_fab2_lib.baseboard_fab2(sch_1):page121_i34:gpio_rcomp_1p8_3p3" )
			)
			( pin "U7C1.AJ1"
				( objectStatus "@baseboard_fab2_lib.baseboard_fab2(sch_1):page121_i34:gpp_k0_lan_ncsi_clk_in" )
			)
			( pin "U7C1.AM2"
				( objectStatus "@baseboard_fab2_lib.baseboard_fab2(sch_1):page121_i34:gpp_k1_lan_ncsi_txd0" )
			)
			( pin "U7C1.AK2"
				( objectStatus "@baseboard_fab2_lib.baseboard_fab2(sch_1):page121_i34:gpp_k2_lan_ncsi_txd1" )
			)
			( pin "U7C1.AL3"
				( objectStatus "@baseboard_fab2_lib.baseboard_fab2(sch_1):page121_i34:gpp_k3_lan_ncsi_tx_en" )
			)
			( pin "U7C1.AN3"
				( objectStatus "@baseboard_fab2_lib.baseboard_fab2(sch_1):page121_i34:gpp_k4_lan_ncsi_crs_dv" )
			)
			( pin "U7C1.AL1"
				( objectStatus "@baseboard_fab2_lib.baseboard_fab2(sch_1):page121_i34:gpp_k5_lan_ncsi_rxd0" )
			)
			( pin "U7C1.AN1"
				( objectStatus "@baseboard_fab2_lib.baseboard_fab2(sch_1):page121_i34:gpp_k6_lan_ncsi_rxd1" )
			)
			( pin "U7C1.AH2"
				( objectStatus "@baseboard_fab2_lib.baseboard_fab2(sch_1):page121_i34:gpp_k7" )
			)
			( pin "U7C1.AJ3"
				( objectStatus "@baseboard_fab2_lib.baseboard_fab2(sch_1):page121_i34:gpp_k8_lan_ncsi_arb_in" )
			)
			( pin "U7C1.AK4"
				( objectStatus "@baseboard_fab2_lib.baseboard_fab2(sch_1):page121_i34:gpp_k9_lan_ncsi_arb_out" )
			)
			( pin "U7C1.AH4"
				( objectStatus "@baseboard_fab2_lib.baseboard_fab2(sch_1):page121_i34:gpp_k10_pe_rst_n" )
			)
			( pin "U7C1.AE18"
				( objectStatus "@baseboard_fab2_lib.baseboard_fab2(sch_1):page121_i34:gpp_l2_testch0_d0" )
			)
			( pin "U7C1.AE15"
				( objectStatus "@baseboard_fab2_lib.baseboard_fab2(sch_1):page121_i34:gpp_l3_testch0_d1" )
			)
			( pin "U7C1.AE11"
				( objectStatus "@baseboard_fab2_lib.baseboard_fab2(sch_1):page121_i34:gpp_l4_testch0_d2" )
			)
			( pin "U7C1.Y18"
				( objectStatus "@baseboard_fab2_lib.baseboard_fab2(sch_1):page121_i34:gpp_l5_testch0_d3" )
			)
			( pin "U7C1.AA20"
				( objectStatus "@baseboard_fab2_lib.baseboard_fab2(sch_1):page121_i34:gpp_l6_testch0_d4" )
			)
			( pin "U7C1.AA17"
				( objectStatus "@baseboard_fab2_lib.baseboard_fab2(sch_1):page121_i34:gpp_l7_testch0_d5" )
			)
			( pin "U7C1.AD9"
				( objectStatus "@baseboard_fab2_lib.baseboard_fab2(sch_1):page121_i34:gpp_l8_testch0_d6" )
			)
			( pin "U7C1.AD17"
				( objectStatus "@baseboard_fab2_lib.baseboard_fab2(sch_1):page121_i34:gpp_l9_testch0_d7" )
			)
			( pin "U7C1.AF20"
				( objectStatus "@baseboard_fab2_lib.baseboard_fab2(sch_1):page121_i34:gpp_l10_testch0_clk" )
			)
			( pin "U7C1.AD20"
				( objectStatus "@baseboard_fab2_lib.baseboard_fab2(sch_1):page121_i34:gpp_l11_testch1_d0" )
			)
			( pin "U7C1.Y15"
				( objectStatus "@baseboard_fab2_lib.baseboard_fab2(sch_1):page121_i34:gpp_l12_testch1_d1" )
			)
			( pin "U7C1.AD13"
				( objectStatus "@baseboard_fab2_lib.baseboard_fab2(sch_1):page121_i34:gpp_l13_testch1_d2" )
			)
			( pin "U7C1.AA13"
				( objectStatus "@baseboard_fab2_lib.baseboard_fab2(sch_1):page121_i34:gpp_l14_testch1_d3" )
			)
			( pin "U7C1.Y11"
				( objectStatus "@baseboard_fab2_lib.baseboard_fab2(sch_1):page121_i34:gpp_l15_testch1_d4" )
			)
			( pin "U7C1.Y7"
				( objectStatus "@baseboard_fab2_lib.baseboard_fab2(sch_1):page121_i34:gpp_l16_testch1_d5" )
			)
			( pin "U7C1.AA9"
				( objectStatus "@baseboard_fab2_lib.baseboard_fab2(sch_1):page121_i34:gpp_l17_testch1_d6" )
			)
			( pin "U7C1.AE7"
				( objectStatus "@baseboard_fab2_lib.baseboard_fab2(sch_1):page121_i34:gpp_l18_testch1_d7" )
			)
			( pin "U7C1.AG11"
				( objectStatus "@baseboard_fab2_lib.baseboard_fab2(sch_1):page121_i34:gpp_l19_testch1_clk" )
			)
			( pin "U7C1.P18"
				( objectStatus "@baseboard_fab2_lib.baseboard_fab2(sch_1):page121_i34:hda_bclk" )
			)
			( pin "U7C1.M18"
				( objectStatus "@baseboard_fab2_lib.baseboard_fab2(sch_1):page121_i34:hda_rst_n" )
			)
			( pin "U7C1.K20"
				( objectStatus "@baseboard_fab2_lib.baseboard_fab2(sch_1):page121_i34:hda_sdi_0" )
			)
			( pin "U7C1.V18"
				( objectStatus "@baseboard_fab2_lib.baseboard_fab2(sch_1):page121_i34:hda_sdi_1" )
			)
			( pin "U7C1.U24"
				( objectStatus "@baseboard_fab2_lib.baseboard_fab2(sch_1):page121_i34:hda_sdo" )
			)
			( pin "U7C1.H20"
				( objectStatus "@baseboard_fab2_lib.baseboard_fab2(sch_1):page121_i34:hda_sync" )
			)
			( pin "U7C1.AG18"
				( objectStatus "@baseboard_fab2_lib.baseboard_fab2(sch_1):page121_i34:intruder_n" )
			)
			( pin "U7C1.AF61"
				( objectStatus "@baseboard_fab2_lib.baseboard_fab2(sch_1):page121_i34:rsvd(0)" )
			)
			( pin "U7C1.AC56"
				( objectStatus "@baseboard_fab2_lib.baseboard_fab2(sch_1):page121_i34:rsvd(1)" )
			)
			( pin "U7C1.AA58"
				( objectStatus "@baseboard_fab2_lib.baseboard_fab2(sch_1):page121_i34:rsvd(2)" )
			)
			( pin "U7C1.V11"
				( objectStatus "@baseboard_fab2_lib.baseboard_fab2(sch_1):page121_i34:rsvd(3)" )
			)
			( pin "U7C1.P37"
				( objectStatus "@baseboard_fab2_lib.baseboard_fab2(sch_1):page121_i34:rsvd(4)" )
			)
			( pin "U7C1.AG15"
				( objectStatus "@baseboard_fab2_lib.baseboard_fab2(sch_1):page121_i34:rsvd(5)" )
			)
			( pin "U7C1.AT69"
				( objectStatus "@baseboard_fab2_lib.baseboard_fab2(sch_1):page121_i34:rsvd(6)" )
			)
			( pin "U7C1.F8"
				( objectStatus "@baseboard_fab2_lib.baseboard_fab2(sch_1):page121_i34:rsvd(7)" )
			)
			( pin "U7C1.F69"
				( objectStatus "@baseboard_fab2_lib.baseboard_fab2(sch_1):page121_i34:rsvd(8)" )
			)
			( pin "U7C1.F66"
				( objectStatus "@baseboard_fab2_lib.baseboard_fab2(sch_1):page121_i34:rsvd(9)" )
			)
			( pin "U7C1.D8"
				( objectStatus "@baseboard_fab2_lib.baseboard_fab2(sch_1):page121_i34:rsvd(10)" )
			)
			( pin "U7C1.C18"
				( objectStatus "@baseboard_fab2_lib.baseboard_fab2(sch_1):page121_i34:rsvd(11)" )
			)
			( pin "U7C1.C68"
				( objectStatus "@baseboard_fab2_lib.baseboard_fab2(sch_1):page121_i34:rsvd(12)" )
			)
			( pin "U7C1.C67"
				( objectStatus "@baseboard_fab2_lib.baseboard_fab2(sch_1):page121_i34:rsvd(13)" )
			)
			( pin "U7C1.E18"
				( objectStatus "@baseboard_fab2_lib.baseboard_fab2(sch_1):page121_i34:rsvd(14)" )
			)
			( pin "U7C1.C6"
				( objectStatus "@baseboard_fab2_lib.baseboard_fab2(sch_1):page121_i34:rsvd(15)" )
			)
			( pin "U7C1.C5"
				( objectStatus "@baseboard_fab2_lib.baseboard_fab2(sch_1):page121_i34:rsvd(16)" )
			)
			( pin "U7C1.B10"
				( objectStatus "@baseboard_fab2_lib.baseboard_fab2(sch_1):page121_i34:rsvd(17)" )
			)
			( pin "U7C1.C11"
				( objectStatus "@baseboard_fab2_lib.baseboard_fab2(sch_1):page121_i34:rsvd(18)" )
			)
			( pin "U7C1.C9"
				( objectStatus "@baseboard_fab2_lib.baseboard_fab2(sch_1):page121_i34:rsvd(19)" )
			)
			( pin "U7C1.D10"
				( objectStatus "@baseboard_fab2_lib.baseboard_fab2(sch_1):page121_i34:rsvd(20)" )
			)
			( pin "U7C1.A11"
				( objectStatus "@baseboard_fab2_lib.baseboard_fab2(sch_1):page121_i34:rsvd(21)" )
			)
			( pin "U7C1.AT71"
				( objectStatus "@baseboard_fab2_lib.baseboard_fab2(sch_1):page121_i34:rsvd(22)" )
			)
			( pin "U7C1.P40"
				( objectStatus "@baseboard_fab2_lib.baseboard_fab2(sch_1):page121_i34:rsvd(23)" )
			)
			( pin "U7C1.P44"
				( objectStatus "@baseboard_fab2_lib.baseboard_fab2(sch_1):page121_i34:rsvd(24)" )
			)
			( pin "U7C1.P48"
				( objectStatus "@baseboard_fab2_lib.baseboard_fab2(sch_1):page121_i34:rsvd(25)" )
			)
			( pin "U7C1.BH24"
				( objectStatus "@baseboard_fab2_lib.baseboard_fab2(sch_1):page121_i34:rsvd(26)" )
			)
			( pin "U7C1.BG26"
				( objectStatus "@baseboard_fab2_lib.baseboard_fab2(sch_1):page121_i34:rsvd(27)" )
			)
			( pin "U7C1.BW3"
				( objectStatus "@baseboard_fab2_lib.baseboard_fab2(sch_1):page121_i34:rsvd(46)" )
			)
			( pin "U7C1.U20"
				( objectStatus "@baseboard_fab2_lib.baseboard_fab2(sch_1):page121_i34:rsvd(66)" )
			)
			( pin "U7C1.R20"
				( objectStatus "@baseboard_fab2_lib.baseboard_fab2(sch_1):page121_i34:rsvd(67)" )
			)
			( pin "U7C1.V22"
				( objectStatus "@baseboard_fab2_lib.baseboard_fab2(sch_1):page121_i34:rsvd(68)" )
			)
			( pin "U7C1.P11"
				( objectStatus "@baseboard_fab2_lib.baseboard_fab2(sch_1):page121_i34:rtcrst_n" )
			)
			( pin "U7C1.K2"
				( objectStatus "@baseboard_fab2_lib.baseboard_fab2(sch_1):page121_i34:spi0_clk" )
			)
			( pin "U7C1.J3"
				( objectStatus "@baseboard_fab2_lib.baseboard_fab2(sch_1):page121_i34:spi0_flash_cs0_n" )
			)
			( pin "U7C1.G7"
				( objectStatus "@baseboard_fab2_lib.baseboard_fab2(sch_1):page121_i34:spi0_flash_cs1_n" )
			)
			( pin "U7C1.F5"
				( objectStatus "@baseboard_fab2_lib.baseboard_fab2(sch_1):page121_i34:spi0_io2" )
			)
			( pin "U7C1.L1"
				( objectStatus "@baseboard_fab2_lib.baseboard_fab2(sch_1):page121_i34:spi0_io3" )
			)
			( pin "U7C1.L3"
				( objectStatus "@baseboard_fab2_lib.baseboard_fab2(sch_1):page121_i34:spi0_miso_io1" )
			)
			( pin "U7C1.H4"
				( objectStatus "@baseboard_fab2_lib.baseboard_fab2(sch_1):page121_i34:spi0_mosi_io0" )
			)
			( pin "U7C1.K4"
				( objectStatus "@baseboard_fab2_lib.baseboard_fab2(sch_1):page121_i34:spi0_tpm_cs_n" )
			)
			( pin "U7C1.G18"
				( objectStatus "@baseboard_fab2_lib.baseboard_fab2(sch_1):page121_i34:srtcrst_n" )
			)
			( pin "R8C26.1"
				( objectStatus "@baseboard_fab2_lib.baseboard_fab2(sch_1):page121_i35:a" )
			)
			( pin "R8C26.2"
				( objectStatus "@baseboard_fab2_lib.baseboard_fab2(sch_1):page121_i35:b" )
			)
			( pin "R3N10.1"
				( objectStatus "@baseboard_fab2_lib.baseboard_fab2(sch_1):page121_i37:a" )
			)
			( pin "R3N10.2"
				( objectStatus "@baseboard_fab2_lib.baseboard_fab2(sch_1):page121_i37:b" )
			)
			( pin "R7C20.1"
				( objectStatus "@baseboard_fab2_lib.baseboard_fab2(sch_1):page121_i73:a" )
			)
			( pin "R7C20.2"
				( objectStatus "@baseboard_fab2_lib.baseboard_fab2(sch_1):page121_i73:b" )
			)
			( pin "R3P3.1"
				( objectStatus "@baseboard_fab2_lib.baseboard_fab2(sch_1):page121_i89:a" )
			)
			( pin "R3P3.2"
				( objectStatus "@baseboard_fab2_lib.baseboard_fab2(sch_1):page121_i89:b" )
			)
			( pin "R3P2.1"
				( objectStatus "@baseboard_fab2_lib.baseboard_fab2(sch_1):page121_i90:a" )
			)
			( pin "R3P2.2"
				( objectStatus "@baseboard_fab2_lib.baseboard_fab2(sch_1):page121_i90:b" )
			)
			( pin "R2P1.1"
				( objectStatus "@baseboard_fab2_lib.baseboard_fab2(sch_1):page121_i91:a" )
			)
			( pin "R2P1.2"
				( objectStatus "@baseboard_fab2_lib.baseboard_fab2(sch_1):page121_i91:b" )
			)
			( pin "R7C14.1"
				( objectStatus "@baseboard_fab2_lib.baseboard_fab2(sch_1):page121_i98:a" )
			)
			( pin "R7C14.2"
				( objectStatus "@baseboard_fab2_lib.baseboard_fab2(sch_1):page121_i98:b" )
			)
			( pin "R8D11.1"
				( objectStatus "@baseboard_fab2_lib.baseboard_fab2(sch_1):page121_i101:a" )
			)
			( pin "R8D11.2"
				( objectStatus "@baseboard_fab2_lib.baseboard_fab2(sch_1):page121_i101:b" )
			)
			( pin "U7C1.R35"
				( objectStatus "@baseboard_fab2_lib.baseboard_fab2(sch_1):page122_i63:rsvd(28)" )
			)
			( pin "U7C1.P33"
				( objectStatus "@baseboard_fab2_lib.baseboard_fab2(sch_1):page122_i63:rsvd(29)" )
			)
			( pin "U7C1.R31"
				( objectStatus "@baseboard_fab2_lib.baseboard_fab2(sch_1):page122_i63:rsvd(30)" )
			)
			( pin "U7C1.P29"
				( objectStatus "@baseboard_fab2_lib.baseboard_fab2(sch_1):page122_i63:rsvd(31)" )
			)
			( pin "U7C1.AP27"
				( objectStatus "@baseboard_fab2_lib.baseboard_fab2(sch_1):page122_i63:rsvd(58)" )
			)
			( pin "U7C1.AT27"
				( objectStatus "@baseboard_fab2_lib.baseboard_fab2(sch_1):page122_i63:rsvd(59)" )
			)
			( pin "U7C1.W50"
				( objectStatus "@baseboard_fab2_lib.baseboard_fab2(sch_1):page122_i63:vcca_clkfilt_1p05(0)" )
			)
			( pin "U7C1.AG45"
				( objectStatus "@baseboard_fab2_lib.baseboard_fab2(sch_1):page122_i63:vcca_clkfilt_1p05(1)" )
			)
			( pin "U7C1.AJ46"
				( objectStatus "@baseboard_fab2_lib.baseboard_fab2(sch_1):page122_i63:vcca_clkfilt_1p05(2)" )
			)
			( pin "U7C1.AJ48"
				( objectStatus "@baseboard_fab2_lib.baseboard_fab2(sch_1):page122_i63:vcca_clkfilt_1p05(3)" )
			)
			( pin "U7C1.AE46"
				( objectStatus "@baseboard_fab2_lib.baseboard_fab2(sch_1):page122_i63:vcca_clkfilt_1p05(4)" )
			)
			( pin "U7C1.AH50"
				( objectStatus "@baseboard_fab2_lib.baseboard_fab2(sch_1):page122_i63:vcca_clkunf_1p05(0)" )
			)
			( pin "U7C1.U50"
				( objectStatus "@baseboard_fab2_lib.baseboard_fab2(sch_1):page122_i63:vcca_clkunf_1p05(1)" )
			)
			( pin "U7C1.AD50"
				( objectStatus "@baseboard_fab2_lib.baseboard_fab2(sch_1):page122_i63:vcca_clkxtal_1p05" )
			)
			( pin "U7C1.AG48"
				( objectStatus "@baseboard_fab2_lib.baseboard_fab2(sch_1):page122_i63:vcca_pll0_1p05" )
			)
			( pin "U7C1.AE45"
				( objectStatus "@baseboard_fab2_lib.baseboard_fab2(sch_1):page122_i63:vcca_pll1_1p05" )
			)
			( pin "U7C1.AW45"
				( objectStatus "@baseboard_fab2_lib.baseboard_fab2(sch_1):page122_i63:vccmphy_1p05(0)" )
			)
			( pin "U7C1.AW43"
				( objectStatus "@baseboard_fab2_lib.baseboard_fab2(sch_1):page122_i63:vccmphy_1p05(1)" )
			)
			( pin "U7C1.AJ43"
				( objectStatus "@baseboard_fab2_lib.baseboard_fab2(sch_1):page122_i63:vccmphy_1p05(2)" )
			)
			( pin "U7C1.AU45"
				( objectStatus "@baseboard_fab2_lib.baseboard_fab2(sch_1):page122_i63:vccmphy_1p05(3)" )
			)
			( pin "U7C1.AU43"
				( objectStatus "@baseboard_fab2_lib.baseboard_fab2(sch_1):page122_i63:vccmphy_1p05(4)" )
			)
			( pin "U7C1.AT45"
				( objectStatus "@baseboard_fab2_lib.baseboard_fab2(sch_1):page122_i63:vccmphy_1p05(5)" )
			)
			( pin "U7C1.AT43"
				( objectStatus "@baseboard_fab2_lib.baseboard_fab2(sch_1):page122_i63:vccmphy_1p05(6)" )
			)
			( pin "U7C1.AP45"
				( objectStatus "@baseboard_fab2_lib.baseboard_fab2(sch_1):page122_i63:vccmphy_1p05(7)" )
			)
			( pin "U7C1.AP43"
				( objectStatus "@baseboard_fab2_lib.baseboard_fab2(sch_1):page122_i63:vccmphy_1p05(8)" )
			)
			( pin "U7C1.AM45"
				( objectStatus "@baseboard_fab2_lib.baseboard_fab2(sch_1):page122_i63:vccmphy_1p05(9)" )
			)
			( pin "U7C1.AM43"
				( objectStatus "@baseboard_fab2_lib.baseboard_fab2(sch_1):page122_i63:vccmphy_1p05(10)" )
			)
			( pin "U7C1.AK45"
				( objectStatus "@baseboard_fab2_lib.baseboard_fab2(sch_1):page122_i63:vccmphy_1p05(11)" )
			)
			( pin "U7C1.AK43"
				( objectStatus "@baseboard_fab2_lib.baseboard_fab2(sch_1):page122_i63:vccmphy_1p05(12)" )
			)
			( pin "U7C1.BA29"
				( objectStatus "@baseboard_fab2_lib.baseboard_fab2(sch_1):page122_i63:vccp10gbe_hv_1p8(0)" )
			)
			( pin "U7C1.BA27"
				( objectStatus "@baseboard_fab2_lib.baseboard_fab2(sch_1):page122_i63:vccp10gbe_hv_1p8(1)" )
			)
			( pin "U7C1.BB37"
				( objectStatus "@baseboard_fab2_lib.baseboard_fab2(sch_1):page122_i63:vccp10gbe_lv_1p05(0)" )
			)
			( pin "U7C1.BB33"
				( objectStatus "@baseboard_fab2_lib.baseboard_fab2(sch_1):page122_i63:vccp10gbe_lv_1p05(1)" )
			)
			( pin "U7C1.BA37"
				( objectStatus "@baseboard_fab2_lib.baseboard_fab2(sch_1):page122_i63:vccp10gbe_lv_1p05(2)" )
			)
			( pin "U7C1.BA36"
				( objectStatus "@baseboard_fab2_lib.baseboard_fab2(sch_1):page122_i63:vccp10gbe_lv_1p05(3)" )
			)
			( pin "U7C1.BA34"
				( objectStatus "@baseboard_fab2_lib.baseboard_fab2(sch_1):page122_i63:vccp10gbe_lv_1p05(4)" )
			)
			( pin "U7C1.BA32"
				( objectStatus "@baseboard_fab2_lib.baseboard_fab2(sch_1):page122_i63:vccp10gbe_lv_1p05(5)" )
			)
			( pin "U7C1.BA30"
				( objectStatus "@baseboard_fab2_lib.baseboard_fab2(sch_1):page122_i63:vccp10gbe_lv_1p05(6)" )
			)
			( pin "U7C1.BD38"
				( objectStatus "@baseboard_fab2_lib.baseboard_fab2(sch_1):page122_i63:vccp10gbepll_1p05(0)" )
			)
			( pin "U7C1.BB40"
				( objectStatus "@baseboard_fab2_lib.baseboard_fab2(sch_1):page122_i63:vccp10gbepll_1p05(1)" )
			)
			( pin "U7C1.BA41"
				( objectStatus "@baseboard_fab2_lib.baseboard_fab2(sch_1):page122_i63:vccp10gbepll_1p05(2)" )
			)
			( pin "U7C1.BA39"
				( objectStatus "@baseboard_fab2_lib.baseboard_fab2(sch_1):page122_i63:vccp10gbepll_1p05(3)" )
			)
			( pin "U7C1.BD46"
				( objectStatus "@baseboard_fab2_lib.baseboard_fab2(sch_1):page122_i63:vccp_1p8(0)" )
			)
			( pin "U7C1.AE26"
				( objectStatus "@baseboard_fab2_lib.baseboard_fab2(sch_1):page122_i63:vccp_1p8(1)" )
			)
			( pin "U7C1.BA46"
				( objectStatus "@baseboard_fab2_lib.baseboard_fab2(sch_1):page122_i63:vccp_3p3(0)" )
			)
			( pin "U7C1.BA45"
				( objectStatus "@baseboard_fab2_lib.baseboard_fab2(sch_1):page122_i63:vccp_3p3(1)" )
			)
			( pin "U7C1.AD24"
				( objectStatus "@baseboard_fab2_lib.baseboard_fab2(sch_1):page122_i63:vccp_3p3(2)" )
			)
			( pin "U7C1.AN24"
				( objectStatus "@baseboard_fab2_lib.baseboard_fab2(sch_1):page122_i63:vccp_3p3(5)" )
			)
			( pin "U7C1.AW48"
				( objectStatus "@baseboard_fab2_lib.baseboard_fab2(sch_1):page122_i63:vccp_hsiopll_1p05(0)" )
			)
			( pin "U7C1.AU48"
				( objectStatus "@baseboard_fab2_lib.baseboard_fab2(sch_1):page122_i63:vccp_hsiopll_1p05(2)" )
			)
			( pin "U7C1.AP48"
				( objectStatus "@baseboard_fab2_lib.baseboard_fab2(sch_1):page122_i63:vccp_hsiopll_1p05(3)" )
			)
			( pin "U7C1.AT48"
				( objectStatus "@baseboard_fab2_lib.baseboard_fab2(sch_1):page122_i63:vccp_hsiopllunf_1p05" )
			)
			( pin "U7C1.AN50"
				( objectStatus "@baseboard_fab2_lib.baseboard_fab2(sch_1):page122_i63:vccp_uppll_1p05(0)" )
			)
			( pin "U7C1.AK50"
				( objectStatus "@baseboard_fab2_lib.baseboard_fab2(sch_1):page122_i63:vccp_uppll_1p05(2)" )
			)
			( pin "U7C1.AM48"
				( objectStatus "@baseboard_fab2_lib.baseboard_fab2(sch_1):page122_i63:vccp_uppllunf_1p05" )
			)
			( pin "U7C1.AH24"
				( objectStatus "@baseboard_fab2_lib.baseboard_fab2(sch_1):page122_i63:vccpdsw_3p3" )
			)
			( pin "U7C1.AU29"
				( objectStatus "@baseboard_fab2_lib.baseboard_fab2(sch_1):page122_i63:vccpgpp_1p8(0)" )
			)
			( pin "U7C1.AW29"
				( objectStatus "@baseboard_fab2_lib.baseboard_fab2(sch_1):page122_i63:vccpgpp_1p8(1)" )
			)
			( pin "U7C1.AT29"
				( objectStatus "@baseboard_fab2_lib.baseboard_fab2(sch_1):page122_i63:vccpgpp_1p8(2)" )
			)
			( pin "U7C1.AM29"
				( objectStatus "@baseboard_fab2_lib.baseboard_fab2(sch_1):page122_i63:vccpgpp_1p8(3)" )
			)
			( pin "U7C1.AP29"
				( objectStatus "@baseboard_fab2_lib.baseboard_fab2(sch_1):page122_i63:vccpgpp_1p8(4)" )
			)
			( pin "U7C1.AW27"
				( objectStatus "@baseboard_fab2_lib.baseboard_fab2(sch_1):page122_i63:vccpgpp_1p8(5)" )
			)
			( pin "U7C1.AK24"
				( objectStatus "@baseboard_fab2_lib.baseboard_fab2(sch_1):page122_i63:vccpgpp_1p8(6)" )
			)
			( pin "U7C1.AW24"
				( objectStatus "@baseboard_fab2_lib.baseboard_fab2(sch_1):page122_i63:vccpgppa" )
			)
			( pin "U7C1.BE26"
				( objectStatus "@baseboard_fab2_lib.baseboard_fab2(sch_1):page122_i63:vccpgppb" )
			)
			( pin "U7C1.BE40"
				( objectStatus "@baseboard_fab2_lib.baseboard_fab2(sch_1):page122_i63:vccpgppc" )
			)
			( pin "U7C1.BA43"
				( objectStatus "@baseboard_fab2_lib.baseboard_fab2(sch_1):page122_i63:vccpgppd" )
			)
			( pin "U7C1.BE44"
				( objectStatus "@baseboard_fab2_lib.baseboard_fab2(sch_1):page122_i63:vccpgppe" )
			)
			( pin "U7C1.AU27"
				( objectStatus "@baseboard_fab2_lib.baseboard_fab2(sch_1):page122_i63:vccpgppf" )
			)
			( pin "U7C1.BA26"
				( objectStatus "@baseboard_fab2_lib.baseboard_fab2(sch_1):page122_i63:vccpgppg" )
			)
			( pin "U7C1.BA24"
				( objectStatus "@baseboard_fab2_lib.baseboard_fab2(sch_1):page122_i63:vccpgpph" )
			)
			( pin "U7C1.BB26"
				( objectStatus "@baseboard_fab2_lib.baseboard_fab2(sch_1):page122_i63:vccpgppj" )
			)
			( pin "U7C1.AU24"
				( objectStatus "@baseboard_fab2_lib.baseboard_fab2(sch_1):page122_i63:vccpgppk" )
			)
			( pin "U7C1.AG27"
				( objectStatus "@baseboard_fab2_lib.baseboard_fab2(sch_1):page122_i63:vccphda_1p8" )
			)
			( pin "U7C1.BF46"
				( objectStatus "@baseboard_fab2_lib.baseboard_fab2(sch_1):page122_i63:vccprim_1p05(0)" )
			)
			( pin "U7C1.BE48"
				( objectStatus "@baseboard_fab2_lib.baseboard_fab2(sch_1):page122_i63:vccprim_1p05(1)" )
			)
			( pin "U7C1.AU39"
				( objectStatus "@baseboard_fab2_lib.baseboard_fab2(sch_1):page122_i63:vccprim_1p05(2)" )
			)
			( pin "U7C1.AU37"
				( objectStatus "@baseboard_fab2_lib.baseboard_fab2(sch_1):page122_i63:vccprim_1p05(3)" )
			)
			( pin "U7C1.AT39"
				( objectStatus "@baseboard_fab2_lib.baseboard_fab2(sch_1):page122_i63:vccprim_1p05(4)" )
			)
			( pin "U7C1.AM27"
				( objectStatus "@baseboard_fab2_lib.baseboard_fab2(sch_1):page122_i63:vccprim_1p05(5)" )
			)
			( pin "U7C1.AJ29"
				( objectStatus "@baseboard_fab2_lib.baseboard_fab2(sch_1):page122_i63:vccprim_1p05(6)" )
			)
			( pin "U7C1.AC26"
				( objectStatus "@baseboard_fab2_lib.baseboard_fab2(sch_1):page122_i63:vccprim_1p05(7)" )
			)
			( pin "U7C1.AA46"
				( objectStatus "@baseboard_fab2_lib.baseboard_fab2(sch_1):page122_i63:vccprim_1p05(8)" )
			)
			( pin "U7C1.AA45"
				( objectStatus "@baseboard_fab2_lib.baseboard_fab2(sch_1):page122_i63:vccprim_1p05(9)" )
			)
			( pin "U7C1.Y46"
				( objectStatus "@baseboard_fab2_lib.baseboard_fab2(sch_1):page122_i63:vccprim_1p05(10)" )
			)
			( pin "U7C1.Y45"
				( objectStatus "@baseboard_fab2_lib.baseboard_fab2(sch_1):page122_i63:vccprim_1p05(11)" )
			)
			( pin "U7C1.V44"
				( objectStatus "@baseboard_fab2_lib.baseboard_fab2(sch_1):page122_i63:vccprim_1p05(12)" )
			)
			( pin "U7C1.U46"
				( objectStatus "@baseboard_fab2_lib.baseboard_fab2(sch_1):page122_i63:vccprim_1p05(13)" )
			)
			( pin "U7C1.T44"
				( objectStatus "@baseboard_fab2_lib.baseboard_fab2(sch_1):page122_i63:vccprim_1p05(14)" )
			)
			( pin "U7C1.R46"
				( objectStatus "@baseboard_fab2_lib.baseboard_fab2(sch_1):page122_i63:vccprim_1p05(15)" )
			)
			( pin "U7C1.R42"
				( objectStatus "@baseboard_fab2_lib.baseboard_fab2(sch_1):page122_i63:vccprim_1p05(16)" )
			)
			( pin "U7C1.AK27"
				( objectStatus "@baseboard_fab2_lib.baseboard_fab2(sch_1):page122_i63:vccprim_1p05(17)" )
			)
			( pin "U7C1.AA24"
				( objectStatus "@baseboard_fab2_lib.baseboard_fab2(sch_1):page122_i63:vccprim_1p05(18)" )
			)
			( pin "U7C1.Y26"
				( objectStatus "@baseboard_fab2_lib.baseboard_fab2(sch_1):page122_i63:vccprim_1p05(19)" )
			)
			( pin "U7C1.AJ27"
				( objectStatus "@baseboard_fab2_lib.baseboard_fab2(sch_1):page122_i63:vccprtc" )
			)
			( pin "U7C1.AG29"
				( objectStatus "@baseboard_fab2_lib.baseboard_fab2(sch_1):page122_i63:vccprtcprim_3p3" )
			)
			( pin "U7C1.AR24"
				( objectStatus "@baseboard_fab2_lib.baseboard_fab2(sch_1):page122_i63:vccpspi" )
			)
			( pin "U7C1.AK29"
				( objectStatus "@baseboard_fab2_lib.baseboard_fab2(sch_1):page122_i63:vccpspi_1p8" )
			)
			( pin "U7C1.BA48"
				( objectStatus "@baseboard_fab2_lib.baseboard_fab2(sch_1):page122_i63:vccpusbdsw_3p3" )
			)
			( pin "U7C1.AG22"
				( objectStatus "@baseboard_fab2_lib.baseboard_fab2(sch_1):page122_i63:vccrtcext" )
			)
			( pin "U7C1.N31"
				( objectStatus "@baseboard_fab2_lib.baseboard_fab2(sch_1):page123_i13:vss(355)" )
			)
			( pin "U7C1.N27"
				( objectStatus "@baseboard_fab2_lib.baseboard_fab2(sch_1):page123_i13:vss(356)" )
			)
			( pin "U7C1.N24"
				( objectStatus "@baseboard_fab2_lib.baseboard_fab2(sch_1):page123_i13:vss(357)" )
			)
			( pin "U7C1.N20"
				( objectStatus "@baseboard_fab2_lib.baseboard_fab2(sch_1):page123_i13:vss(358)" )
			)
			( pin "U7C1.N17"
				( objectStatus "@baseboard_fab2_lib.baseboard_fab2(sch_1):page123_i13:vss(359)" )
			)
			( pin "U7C1.N13"
				( objectStatus "@baseboard_fab2_lib.baseboard_fab2(sch_1):page123_i13:vss(360)" )
			)
			( pin "U7C1.M48"
				( objectStatus "@baseboard_fab2_lib.baseboard_fab2(sch_1):page123_i13:vss(361)" )
			)
			( pin "U7C1.M44"
				( objectStatus "@baseboard_fab2_lib.baseboard_fab2(sch_1):page123_i13:vss(362)" )
			)
			( pin "U7C1.N50"
				( objectStatus "@baseboard_fab2_lib.baseboard_fab2(sch_1):page123_i13:vss(363)" )
			)
			( pin "U7C1.N42"
				( objectStatus "@baseboard_fab2_lib.baseboard_fab2(sch_1):page123_i13:vss(364)" )
			)
			( pin "U7C1.M40"
				( objectStatus "@baseboard_fab2_lib.baseboard_fab2(sch_1):page123_i13:vss(365)" )
			)
			( pin "U7C1.M4"
				( objectStatus "@baseboard_fab2_lib.baseboard_fab2(sch_1):page123_i13:vss(366)" )
			)
			( pin "U7C1.M37"
				( objectStatus "@baseboard_fab2_lib.baseboard_fab2(sch_1):page123_i13:vss(367)" )
			)
			( pin "U7C1.M33"
				( objectStatus "@baseboard_fab2_lib.baseboard_fab2(sch_1):page123_i13:vss(368)" )
			)
			( pin "U7C1.M29"
				( objectStatus "@baseboard_fab2_lib.baseboard_fab2(sch_1):page123_i13:vss(369)" )
			)
			( pin "U7C1.M26"
				( objectStatus "@baseboard_fab2_lib.baseboard_fab2(sch_1):page123_i13:vss(370)" )
			)
			( pin "U7C1.M22"
				( objectStatus "@baseboard_fab2_lib.baseboard_fab2(sch_1):page123_i13:vss(371)" )
			)
			( pin "U7C1.M2"
				( objectStatus "@baseboard_fab2_lib.baseboard_fab2(sch_1):page123_i13:vss(372)" )
			)
			( pin "U7C1.L68"
				( objectStatus "@baseboard_fab2_lib.baseboard_fab2(sch_1):page123_i13:vss(373)" )
			)
			( pin "U7C1.L5"
				( objectStatus "@baseboard_fab2_lib.baseboard_fab2(sch_1):page123_i13:vss(374)" )
			)
			( pin "U7C1.K71"
				( objectStatus "@baseboard_fab2_lib.baseboard_fab2(sch_1):page123_i13:vss(375)" )
			)
			( pin "U7C1.K69"
				( objectStatus "@baseboard_fab2_lib.baseboard_fab2(sch_1):page123_i13:vss(376)" )
			)
			( pin "U7C1.K54"
				( objectStatus "@baseboard_fab2_lib.baseboard_fab2(sch_1):page123_i13:vss(377)" )
			)
			( pin "U7C1.J70"
				( objectStatus "@baseboard_fab2_lib.baseboard_fab2(sch_1):page123_i13:vss(378)" )
			)
			( pin "U7C1.J68"
				( objectStatus "@baseboard_fab2_lib.baseboard_fab2(sch_1):page123_i13:vss(379)" )
			)
			( pin "U7C1.J59"
				( objectStatus "@baseboard_fab2_lib.baseboard_fab2(sch_1):page123_i13:vss(380)" )
			)
			( pin "U7C1.J44"
				( objectStatus "@baseboard_fab2_lib.baseboard_fab2(sch_1):page123_i13:vss(381)" )
			)
			( pin "U7C1.J37"
				( objectStatus "@baseboard_fab2_lib.baseboard_fab2(sch_1):page123_i13:vss(382)" )
			)
			( pin "U7C1.J22"
				( objectStatus "@baseboard_fab2_lib.baseboard_fab2(sch_1):page123_i13:vss(383)" )
			)
			( pin "U7C1.J15"
				( objectStatus "@baseboard_fab2_lib.baseboard_fab2(sch_1):page123_i13:vss(384)" )
			)
			( pin "U7C1.J11"
				( objectStatus "@baseboard_fab2_lib.baseboard_fab2(sch_1):page123_i13:vss(385)" )
			)
			( pin "U7C1.H65"
				( objectStatus "@baseboard_fab2_lib.baseboard_fab2(sch_1):page123_i13:vss(386)" )
			)
			( pin "U7C1.J7"
				( objectStatus "@baseboard_fab2_lib.baseboard_fab2(sch_1):page123_i13:vss(387)" )
			)
			( pin "U7C1.J5"
				( objectStatus "@baseboard_fab2_lib.baseboard_fab2(sch_1):page123_i13:vss(388)" )
			)
			( pin "U7C1.J29"
				( objectStatus "@baseboard_fab2_lib.baseboard_fab2(sch_1):page123_i13:vss(389)" )
			)
			( pin "U7C1.H58"
				( objectStatus "@baseboard_fab2_lib.baseboard_fab2(sch_1):page123_i13:vss(390)" )
			)
			( pin "U7C1.G66"
				( objectStatus "@baseboard_fab2_lib.baseboard_fab2(sch_1):page123_i13:vss(391)" )
			)
			( pin "U7C1.G63"
				( objectStatus "@baseboard_fab2_lib.baseboard_fab2(sch_1):page123_i13:vss(392)" )
			)
			( pin "U7C1.G6"
				( objectStatus "@baseboard_fab2_lib.baseboard_fab2(sch_1):page123_i13:vss(393)" )
			)
			( pin "U7C1.G48"
				( objectStatus "@baseboard_fab2_lib.baseboard_fab2(sch_1):page123_i13:vss(394)" )
			)
			( pin "U7C1.G37"
				( objectStatus "@baseboard_fab2_lib.baseboard_fab2(sch_1):page123_i13:vss(395)" )
			)
			( pin "U7C1.G29"
				( objectStatus "@baseboard_fab2_lib.baseboard_fab2(sch_1):page123_i13:vss(396)" )
			)
			( pin "U7C1.G22"
				( objectStatus "@baseboard_fab2_lib.baseboard_fab2(sch_1):page123_i13:vss(397)" )
			)
			( pin "U7C1.E9"
				( objectStatus "@baseboard_fab2_lib.baseboard_fab2(sch_1):page123_i13:vss(398)" )
			)
			( pin "U7C1.G59"
				( objectStatus "@baseboard_fab2_lib.baseboard_fab2(sch_1):page123_i13:vss(399)" )
			)
			( pin "U7C1.E63"
				( objectStatus "@baseboard_fab2_lib.baseboard_fab2(sch_1):page123_i13:vss(400)" )
			)
			( pin "U7C1.E61"
				( objectStatus "@baseboard_fab2_lib.baseboard_fab2(sch_1):page123_i13:vss(401)" )
			)
			( pin "U7C1.E6"
				( objectStatus "@baseboard_fab2_lib.baseboard_fab2(sch_1):page123_i13:vss(402)" )
			)
			( pin "U7C1.E57"
				( objectStatus "@baseboard_fab2_lib.baseboard_fab2(sch_1):page123_i13:vss(403)" )
			)
			( pin "U7C1.E54"
				( objectStatus "@baseboard_fab2_lib.baseboard_fab2(sch_1):page123_i13:vss(404)" )
			)
			( pin "U7C1.E52"
				( objectStatus "@baseboard_fab2_lib.baseboard_fab2(sch_1):page123_i13:vss(405)" )
			)
			( pin "U7C1.E50"
				( objectStatus "@baseboard_fab2_lib.baseboard_fab2(sch_1):page123_i13:vss(406)" )
			)
			( pin "U7C1.E48"
				( objectStatus "@baseboard_fab2_lib.baseboard_fab2(sch_1):page123_i13:vss(407)" )
			)
			( pin "U7C1.E45"
				( objectStatus "@baseboard_fab2_lib.baseboard_fab2(sch_1):page123_i13:vss(408)" )
			)
			( pin "U7C1.E43"
				( objectStatus "@baseboard_fab2_lib.baseboard_fab2(sch_1):page123_i13:vss(409)" )
			)
			( pin "U7C1.E41"
				( objectStatus "@baseboard_fab2_lib.baseboard_fab2(sch_1):page123_i13:vss(410)" )
			)
			( pin "U7C1.E39"
				( objectStatus "@baseboard_fab2_lib.baseboard_fab2(sch_1):page123_i13:vss(411)" )
			)
			( pin "U7C1.E37"
				( objectStatus "@baseboard_fab2_lib.baseboard_fab2(sch_1):page123_i13:vss(412)" )
			)
			( pin "U7C1.E34"
				( objectStatus "@baseboard_fab2_lib.baseboard_fab2(sch_1):page123_i13:vss(413)" )
			)
			( pin "U7C1.E32"
				( objectStatus "@baseboard_fab2_lib.baseboard_fab2(sch_1):page123_i13:vss(414)" )
			)
			( pin "U7C1.E30"
				( objectStatus "@baseboard_fab2_lib.baseboard_fab2(sch_1):page123_i13:vss(415)" )
			)
			( pin "U7C1.E28"
				( objectStatus "@baseboard_fab2_lib.baseboard_fab2(sch_1):page123_i13:vss(416)" )
			)
			( pin "U7C1.E26"
				( objectStatus "@baseboard_fab2_lib.baseboard_fab2(sch_1):page123_i13:vss(417)" )
			)
			( pin "U7C1.E24"
				( objectStatus "@baseboard_fab2_lib.baseboard_fab2(sch_1):page123_i13:vss(418)" )
			)
			( pin "U7C1.E22"
				( objectStatus "@baseboard_fab2_lib.baseboard_fab2(sch_1):page123_i13:vss(419)" )
			)
			( pin "U7C1.E20"
				( objectStatus "@baseboard_fab2_lib.baseboard_fab2(sch_1):page123_i13:vss(420)" )
			)
			( pin "U7C1.E15"
				( objectStatus "@baseboard_fab2_lib.baseboard_fab2(sch_1):page123_i13:vss(421)" )
			)
			( pin "U7C1.E13"
				( objectStatus "@baseboard_fab2_lib.baseboard_fab2(sch_1):page123_i13:vss(422)" )
			)
			( pin "U7C1.E11"
				( objectStatus "@baseboard_fab2_lib.baseboard_fab2(sch_1):page123_i13:vss(423)" )
			)
			( pin "U7C1.D47"
				( objectStatus "@baseboard_fab2_lib.baseboard_fab2(sch_1):page123_i13:vss(424)" )
			)
			( pin "U7C1.E65"
				( objectStatus "@baseboard_fab2_lib.baseboard_fab2(sch_1):page123_i13:vss(425)" )
			)
			( pin "U7C1.E59"
				( objectStatus "@baseboard_fab2_lib.baseboard_fab2(sch_1):page123_i13:vss(426)" )
			)
			( pin "U7C1.D27"
				( objectStatus "@baseboard_fab2_lib.baseboard_fab2(sch_1):page123_i13:vss(427)" )
			)
			( pin "U7C1.D25"
				( objectStatus "@baseboard_fab2_lib.baseboard_fab2(sch_1):page123_i13:vss(428)" )
			)
			( pin "U7C1.D19"
				( objectStatus "@baseboard_fab2_lib.baseboard_fab2(sch_1):page123_i13:vss(429)" )
			)
			( pin "U7C1.D16"
				( objectStatus "@baseboard_fab2_lib.baseboard_fab2(sch_1):page123_i13:vss(430)" )
			)
			( pin "U7C1.D12"
				( objectStatus "@baseboard_fab2_lib.baseboard_fab2(sch_1):page123_i13:vss(431)" )
			)
			( pin "U7C1.C65"
				( objectStatus "@baseboard_fab2_lib.baseboard_fab2(sch_1):page123_i13:vss(432)" )
			)
			( pin "U7C1.C41"
				( objectStatus "@baseboard_fab2_lib.baseboard_fab2(sch_1):page123_i13:vss(433)" )
			)
			( pin "U7C1.C37"
				( objectStatus "@baseboard_fab2_lib.baseboard_fab2(sch_1):page123_i13:vss(434)" )
			)
			( pin "U7C1.C34"
				( objectStatus "@baseboard_fab2_lib.baseboard_fab2(sch_1):page123_i13:vss(435)" )
			)
			( pin "U7C1.C30"
				( objectStatus "@baseboard_fab2_lib.baseboard_fab2(sch_1):page123_i13:vss(436)" )
			)
			( pin "U7C1.C22"
				( objectStatus "@baseboard_fab2_lib.baseboard_fab2(sch_1):page123_i13:vss(437)" )
			)
			( pin "U7C1.B47"
				( objectStatus "@baseboard_fab2_lib.baseboard_fab2(sch_1):page123_i13:vss(438)" )
			)
			( pin "U7C1.B27"
				( objectStatus "@baseboard_fab2_lib.baseboard_fab2(sch_1):page123_i13:vss(439)" )
			)
			( pin "U7C1.B25"
				( objectStatus "@baseboard_fab2_lib.baseboard_fab2(sch_1):page123_i13:vss(440)" )
			)
			( pin "U7C1.B19"
				( objectStatus "@baseboard_fab2_lib.baseboard_fab2(sch_1):page123_i13:vss(441)" )
			)
			( pin "U7C1.B12"
				( objectStatus "@baseboard_fab2_lib.baseboard_fab2(sch_1):page123_i13:vss(442)" )
			)
			( pin "U7C1.A41"
				( objectStatus "@baseboard_fab2_lib.baseboard_fab2(sch_1):page123_i13:vss(443)" )
			)
			( pin "U7C1.A37"
				( objectStatus "@baseboard_fab2_lib.baseboard_fab2(sch_1):page123_i13:vss(444)" )
			)
			( pin "U7C1.A34"
				( objectStatus "@baseboard_fab2_lib.baseboard_fab2(sch_1):page123_i13:vss(445)" )
			)
			( pin "U7C1.A30"
				( objectStatus "@baseboard_fab2_lib.baseboard_fab2(sch_1):page123_i13:vss(446)" )
			)
			( pin "U7C1.A22"
				( objectStatus "@baseboard_fab2_lib.baseboard_fab2(sch_1):page123_i13:vss(447)" )
			)
			( pin "U7C1.A18"
				( objectStatus "@baseboard_fab2_lib.baseboard_fab2(sch_1):page123_i13:vss(448)" )
			)
			( pin "U7C1.Y70"
				( objectStatus "@baseboard_fab2_lib.baseboard_fab2(sch_1):page123_i13:vss(449)" )
			)
			( pin "U7C1.Y72"
				( objectStatus "@baseboard_fab2_lib.baseboard_fab2(sch_1):page123_i13:vss(450)" )
			)
			( pin "U7C1.AT37"
				( objectStatus "@baseboard_fab2_lib.baseboard_fab2(sch_1):page123_i13:vss(451)" )
			)
			( pin "U7C1.BB48"
				( objectStatus "@baseboard_fab2_lib.baseboard_fab2(sch_1):page123_i13:vss(452)" )
			)
			( pin "U7C1.CA70"
				( objectStatus "@baseboard_fab2_lib.baseboard_fab2(sch_1):page123_i13:vss(453)" )
			)
			( pin "U7C1.BW72"
				( objectStatus "@baseboard_fab2_lib.baseboard_fab2(sch_1):page123_i13:vss(454)" )
			)
			( pin "U7C1.BW70"
				( objectStatus "@baseboard_fab2_lib.baseboard_fab2(sch_1):page123_i13:vss(455)" )
			)
			( pin "U7C1.BU72"
				( objectStatus "@baseboard_fab2_lib.baseboard_fab2(sch_1):page123_i13:vss(456)" )
			)
			( pin "U7C1.BR72"
				( objectStatus "@baseboard_fab2_lib.baseboard_fab2(sch_1):page123_i13:vss(457)" )
			)
			( pin "U7C1.G72"
				( objectStatus "@baseboard_fab2_lib.baseboard_fab2(sch_1):page123_i13:vss(458)" )
			)
			( pin "U7C1.G1"
				( objectStatus "@baseboard_fab2_lib.baseboard_fab2(sch_1):page123_i13:vss(459)" )
			)
			( pin "U7C1.E72"
				( objectStatus "@baseboard_fab2_lib.baseboard_fab2(sch_1):page123_i13:vss(460)" )
			)
			( pin "U7C1.E1"
				( objectStatus "@baseboard_fab2_lib.baseboard_fab2(sch_1):page123_i13:vss(461)" )
			)
			( pin "U7C1.C72"
				( objectStatus "@baseboard_fab2_lib.baseboard_fab2(sch_1):page123_i13:vss(462)" )
			)
			( pin "U7C1.C3"
				( objectStatus "@baseboard_fab2_lib.baseboard_fab2(sch_1):page123_i13:vss(463)" )
			)
			( pin "U7C1.BR1"
				( objectStatus "@baseboard_fab2_lib.baseboard_fab2(sch_1):page123_i13:vss(464)" )
			)
			( pin "U7C1.BU1"
				( objectStatus "@baseboard_fab2_lib.baseboard_fab2(sch_1):page123_i13:vss(465)" )
			)
			( pin "U7C1.BW1"
				( objectStatus "@baseboard_fab2_lib.baseboard_fab2(sch_1):page123_i13:vss(466)" )
			)
			( pin "U7C1.CA3"
				( objectStatus "@baseboard_fab2_lib.baseboard_fab2(sch_1):page123_i13:vss(467)" )
			)
			( pin "U7C1.A70"
				( objectStatus "@baseboard_fab2_lib.baseboard_fab2(sch_1):page123_i13:vss(468)" )
			)
			( pin "U7C1.CA5"
				( objectStatus "@baseboard_fab2_lib.baseboard_fab2(sch_1):page123_i13:vss(469)" )
			)
			( pin "U7C1.CA7"
				( objectStatus "@baseboard_fab2_lib.baseboard_fab2(sch_1):page123_i13:vss(470)" )
			)
			( pin "U7C1.CA9"
				( objectStatus "@baseboard_fab2_lib.baseboard_fab2(sch_1):page123_i13:vss(471)" )
			)
			( pin "U7C1.CA65"
				( objectStatus "@baseboard_fab2_lib.baseboard_fab2(sch_1):page123_i13:vss(472)" )
			)
			( pin "U7C1.CA66"
				( objectStatus "@baseboard_fab2_lib.baseboard_fab2(sch_1):page123_i13:vss(473)" )
			)
			( pin "U7C1.CA68"
				( objectStatus "@baseboard_fab2_lib.baseboard_fab2(sch_1):page123_i13:vss(474)" )
			)
			( pin "U7C1.BN72"
				( objectStatus "@baseboard_fab2_lib.baseboard_fab2(sch_1):page123_i13:vss(475)" )
			)
			( pin "U7C1.BN1"
				( objectStatus "@baseboard_fab2_lib.baseboard_fab2(sch_1):page123_i13:vss(476)" )
			)
			( pin "U7C1.J72"
				( objectStatus "@baseboard_fab2_lib.baseboard_fab2(sch_1):page123_i13:vss(477)" )
			)
			( pin "U7C1.J1"
				( objectStatus "@baseboard_fab2_lib.baseboard_fab2(sch_1):page123_i13:vss(478)" )
			)
			( pin "U7C1.A68"
				( objectStatus "@baseboard_fab2_lib.baseboard_fab2(sch_1):page123_i13:vss(479)" )
			)
			( pin "U7C1.A66"
				( objectStatus "@baseboard_fab2_lib.baseboard_fab2(sch_1):page123_i13:vss(480)" )
			)
			( pin "U7C1.A65"
				( objectStatus "@baseboard_fab2_lib.baseboard_fab2(sch_1):page123_i13:vss(481)" )
			)
			( pin "U7C1.A9"
				( objectStatus "@baseboard_fab2_lib.baseboard_fab2(sch_1):page123_i13:vss(482)" )
			)
			( pin "U7C1.A7"
				( objectStatus "@baseboard_fab2_lib.baseboard_fab2(sch_1):page123_i13:vss(483)" )
			)
			( pin "U7C1.A5"
				( objectStatus "@baseboard_fab2_lib.baseboard_fab2(sch_1):page123_i13:vss(484)" )
			)
			( pin "U7C1.E3"
				( objectStatus "@baseboard_fab2_lib.baseboard_fab2(sch_1):page123_i13:vss(485)" )
			)
			( pin "U7C1.F3"
				( objectStatus "@baseboard_fab2_lib.baseboard_fab2(sch_1):page123_i13:vss(486)" )
			)
			( pin "U7C1.BR3"
				( objectStatus "@baseboard_fab2_lib.baseboard_fab2(sch_1):page123_i13:vss(487)" )
			)
			( pin "U7C1.BU3"
				( objectStatus "@baseboard_fab2_lib.baseboard_fab2(sch_1):page123_i13:vss(488)" )
			)
			( pin "U7C1.E70"
				( objectStatus "@baseboard_fab2_lib.baseboard_fab2(sch_1):page123_i13:vss(489)" )
			)
			( pin "U7C1.F70"
				( objectStatus "@baseboard_fab2_lib.baseboard_fab2(sch_1):page123_i13:vss(490)" )
			)
			( pin "U7C1.BR70"
				( objectStatus "@baseboard_fab2_lib.baseboard_fab2(sch_1):page123_i13:vss(491)" )
			)
			( pin "U7C1.BU70"
				( objectStatus "@baseboard_fab2_lib.baseboard_fab2(sch_1):page123_i13:vss(492)" )
			)
			( pin "U7C1.BT69"
				( objectStatus "@baseboard_fab2_lib.baseboard_fab2(sch_1):page123_i13:vss(493)" )
			)
			( pin "U7C1.BP69"
				( objectStatus "@baseboard_fab2_lib.baseboard_fab2(sch_1):page123_i13:vss(494)" )
			)
			( pin "U7C1.AE27"
				( objectStatus "@baseboard_fab2_lib.baseboard_fab2(sch_1):page123_i21:vccmphy_1p05(13)" )
			)
			( pin "U7C1.AU36"
				( objectStatus "@baseboard_fab2_lib.baseboard_fab2(sch_1):page123_i21:vccprim_avid(0)" )
			)
			( pin "U7C1.AU34"
				( objectStatus "@baseboard_fab2_lib.baseboard_fab2(sch_1):page123_i21:vccprim_avid(1)" )
			)
			( pin "U7C1.AU32"
				( objectStatus "@baseboard_fab2_lib.baseboard_fab2(sch_1):page123_i21:vccprim_avid(2)" )
			)
			( pin "U7C1.AT36"
				( objectStatus "@baseboard_fab2_lib.baseboard_fab2(sch_1):page123_i21:vccprim_avid(3)" )
			)
			( pin "U7C1.AT34"
				( objectStatus "@baseboard_fab2_lib.baseboard_fab2(sch_1):page123_i21:vccprim_avid(4)" )
			)
			( pin "U7C1.AT32"
				( objectStatus "@baseboard_fab2_lib.baseboard_fab2(sch_1):page123_i21:vccprim_avid(5)" )
			)
			( pin "U7C1.AP39"
				( objectStatus "@baseboard_fab2_lib.baseboard_fab2(sch_1):page123_i21:vccprim_avid(6)" )
			)
			( pin "U7C1.AP37"
				( objectStatus "@baseboard_fab2_lib.baseboard_fab2(sch_1):page123_i21:vccprim_avid(7)" )
			)
			( pin "U7C1.AP36"
				( objectStatus "@baseboard_fab2_lib.baseboard_fab2(sch_1):page123_i21:vccprim_avid(8)" )
			)
			( pin "U7C1.AP34"
				( objectStatus "@baseboard_fab2_lib.baseboard_fab2(sch_1):page123_i21:vccprim_avid(9)" )
			)
			( pin "U7C1.AP32"
				( objectStatus "@baseboard_fab2_lib.baseboard_fab2(sch_1):page123_i21:vccprim_avid(10)" )
			)
			( pin "U7C1.AM39"
				( objectStatus "@baseboard_fab2_lib.baseboard_fab2(sch_1):page123_i21:vccprim_avid(11)" )
			)
			( pin "U7C1.AM37"
				( objectStatus "@baseboard_fab2_lib.baseboard_fab2(sch_1):page123_i21:vccprim_avid(12)" )
			)
			( pin "U7C1.AM36"
				( objectStatus "@baseboard_fab2_lib.baseboard_fab2(sch_1):page123_i21:vccprim_avid(13)" )
			)
			( pin "U7C1.AM34"
				( objectStatus "@baseboard_fab2_lib.baseboard_fab2(sch_1):page123_i21:vccprim_avid(14)" )
			)
			( pin "U7C1.AM32"
				( objectStatus "@baseboard_fab2_lib.baseboard_fab2(sch_1):page123_i21:vccprim_avid(15)" )
			)
			( pin "U7C1.AK39"
				( objectStatus "@baseboard_fab2_lib.baseboard_fab2(sch_1):page123_i21:vccprim_avid(16)" )
			)
			( pin "U7C1.AK37"
				( objectStatus "@baseboard_fab2_lib.baseboard_fab2(sch_1):page123_i21:vccprim_avid(17)" )
			)
			( pin "U7C1.AK34"
				( objectStatus "@baseboard_fab2_lib.baseboard_fab2(sch_1):page123_i21:vccprim_avid(18)" )
			)
			( pin "U7C1.AG39"
				( objectStatus "@baseboard_fab2_lib.baseboard_fab2(sch_1):page123_i21:vccprim_avid(19)" )
			)
			( pin "U7C1.AG37"
				( objectStatus "@baseboard_fab2_lib.baseboard_fab2(sch_1):page123_i21:vccprim_avid(20)" )
			)
			( pin "U7C1.AG36"
				( objectStatus "@baseboard_fab2_lib.baseboard_fab2(sch_1):page123_i21:vccprim_avid(21)" )
			)
			( pin "U7C1.AG34"
				( objectStatus "@baseboard_fab2_lib.baseboard_fab2(sch_1):page123_i21:vccprim_avid(22)" )
			)
			( pin "U7C1.AG32"
				( objectStatus "@baseboard_fab2_lib.baseboard_fab2(sch_1):page123_i21:vccprim_avid(23)" )
			)
			( pin "U7C1.AE41"
				( objectStatus "@baseboard_fab2_lib.baseboard_fab2(sch_1):page123_i21:vccprim_avid(24)" )
			)
			( pin "U7C1.AE39"
				( objectStatus "@baseboard_fab2_lib.baseboard_fab2(sch_1):page123_i21:vccprim_avid(25)" )
			)
			( pin "U7C1.AE37"
				( objectStatus "@baseboard_fab2_lib.baseboard_fab2(sch_1):page123_i21:vccprim_avid(26)" )
			)
			( pin "U7C1.AE36"
				( objectStatus "@baseboard_fab2_lib.baseboard_fab2(sch_1):page123_i21:vccprim_avid(27)" )
			)
			( pin "U7C1.AE34"
				( objectStatus "@baseboard_fab2_lib.baseboard_fab2(sch_1):page123_i21:vccprim_avid(28)" )
			)
			( pin "U7C1.AE32"
				( objectStatus "@baseboard_fab2_lib.baseboard_fab2(sch_1):page123_i21:vccprim_avid(29)" )
			)
			( pin "U7C1.AE30"
				( objectStatus "@baseboard_fab2_lib.baseboard_fab2(sch_1):page123_i21:vccprim_avid(30)" )
			)
			( pin "U7C1.U27"
				( objectStatus "@baseboard_fab2_lib.baseboard_fab2(sch_1):page123_i21:vccprim_avid(31)" )
			)
			( pin "U7C1.AC41"
				( objectStatus "@baseboard_fab2_lib.baseboard_fab2(sch_1):page123_i21:vccprim_avid(32)" )
			)
			( pin "U7C1.AC39"
				( objectStatus "@baseboard_fab2_lib.baseboard_fab2(sch_1):page123_i21:vccprim_avid(33)" )
			)
			( pin "U7C1.AC37"
				( objectStatus "@baseboard_fab2_lib.baseboard_fab2(sch_1):page123_i21:vccprim_avid(34)" )
			)
			( pin "U7C1.AC36"
				( objectStatus "@baseboard_fab2_lib.baseboard_fab2(sch_1):page123_i21:vccprim_avid(35)" )
			)
			( pin "U7C1.AC34"
				( objectStatus "@baseboard_fab2_lib.baseboard_fab2(sch_1):page123_i21:vccprim_avid(36)" )
			)
			( pin "U7C1.AC32"
				( objectStatus "@baseboard_fab2_lib.baseboard_fab2(sch_1):page123_i21:vccprim_avid(37)" )
			)
			( pin "U7C1.AC30"
				( objectStatus "@baseboard_fab2_lib.baseboard_fab2(sch_1):page123_i21:vccprim_avid(38)" )
			)
			( pin "U7C1.AC29"
				( objectStatus "@baseboard_fab2_lib.baseboard_fab2(sch_1):page123_i21:vccprim_avid(39)" )
			)
			( pin "U7C1.AA41"
				( objectStatus "@baseboard_fab2_lib.baseboard_fab2(sch_1):page123_i21:vccprim_avid(40)" )
			)
			( pin "U7C1.AA39"
				( objectStatus "@baseboard_fab2_lib.baseboard_fab2(sch_1):page123_i21:vccprim_avid(41)" )
			)
			( pin "U7C1.AA37"
				( objectStatus "@baseboard_fab2_lib.baseboard_fab2(sch_1):page123_i21:vccprim_avid(42)" )
			)
			( pin "U7C1.AA36"
				( objectStatus "@baseboard_fab2_lib.baseboard_fab2(sch_1):page123_i21:vccprim_avid(43)" )
			)
			( pin "U7C1.AA34"
				( objectStatus "@baseboard_fab2_lib.baseboard_fab2(sch_1):page123_i21:vccprim_avid(44)" )
			)
			( pin "U7C1.AA32"
				( objectStatus "@baseboard_fab2_lib.baseboard_fab2(sch_1):page123_i21:vccprim_avid(45)" )
			)
			( pin "U7C1.AA30"
				( objectStatus "@baseboard_fab2_lib.baseboard_fab2(sch_1):page123_i21:vccprim_avid(46)" )
			)
			( pin "U7C1.AA29"
				( objectStatus "@baseboard_fab2_lib.baseboard_fab2(sch_1):page123_i21:vccprim_avid(47)" )
			)
			( pin "U7C1.Y41"
				( objectStatus "@baseboard_fab2_lib.baseboard_fab2(sch_1):page123_i21:vccprim_avid(48)" )
			)
			( pin "U7C1.Y39"
				( objectStatus "@baseboard_fab2_lib.baseboard_fab2(sch_1):page123_i21:vccprim_avid(49)" )
			)
			( pin "U7C1.Y37"
				( objectStatus "@baseboard_fab2_lib.baseboard_fab2(sch_1):page123_i21:vccprim_avid(50)" )
			)
			( pin "U7C1.Y36"
				( objectStatus "@baseboard_fab2_lib.baseboard_fab2(sch_1):page123_i21:vccprim_avid(51)" )
			)
			( pin "U7C1.Y34"
				( objectStatus "@baseboard_fab2_lib.baseboard_fab2(sch_1):page123_i21:vccprim_avid(52)" )
			)
			( pin "U7C1.Y32"
				( objectStatus "@baseboard_fab2_lib.baseboard_fab2(sch_1):page123_i21:vccprim_avid(53)" )
			)
			( pin "U7C1.Y30"
				( objectStatus "@baseboard_fab2_lib.baseboard_fab2(sch_1):page123_i21:vccprim_avid(54)" )
			)
			( pin "U7C1.Y29"
				( objectStatus "@baseboard_fab2_lib.baseboard_fab2(sch_1):page123_i21:vccprim_avid(55)" )
			)
			( pin "U7C1.V40"
				( objectStatus "@baseboard_fab2_lib.baseboard_fab2(sch_1):page123_i21:vccprim_avid(56)" )
			)
			( pin "U7C1.V33"
				( objectStatus "@baseboard_fab2_lib.baseboard_fab2(sch_1):page123_i21:vccprim_avid(57)" )
			)
			( pin "U7C1.V29"
				( objectStatus "@baseboard_fab2_lib.baseboard_fab2(sch_1):page123_i21:vccprim_avid(58)" )
			)
			( pin "U7C1.U38"
				( objectStatus "@baseboard_fab2_lib.baseboard_fab2(sch_1):page123_i21:vccprim_avid(59)" )
			)
			( pin "U7C1.U35"
				( objectStatus "@baseboard_fab2_lib.baseboard_fab2(sch_1):page123_i21:vccprim_avid(60)" )
			)
			( pin "U7C1.U31"
				( objectStatus "@baseboard_fab2_lib.baseboard_fab2(sch_1):page123_i21:vccprim_avid(61)" )
			)
			( pin "U7C1.AK32"
				( objectStatus "@baseboard_fab2_lib.baseboard_fab2(sch_1):page123_i21:vccprim_avid(62)" )
			)
			( pin "U7C1.V37"
				( objectStatus "@baseboard_fab2_lib.baseboard_fab2(sch_1):page123_i21:vccprim_avid_qat_sense" )
			)
			( pin "U7C1.AK36"
				( objectStatus "@baseboard_fab2_lib.baseboard_fab2(sch_1):page123_i21:vccprim_avid_sense" )
			)
			( pin "U7C1.CA52"
				( objectStatus "@baseboard_fab2_lib.baseboard_fab2(sch_1):page124_i15:vss(0)" )
			)
			( pin "U7C1.CA50"
				( objectStatus "@baseboard_fab2_lib.baseboard_fab2(sch_1):page124_i15:vss(1)" )
			)
			( pin "U7C1.CA26"
				( objectStatus "@baseboard_fab2_lib.baseboard_fab2(sch_1):page124_i15:vss(2)" )
			)
			( pin "U7C1.CA18"
				( objectStatus "@baseboard_fab2_lib.baseboard_fab2(sch_1):page124_i15:vss(3)" )
			)
			( pin "U7C1.CA15"
				( objectStatus "@baseboard_fab2_lib.baseboard_fab2(sch_1):page124_i15:vss(4)" )
			)
			( pin "U7C1.BY49"
				( objectStatus "@baseboard_fab2_lib.baseboard_fab2(sch_1):page124_i15:vss(5)" )
			)
			( pin "U7C1.BY40"
				( objectStatus "@baseboard_fab2_lib.baseboard_fab2(sch_1):page124_i15:vss(6)" )
			)
			( pin "U7C1.BW52"
				( objectStatus "@baseboard_fab2_lib.baseboard_fab2(sch_1):page124_i15:vss(7)" )
			)
			( pin "U7C1.BW26"
				( objectStatus "@baseboard_fab2_lib.baseboard_fab2(sch_1):page124_i15:vss(8)" )
			)
			( pin "U7C1.BW18"
				( objectStatus "@baseboard_fab2_lib.baseboard_fab2(sch_1):page124_i15:vss(9)" )
			)
			( pin "U7C1.BW15"
				( objectStatus "@baseboard_fab2_lib.baseboard_fab2(sch_1):page124_i15:vss(10)" )
			)
			( pin "U7C1.BV40"
				( objectStatus "@baseboard_fab2_lib.baseboard_fab2(sch_1):page124_i15:vss(11)" )
			)
			( pin "U7C1.BU9"
				( objectStatus "@baseboard_fab2_lib.baseboard_fab2(sch_1):page124_i15:vss(12)" )
			)
			( pin "U7C1.BU63"
				( objectStatus "@baseboard_fab2_lib.baseboard_fab2(sch_1):page124_i15:vss(13)" )
			)
			( pin "U7C1.BU61"
				( objectStatus "@baseboard_fab2_lib.baseboard_fab2(sch_1):page124_i15:vss(14)" )
			)
			( pin "U7C1.BU59"
				( objectStatus "@baseboard_fab2_lib.baseboard_fab2(sch_1):page124_i15:vss(15)" )
			)
			( pin "U7C1.BU57"
				( objectStatus "@baseboard_fab2_lib.baseboard_fab2(sch_1):page124_i15:vss(16)" )
			)
			( pin "U7C1.BU54"
				( objectStatus "@baseboard_fab2_lib.baseboard_fab2(sch_1):page124_i15:vss(17)" )
			)
			( pin "U7C1.BU52"
				( objectStatus "@baseboard_fab2_lib.baseboard_fab2(sch_1):page124_i15:vss(18)" )
			)
			( pin "U7C1.BU50"
				( objectStatus "@baseboard_fab2_lib.baseboard_fab2(sch_1):page124_i15:vss(19)" )
			)
			( pin "U7C1.BU48"
				( objectStatus "@baseboard_fab2_lib.baseboard_fab2(sch_1):page124_i15:vss(20)" )
			)
			( pin "U7C1.BU45"
				( objectStatus "@baseboard_fab2_lib.baseboard_fab2(sch_1):page124_i15:vss(21)" )
			)
			( pin "U7C1.BU43"
				( objectStatus "@baseboard_fab2_lib.baseboard_fab2(sch_1):page124_i15:vss(22)" )
			)
			( pin "U7C1.BU41"
				( objectStatus "@baseboard_fab2_lib.baseboard_fab2(sch_1):page124_i15:vss(23)" )
			)
			( pin "U7C1.BU39"
				( objectStatus "@baseboard_fab2_lib.baseboard_fab2(sch_1):page124_i15:vss(24)" )
			)
			( pin "U7C1.BU37"
				( objectStatus "@baseboard_fab2_lib.baseboard_fab2(sch_1):page124_i15:vss(25)" )
			)
			( pin "U7C1.BU34"
				( objectStatus "@baseboard_fab2_lib.baseboard_fab2(sch_1):page124_i15:vss(26)" )
			)
			( pin "U7C1.BU32"
				( objectStatus "@baseboard_fab2_lib.baseboard_fab2(sch_1):page124_i15:vss(27)" )
			)
			( pin "U7C1.BU30"
				( objectStatus "@baseboard_fab2_lib.baseboard_fab2(sch_1):page124_i15:vss(28)" )
			)
			( pin "U7C1.BU28"
				( objectStatus "@baseboard_fab2_lib.baseboard_fab2(sch_1):page124_i15:vss(29)" )
			)
			( pin "U7C1.BU26"
				( objectStatus "@baseboard_fab2_lib.baseboard_fab2(sch_1):page124_i15:vss(30)" )
			)
			( pin "U7C1.BU24"
				( objectStatus "@baseboard_fab2_lib.baseboard_fab2(sch_1):page124_i15:vss(31)" )
			)
			( pin "U7C1.BU22"
				( objectStatus "@baseboard_fab2_lib.baseboard_fab2(sch_1):page124_i15:vss(32)" )
			)
			( pin "U7C1.BU20"
				( objectStatus "@baseboard_fab2_lib.baseboard_fab2(sch_1):page124_i15:vss(33)" )
			)
			( pin "U7C1.BU18"
				( objectStatus "@baseboard_fab2_lib.baseboard_fab2(sch_1):page124_i15:vss(34)" )
			)
			( pin "U7C1.BU15"
				( objectStatus "@baseboard_fab2_lib.baseboard_fab2(sch_1):page124_i15:vss(35)" )
			)
			( pin "U7C1.BV49"
				( objectStatus "@baseboard_fab2_lib.baseboard_fab2(sch_1):page124_i15:vss(36)" )
			)
			( pin "U7C1.BU11"
				( objectStatus "@baseboard_fab2_lib.baseboard_fab2(sch_1):page124_i15:vss(37)" )
			)
			( pin "U7C1.BU13"
				( objectStatus "@baseboard_fab2_lib.baseboard_fab2(sch_1):page124_i15:vss(38)" )
			)
			( pin "U7C1.BT66"
				( objectStatus "@baseboard_fab2_lib.baseboard_fab2(sch_1):page124_i15:vss(39)" )
			)
			( pin "U7C1.BR6"
				( objectStatus "@baseboard_fab2_lib.baseboard_fab2(sch_1):page124_i15:vss(40)" )
			)
			( pin "U7C1.BR58"
				( objectStatus "@baseboard_fab2_lib.baseboard_fab2(sch_1):page124_i15:vss(41)" )
			)
			( pin "U7C1.BR54"
				( objectStatus "@baseboard_fab2_lib.baseboard_fab2(sch_1):page124_i15:vss(42)" )
			)
			( pin "U7C1.BT8"
				( objectStatus "@baseboard_fab2_lib.baseboard_fab2(sch_1):page124_i15:vss(43)" )
			)
			( pin "U7C1.BR50"
				( objectStatus "@baseboard_fab2_lib.baseboard_fab2(sch_1):page124_i15:vss(44)" )
			)
			( pin "U7C1.BR20"
				( objectStatus "@baseboard_fab2_lib.baseboard_fab2(sch_1):page124_i15:vss(45)" )
			)
			( pin "U7C1.BN66"
				( objectStatus "@baseboard_fab2_lib.baseboard_fab2(sch_1):page124_i15:vss(46)" )
			)
			( pin "U7C1.BN52"
				( objectStatus "@baseboard_fab2_lib.baseboard_fab2(sch_1):page124_i15:vss(47)" )
			)
			( pin "U7C1.BN5"
				( objectStatus "@baseboard_fab2_lib.baseboard_fab2(sch_1):page124_i15:vss(48)" )
			)
			( pin "U7C1.BN59"
				( objectStatus "@baseboard_fab2_lib.baseboard_fab2(sch_1):page124_i15:vss(49)" )
			)
			( pin "U7C1.BN22"
				( objectStatus "@baseboard_fab2_lib.baseboard_fab2(sch_1):page124_i15:vss(50)" )
			)
			( pin "U7C1.BM9"
				( objectStatus "@baseboard_fab2_lib.baseboard_fab2(sch_1):page124_i15:vss(51)" )
			)
			( pin "U7C1.BM71"
				( objectStatus "@baseboard_fab2_lib.baseboard_fab2(sch_1):page124_i15:vss(52)" )
			)
			( pin "U7C1.BM69"
				( objectStatus "@baseboard_fab2_lib.baseboard_fab2(sch_1):page124_i15:vss(53)" )
			)
			( pin "U7C1.BM58"
				( objectStatus "@baseboard_fab2_lib.baseboard_fab2(sch_1):page124_i15:vss(54)" )
			)
			( pin "U7C1.BM50"
				( objectStatus "@baseboard_fab2_lib.baseboard_fab2(sch_1):page124_i15:vss(55)" )
			)
			( pin "U7C1.BM46"
				( objectStatus "@baseboard_fab2_lib.baseboard_fab2(sch_1):page124_i15:vss(56)" )
			)
			( pin "U7C1.BN37"
				( objectStatus "@baseboard_fab2_lib.baseboard_fab2(sch_1):page124_i15:vss(57)" )
			)
			( pin "U7C1.BM17"
				( objectStatus "@baseboard_fab2_lib.baseboard_fab2(sch_1):page124_i15:vss(58)" )
			)
			( pin "U7C1.BM13"
				( objectStatus "@baseboard_fab2_lib.baseboard_fab2(sch_1):page124_i15:vss(59)" )
			)
			( pin "U7C1.BL72"
				( objectStatus "@baseboard_fab2_lib.baseboard_fab2(sch_1):page124_i15:vss(60)" )
			)
			( pin "U7C1.BL70"
				( objectStatus "@baseboard_fab2_lib.baseboard_fab2(sch_1):page124_i15:vss(61)" )
			)
			( pin "U7C1.BL63"
				( objectStatus "@baseboard_fab2_lib.baseboard_fab2(sch_1):page124_i15:vss(62)" )
			)
			( pin "U7C1.BL5"
				( objectStatus "@baseboard_fab2_lib.baseboard_fab2(sch_1):page124_i15:vss(63)" )
			)
			( pin "U7C1.BL37"
				( objectStatus "@baseboard_fab2_lib.baseboard_fab2(sch_1):page124_i15:vss(64)" )
			)
			( pin "U7C1.BL68"
				( objectStatus "@baseboard_fab2_lib.baseboard_fab2(sch_1):page124_i15:vss(65)" )
			)
			( pin "U7C1.BL40"
				( objectStatus "@baseboard_fab2_lib.baseboard_fab2(sch_1):page124_i15:vss(66)" )
			)
			( pin "U7C1.BL22"
				( objectStatus "@baseboard_fab2_lib.baseboard_fab2(sch_1):page124_i15:vss(67)" )
			)
			( pin "U7C1.BK50"
				( objectStatus "@baseboard_fab2_lib.baseboard_fab2(sch_1):page124_i15:vss(68)" )
			)
			( pin "U7C1.BK42"
				( objectStatus "@baseboard_fab2_lib.baseboard_fab2(sch_1):page124_i15:vss(69)" )
			)
			( pin "U7C1.BK38"
				( objectStatus "@baseboard_fab2_lib.baseboard_fab2(sch_1):page124_i15:vss(70)" )
			)
			( pin "U7C1.BK35"
				( objectStatus "@baseboard_fab2_lib.baseboard_fab2(sch_1):page124_i15:vss(71)" )
			)
			( pin "U7C1.BK31"
				( objectStatus "@baseboard_fab2_lib.baseboard_fab2(sch_1):page124_i15:vss(72)" )
			)
			( pin "U7C1.BK27"
				( objectStatus "@baseboard_fab2_lib.baseboard_fab2(sch_1):page124_i15:vss(73)" )
			)
			( pin "U7C1.BK24"
				( objectStatus "@baseboard_fab2_lib.baseboard_fab2(sch_1):page124_i15:vss(74)" )
			)
			( pin "U7C1.BJ68"
				( objectStatus "@baseboard_fab2_lib.baseboard_fab2(sch_1):page124_i16:vss(75)" )
			)
			( pin "U7C1.BJ52"
				( objectStatus "@baseboard_fab2_lib.baseboard_fab2(sch_1):page124_i16:vss(76)" )
			)
			( pin "U7C1.BJ33"
				( objectStatus "@baseboard_fab2_lib.baseboard_fab2(sch_1):page124_i16:vss(77)" )
			)
			( pin "U7C1.BJ3"
				( objectStatus "@baseboard_fab2_lib.baseboard_fab2(sch_1):page124_i16:vss(78)" )
			)
			( pin "U7C1.BJ26"
				( objectStatus "@baseboard_fab2_lib.baseboard_fab2(sch_1):page124_i16:vss(79)" )
			)
			( pin "U7C1.BJ18"
				( objectStatus "@baseboard_fab2_lib.baseboard_fab2(sch_1):page124_i16:vss(80)" )
			)
			( pin "U7C1.BJ15"
				( objectStatus "@baseboard_fab2_lib.baseboard_fab2(sch_1):page124_i16:vss(81)" )
			)
			( pin "U7C1.BJ7"
				( objectStatus "@baseboard_fab2_lib.baseboard_fab2(sch_1):page124_i16:vss(82)" )
			)
			( pin "U7C1.BJ5"
				( objectStatus "@baseboard_fab2_lib.baseboard_fab2(sch_1):page124_i16:vss(83)" )
			)
			( pin "U7C1.BJ11"
				( objectStatus "@baseboard_fab2_lib.baseboard_fab2(sch_1):page124_i16:vss(84)" )
			)
			( pin "U7C1.BJ1"
				( objectStatus "@baseboard_fab2_lib.baseboard_fab2(sch_1):page124_i16:vss(85)" )
			)
			( pin "U7C1.BH54"
				( objectStatus "@baseboard_fab2_lib.baseboard_fab2(sch_1):page124_i16:vss(86)" )
			)
			( pin "U7C1.BH46"
				( objectStatus "@baseboard_fab2_lib.baseboard_fab2(sch_1):page124_i16:vss(87)" )
			)
			( pin "U7C1.BH42"
				( objectStatus "@baseboard_fab2_lib.baseboard_fab2(sch_1):page124_i16:vss(88)" )
			)
			( pin "U7C1.BH38"
				( objectStatus "@baseboard_fab2_lib.baseboard_fab2(sch_1):page124_i16:vss(89)" )
			)
			( pin "U7C1.BH27"
				( objectStatus "@baseboard_fab2_lib.baseboard_fab2(sch_1):page124_i16:vss(90)" )
			)
			( pin "U7C1.BG63"
				( objectStatus "@baseboard_fab2_lib.baseboard_fab2(sch_1):page124_i16:vss(91)" )
			)
			( pin "U7C1.BG59"
				( objectStatus "@baseboard_fab2_lib.baseboard_fab2(sch_1):page124_i16:vss(92)" )
			)
			( pin "U7C1.BG48"
				( objectStatus "@baseboard_fab2_lib.baseboard_fab2(sch_1):page124_i16:vss(93)" )
			)
			( pin "U7C1.BG33"
				( objectStatus "@baseboard_fab2_lib.baseboard_fab2(sch_1):page124_i16:vss(94)" )
			)
			( pin "U7C1.BF9"
				( objectStatus "@baseboard_fab2_lib.baseboard_fab2(sch_1):page124_i16:vss(95)" )
			)
			( pin "U7C1.BF68"
				( objectStatus "@baseboard_fab2_lib.baseboard_fab2(sch_1):page124_i16:vss(96)" )
			)
			( pin "U7C1.BF65"
				( objectStatus "@baseboard_fab2_lib.baseboard_fab2(sch_1):page124_i16:vss(97)" )
			)
			( pin "U7C1.BF61"
				( objectStatus "@baseboard_fab2_lib.baseboard_fab2(sch_1):page124_i16:vss(98)" )
			)
			( pin "U7C1.BF58"
				( objectStatus "@baseboard_fab2_lib.baseboard_fab2(sch_1):page124_i16:vss(99)" )
			)
			( pin "U7C1.BF50"
				( objectStatus "@baseboard_fab2_lib.baseboard_fab2(sch_1):page124_i16:vss(100)" )
			)
			( pin "U7C1.BF5"
				( objectStatus "@baseboard_fab2_lib.baseboard_fab2(sch_1):page124_i16:vss(101)" )
			)
			( pin "U7C1.BF42"
				( objectStatus "@baseboard_fab2_lib.baseboard_fab2(sch_1):page124_i16:vss(102)" )
			)
			( pin "U7C1.BF38"
				( objectStatus "@baseboard_fab2_lib.baseboard_fab2(sch_1):page124_i16:vss(103)" )
			)
			( pin "U7C1.BF27"
				( objectStatus "@baseboard_fab2_lib.baseboard_fab2(sch_1):page124_i16:vss(104)" )
			)
			( pin "U7C1.BF24"
				( objectStatus "@baseboard_fab2_lib.baseboard_fab2(sch_1):page124_i16:vss(105)" )
			)
			( pin "U7C1.BF20"
				( objectStatus "@baseboard_fab2_lib.baseboard_fab2(sch_1):page124_i16:vss(106)" )
			)
			( pin "U7C1.BG44"
				( objectStatus "@baseboard_fab2_lib.baseboard_fab2(sch_1):page124_i16:vss(107)" )
			)
			( pin "U7C1.BF54"
				( objectStatus "@baseboard_fab2_lib.baseboard_fab2(sch_1):page124_i16:vss(108)" )
			)
			( pin "U7C1.BF17"
				( objectStatus "@baseboard_fab2_lib.baseboard_fab2(sch_1):page124_i16:vss(109)" )
			)
			( pin "U7C1.BF13"
				( objectStatus "@baseboard_fab2_lib.baseboard_fab2(sch_1):page124_i16:vss(110)" )
			)
			( pin "U7C1.BE66"
				( objectStatus "@baseboard_fab2_lib.baseboard_fab2(sch_1):page124_i16:vss(111)" )
			)
			( pin "U7C1.BE63"
				( objectStatus "@baseboard_fab2_lib.baseboard_fab2(sch_1):page124_i16:vss(112)" )
			)
			( pin "U7C1.BE59"
				( objectStatus "@baseboard_fab2_lib.baseboard_fab2(sch_1):page124_i16:vss(113)" )
			)
			( pin "U7C1.BE56"
				( objectStatus "@baseboard_fab2_lib.baseboard_fab2(sch_1):page124_i16:vss(114)" )
			)
			( pin "U7C1.BE37"
				( objectStatus "@baseboard_fab2_lib.baseboard_fab2(sch_1):page124_i16:vss(115)" )
			)
			( pin "U7C1.BE33"
				( objectStatus "@baseboard_fab2_lib.baseboard_fab2(sch_1):page124_i16:vss(116)" )
			)
			( pin "U7C1.BE29"
				( objectStatus "@baseboard_fab2_lib.baseboard_fab2(sch_1):page124_i16:vss(117)" )
			)
			( pin "U7C1.BD68"
				( objectStatus "@baseboard_fab2_lib.baseboard_fab2(sch_1):page124_i16:vss(118)" )
			)
			( pin "U7C1.BD54"
				( objectStatus "@baseboard_fab2_lib.baseboard_fab2(sch_1):page124_i16:vss(119)" )
			)
			( pin "U7C1.BD50"
				( objectStatus "@baseboard_fab2_lib.baseboard_fab2(sch_1):page124_i16:vss(120)" )
			)
			( pin "U7C1.BD5"
				( objectStatus "@baseboard_fab2_lib.baseboard_fab2(sch_1):page124_i16:vss(121)" )
			)
			( pin "U7C1.BD35"
				( objectStatus "@baseboard_fab2_lib.baseboard_fab2(sch_1):page124_i16:vss(122)" )
			)
			( pin "U7C1.BD31"
				( objectStatus "@baseboard_fab2_lib.baseboard_fab2(sch_1):page124_i16:vss(123)" )
			)
			( pin "U7C1.BD27"
				( objectStatus "@baseboard_fab2_lib.baseboard_fab2(sch_1):page124_i16:vss(124)" )
			)
			( pin "U7C1.BD24"
				( objectStatus "@baseboard_fab2_lib.baseboard_fab2(sch_1):page124_i16:vss(125)" )
			)
			( pin "U7C1.BC71"
				( objectStatus "@baseboard_fab2_lib.baseboard_fab2(sch_1):page124_i16:vss(126)" )
			)
			( pin "U7C1.BC69"
				( objectStatus "@baseboard_fab2_lib.baseboard_fab2(sch_1):page124_i16:vss(127)" )
			)
			( pin "U7C1.BB72"
				( objectStatus "@baseboard_fab2_lib.baseboard_fab2(sch_1):page124_i16:vss(128)" )
			)
			( pin "U7C1.BB70"
				( objectStatus "@baseboard_fab2_lib.baseboard_fab2(sch_1):page124_i16:vss(129)" )
			)
			( pin "U7C1.BB68"
				( objectStatus "@baseboard_fab2_lib.baseboard_fab2(sch_1):page124_i16:vss(130)" )
			)
			( pin "U7C1.BB66"
				( objectStatus "@baseboard_fab2_lib.baseboard_fab2(sch_1):page124_i16:vss(131)" )
			)
			( pin "U7C1.BB59"
				( objectStatus "@baseboard_fab2_lib.baseboard_fab2(sch_1):page124_i16:vss(132)" )
			)
			( pin "U7C1.BB44"
				( objectStatus "@baseboard_fab2_lib.baseboard_fab2(sch_1):page124_i16:vss(133)" )
			)
			( pin "U7C1.BB22"
				( objectStatus "@baseboard_fab2_lib.baseboard_fab2(sch_1):page124_i16:vss(134)" )
			)
			( pin "U7C1.BB18"
				( objectStatus "@baseboard_fab2_lib.baseboard_fab2(sch_1):page124_i16:vss(135)" )
			)
			( pin "U7C1.BB15"
				( objectStatus "@baseboard_fab2_lib.baseboard_fab2(sch_1):page124_i16:vss(136)" )
			)
			( pin "U7C1.BB11"
				( objectStatus "@baseboard_fab2_lib.baseboard_fab2(sch_1):page124_i16:vss(137)" )
			)
			( pin "U7C1.BB7"
				( objectStatus "@baseboard_fab2_lib.baseboard_fab2(sch_1):page124_i16:vss(138)" )
			)
			( pin "U7C1.BB5"
				( objectStatus "@baseboard_fab2_lib.baseboard_fab2(sch_1):page124_i16:vss(139)" )
			)
			( pin "U7C1.BA58"
				( objectStatus "@baseboard_fab2_lib.baseboard_fab2(sch_1):page124_i16:vss(140)" )
			)
			( pin "U7C1.BA54"
				( objectStatus "@baseboard_fab2_lib.baseboard_fab2(sch_1):page124_i16:vss(141)" )
			)
			( pin "U7C1.BA50"
				( objectStatus "@baseboard_fab2_lib.baseboard_fab2(sch_1):page124_i16:vss(142)" )
			)
			( pin "U7C1.AY68"
				( objectStatus "@baseboard_fab2_lib.baseboard_fab2(sch_1):page124_i16:vss(143)" )
			)
			( pin "U7C1.AY63"
				( objectStatus "@baseboard_fab2_lib.baseboard_fab2(sch_1):page124_i16:vss(144)" )
			)
			( pin "U7C1.AY56"
				( objectStatus "@baseboard_fab2_lib.baseboard_fab2(sch_1):page124_i16:vss(145)" )
			)
			( pin "U7C1.AY22"
				( objectStatus "@baseboard_fab2_lib.baseboard_fab2(sch_1):page124_i16:vss(146)" )
			)
			( pin "U7C1.AY5"
				( objectStatus "@baseboard_fab2_lib.baseboard_fab2(sch_1):page124_i16:vss(147)" )
			)
			( pin "U7C1.AW61"
				( objectStatus "@baseboard_fab2_lib.baseboard_fab2(sch_1):page124_i16:vss(148)" )
			)
			( pin "U7C1.AW58"
				( objectStatus "@baseboard_fab2_lib.baseboard_fab2(sch_1):page124_i16:vss(149)" )
			)
			( pin "U7C1.AW50"
				( objectStatus "@baseboard_fab2_lib.baseboard_fab2(sch_1):page124_i16:vss(150)" )
			)
			( pin "U7C1.AW46"
				( objectStatus "@baseboard_fab2_lib.baseboard_fab2(sch_1):page124_i16:vss(151)" )
			)
			( pin "U7C1.AW41"
				( objectStatus "@baseboard_fab2_lib.baseboard_fab2(sch_1):page124_i16:vss(152)" )
			)
			( pin "U7C1.AW39"
				( objectStatus "@baseboard_fab2_lib.baseboard_fab2(sch_1):page124_i16:vss(153)" )
			)
			( pin "U7C1.AW37"
				( objectStatus "@baseboard_fab2_lib.baseboard_fab2(sch_1):page124_i16:vss(154)" )
			)
			( pin "U7C1.AW36"
				( objectStatus "@baseboard_fab2_lib.baseboard_fab2(sch_1):page124_i16:vss(155)" )
			)
			( pin "U7C1.AW34"
				( objectStatus "@baseboard_fab2_lib.baseboard_fab2(sch_1):page124_i16:vss(156)" )
			)
			( pin "U7C1.AW32"
				( objectStatus "@baseboard_fab2_lib.baseboard_fab2(sch_1):page124_i16:vss(157)" )
			)
			( pin "U7C1.AW30"
				( objectStatus "@baseboard_fab2_lib.baseboard_fab2(sch_1):page124_i16:vss(158)" )
			)
			( pin "U7C1.AW26"
				( objectStatus "@baseboard_fab2_lib.baseboard_fab2(sch_1):page124_i16:vss(159)" )
			)
			( pin "U7C1.AW17"
				( objectStatus "@baseboard_fab2_lib.baseboard_fab2(sch_1):page124_i16:vss(160)" )
			)
			( pin "U7C1.AW13"
				( objectStatus "@baseboard_fab2_lib.baseboard_fab2(sch_1):page124_i16:vss(161)" )
			)
			( pin "U7C1.AW9"
				( objectStatus "@baseboard_fab2_lib.baseboard_fab2(sch_1):page124_i16:vss(162)" )
			)
			( pin "U7C1.AV68"
				( objectStatus "@baseboard_fab2_lib.baseboard_fab2(sch_1):page124_i16:vss(163)" )
			)
			( pin "U7C1.AV59"
				( objectStatus "@baseboard_fab2_lib.baseboard_fab2(sch_1):page124_i16:vss(164)" )
			)
			( pin "U7C1.AV22"
				( objectStatus "@baseboard_fab2_lib.baseboard_fab2(sch_1):page124_i16:vss(165)" )
			)
			( pin "U7C1.AV5"
				( objectStatus "@baseboard_fab2_lib.baseboard_fab2(sch_1):page124_i16:vss(166)" )
			)
			( pin "U7C1.AU61"
				( objectStatus "@baseboard_fab2_lib.baseboard_fab2(sch_1):page124_i16:vss(167)" )
			)
			( pin "U7C1.AU54"
				( objectStatus "@baseboard_fab2_lib.baseboard_fab2(sch_1):page124_i16:vss(168)" )
			)
			( pin "U7C1.AU50"
				( objectStatus "@baseboard_fab2_lib.baseboard_fab2(sch_1):page124_i16:vss(169)" )
			)
			( pin "U7C1.AU46"
				( objectStatus "@baseboard_fab2_lib.baseboard_fab2(sch_1):page124_i16:vss(170)" )
			)
			( pin "U7C1.AU41"
				( objectStatus "@baseboard_fab2_lib.baseboard_fab2(sch_1):page124_i16:vss(171)" )
			)
			( pin "U7C1.AE22"
				( objectStatus "@baseboard_fab2_lib.baseboard_fab2(sch_1):page124_i16:vss(172)" )
			)
			( pin "U7C1.AU30"
				( objectStatus "@baseboard_fab2_lib.baseboard_fab2(sch_1):page124_i16:vss(173)" )
			)
			( pin "U7C1.AU26"
				( objectStatus "@baseboard_fab2_lib.baseboard_fab2(sch_1):page124_i16:vss(174)" )
			)
			( pin "U7C1.AT59"
				( objectStatus "@baseboard_fab2_lib.baseboard_fab2(sch_1):page124_i16:vss(175)" )
			)
			( pin "U7C1.AT46"
				( objectStatus "@baseboard_fab2_lib.baseboard_fab2(sch_1):page124_i16:vss(176)" )
			)
			( pin "U7C1.AT41"
				( objectStatus "@baseboard_fab2_lib.baseboard_fab2(sch_1):page124_i16:vss(177)" )
			)
			( pin "U7C1.AT30"
				( objectStatus "@baseboard_fab2_lib.baseboard_fab2(sch_1):page124_i16:vss(178)" )
			)
			( pin "U7C1.AT26"
				( objectStatus "@baseboard_fab2_lib.baseboard_fab2(sch_1):page124_i16:vss(179)" )
			)
			( pin "U7C1.AT22"
				( objectStatus "@baseboard_fab2_lib.baseboard_fab2(sch_1):page124_i16:vss(180)" )
			)
			( pin "U7C1.AT18"
				( objectStatus "@baseboard_fab2_lib.baseboard_fab2(sch_1):page124_i16:vss(181)" )
			)
			( pin "U7C1.AT15"
				( objectStatus "@baseboard_fab2_lib.baseboard_fab2(sch_1):page124_i16:vss(182)" )
			)
			( pin "U7C1.AT11"
				( objectStatus "@baseboard_fab2_lib.baseboard_fab2(sch_1):page124_i16:vss(183)" )
			)
			( pin "U7C1.AT7"
				( objectStatus "@baseboard_fab2_lib.baseboard_fab2(sch_1):page124_i16:vss(184)" )
			)
			( pin "U7C1.AR72"
				( objectStatus "@baseboard_fab2_lib.baseboard_fab2(sch_1):page124_i16:vss(185)" )
			)
			( pin "U7C1.AR70"
				( objectStatus "@baseboard_fab2_lib.baseboard_fab2(sch_1):page124_i16:vss(186)" )
			)
			( pin "U7C1.AR68"
				( objectStatus "@baseboard_fab2_lib.baseboard_fab2(sch_1):page124_i16:vss(187)" )
			)
			( pin "U7C1.AR65"
				( objectStatus "@baseboard_fab2_lib.baseboard_fab2(sch_1):page124_i16:vss(188)" )
			)
			( pin "U7C1.AR58"
				( objectStatus "@baseboard_fab2_lib.baseboard_fab2(sch_1):page124_i16:vss(189)" )
			)
			( pin "U7C1.AR50"
				( objectStatus "@baseboard_fab2_lib.baseboard_fab2(sch_1):page124_i16:vss(190)" )
			)
			( pin "U7C1.AR5"
				( objectStatus "@baseboard_fab2_lib.baseboard_fab2(sch_1):page124_i16:vss(191)" )
			)
			( pin "U7C1.AP66"
				( objectStatus "@baseboard_fab2_lib.baseboard_fab2(sch_1):page124_i16:vss(192)" )
			)
			( pin "U7C1.AP52"
				( objectStatus "@baseboard_fab2_lib.baseboard_fab2(sch_1):page124_i16:vss(193)" )
			)
			( pin "U7C1.AP46"
				( objectStatus "@baseboard_fab2_lib.baseboard_fab2(sch_1):page124_i16:vss(194)" )
			)
			( pin "U7C1.AP41"
				( objectStatus "@baseboard_fab2_lib.baseboard_fab2(sch_1):page124_i16:vss(195)" )
			)
			( pin "U7C1.AP4"
				( objectStatus "@baseboard_fab2_lib.baseboard_fab2(sch_1):page124_i16:vss(196)" )
			)
			( pin "U7C1.AP30"
				( objectStatus "@baseboard_fab2_lib.baseboard_fab2(sch_1):page124_i16:vss(197)" )
			)
			( pin "U7C1.AP26"
				( objectStatus "@baseboard_fab2_lib.baseboard_fab2(sch_1):page124_i16:vss(198)" )
			)
			( pin "U7C1.AP2"
				( objectStatus "@baseboard_fab2_lib.baseboard_fab2(sch_1):page124_i16:vss(199)" )
			)
			( pin "U7C1.AN9"
				( objectStatus "@baseboard_fab2_lib.baseboard_fab2(sch_1):page124_i16:vss(200)" )
			)
			( pin "U7C1.AN58"
				( objectStatus "@baseboard_fab2_lib.baseboard_fab2(sch_1):page124_i16:vss(201)" )
			)
			( pin "U7C1.AN5"
				( objectStatus "@baseboard_fab2_lib.baseboard_fab2(sch_1):page124_i16:vss(202)" )
			)
			( pin "U7C1.AN20"
				( objectStatus "@baseboard_fab2_lib.baseboard_fab2(sch_1):page124_i16:vss(203)" )
			)
			( pin "U7C1.AP22"
				( objectStatus "@baseboard_fab2_lib.baseboard_fab2(sch_1):page124_i16:vss(204)" )
			)
			( pin "U7C1.AN68"
				( objectStatus "@baseboard_fab2_lib.baseboard_fab2(sch_1):page124_i16:vss(205)" )
			)
			( pin "U7C1.AN17"
				( objectStatus "@baseboard_fab2_lib.baseboard_fab2(sch_1):page124_i16:vss(206)" )
			)
			( pin "U7C1.AN13"
				( objectStatus "@baseboard_fab2_lib.baseboard_fab2(sch_1):page124_i16:vss(207)" )
			)
			( pin "U7C1.AM46"
				( objectStatus "@baseboard_fab2_lib.baseboard_fab2(sch_1):page124_i16:vss(208)" )
			)
			( pin "U7C1.AM41"
				( objectStatus "@baseboard_fab2_lib.baseboard_fab2(sch_1):page124_i16:vss(209)" )
			)
			( pin "U7C1.AM30"
				( objectStatus "@baseboard_fab2_lib.baseboard_fab2(sch_1):page124_i16:vss(210)" )
			)
			( pin "U7C1.AM26"
				( objectStatus "@baseboard_fab2_lib.baseboard_fab2(sch_1):page124_i16:vss(211)" )
			)
			( pin "U7C1.AL72"
				( objectStatus "@baseboard_fab2_lib.baseboard_fab2(sch_1):page124_i16:vss(212)" )
			)
			( pin "U7C1.AL70"
				( objectStatus "@baseboard_fab2_lib.baseboard_fab2(sch_1):page124_i16:vss(213)" )
			)
			( pin "U7C1.AL68"
				( objectStatus "@baseboard_fab2_lib.baseboard_fab2(sch_1):page124_i16:vss(214)" )
			)
			( pin "U7C1.AL59"
				( objectStatus "@baseboard_fab2_lib.baseboard_fab2(sch_1):page124_i17:vss(215)" )
			)
			( pin "U7C1.AL52"
				( objectStatus "@baseboard_fab2_lib.baseboard_fab2(sch_1):page124_i17:vss(216)" )
			)
			( pin "U7C1.AL5"
				( objectStatus "@baseboard_fab2_lib.baseboard_fab2(sch_1):page124_i17:vss(217)" )
			)
			( pin "U7C1.AL22"
				( objectStatus "@baseboard_fab2_lib.baseboard_fab2(sch_1):page124_i17:vss(218)" )
			)
			( pin "U7C1.AK71"
				( objectStatus "@baseboard_fab2_lib.baseboard_fab2(sch_1):page124_i17:vss(219)" )
			)
			( pin "U7C1.AK69"
				( objectStatus "@baseboard_fab2_lib.baseboard_fab2(sch_1):page124_i17:vss(220)" )
			)
			( pin "U7C1.AK61"
				( objectStatus "@baseboard_fab2_lib.baseboard_fab2(sch_1):page124_i17:vss(221)" )
			)
			( pin "U7C1.AK58"
				( objectStatus "@baseboard_fab2_lib.baseboard_fab2(sch_1):page124_i17:vss(222)" )
			)
			( pin "U7C1.AK48"
				( objectStatus "@baseboard_fab2_lib.baseboard_fab2(sch_1):page124_i17:vss(223)" )
			)
			( pin "U7C1.AK46"
				( objectStatus "@baseboard_fab2_lib.baseboard_fab2(sch_1):page124_i17:vss(224)" )
			)
			( pin "U7C1.AK41"
				( objectStatus "@baseboard_fab2_lib.baseboard_fab2(sch_1):page124_i17:vss(225)" )
			)
			( pin "U7C1.AK26"
				( objectStatus "@baseboard_fab2_lib.baseboard_fab2(sch_1):page124_i17:vss(226)" )
			)
			( pin "U7C1.AJ7"
				( objectStatus "@baseboard_fab2_lib.baseboard_fab2(sch_1):page124_i17:vss(227)" )
			)
			( pin "U7C1.AJ68"
				( objectStatus "@baseboard_fab2_lib.baseboard_fab2(sch_1):page124_i17:vss(228)" )
			)
			( pin "U7C1.AJ66"
				( objectStatus "@baseboard_fab2_lib.baseboard_fab2(sch_1):page124_i17:vss(229)" )
			)
			( pin "U7C1.AJ59"
				( objectStatus "@baseboard_fab2_lib.baseboard_fab2(sch_1):page124_i17:vss(230)" )
			)
			( pin "U7C1.AJ52"
				( objectStatus "@baseboard_fab2_lib.baseboard_fab2(sch_1):page124_i17:vss(231)" )
			)
			( pin "U7C1.AJ5"
				( objectStatus "@baseboard_fab2_lib.baseboard_fab2(sch_1):page124_i17:vss(232)" )
			)
			( pin "U7C1.AJ41"
				( objectStatus "@baseboard_fab2_lib.baseboard_fab2(sch_1):page124_i17:vss(233)" )
			)
			( pin "U7C1.AJ39"
				( objectStatus "@baseboard_fab2_lib.baseboard_fab2(sch_1):page124_i17:vss(234)" )
			)
			( pin "U7C1.AJ37"
				( objectStatus "@baseboard_fab2_lib.baseboard_fab2(sch_1):page124_i17:vss(235)" )
			)
			( pin "U7C1.AJ36"
				( objectStatus "@baseboard_fab2_lib.baseboard_fab2(sch_1):page124_i17:vss(236)" )
			)
			( pin "U7C1.AJ34"
				( objectStatus "@baseboard_fab2_lib.baseboard_fab2(sch_1):page124_i17:vss(237)" )
			)
			( pin "U7C1.AJ30"
				( objectStatus "@baseboard_fab2_lib.baseboard_fab2(sch_1):page124_i17:vss(238)" )
			)
			( pin "U7C1.AJ26"
				( objectStatus "@baseboard_fab2_lib.baseboard_fab2(sch_1):page124_i17:vss(239)" )
			)
			( pin "U7C1.AJ22"
				( objectStatus "@baseboard_fab2_lib.baseboard_fab2(sch_1):page124_i17:vss(240)" )
			)
			( pin "U7C1.AJ18"
				( objectStatus "@baseboard_fab2_lib.baseboard_fab2(sch_1):page124_i17:vss(241)" )
			)
			( pin "U7C1.AJ15"
				( objectStatus "@baseboard_fab2_lib.baseboard_fab2(sch_1):page124_i17:vss(242)" )
			)
			( pin "U7C1.AK30"
				( objectStatus "@baseboard_fab2_lib.baseboard_fab2(sch_1):page124_i17:vss(243)" )
			)
			( pin "U7C1.AJ56"
				( objectStatus "@baseboard_fab2_lib.baseboard_fab2(sch_1):page124_i17:vss(244)" )
			)
			( pin "U7C1.AJ32"
				( objectStatus "@baseboard_fab2_lib.baseboard_fab2(sch_1):page124_i17:vss(245)" )
			)
			( pin "U7C1.AJ11"
				( objectStatus "@baseboard_fab2_lib.baseboard_fab2(sch_1):page124_i17:vss(246)" )
			)
			( pin "U7C1.AH20"
				( objectStatus "@baseboard_fab2_lib.baseboard_fab2(sch_1):page124_i17:vss(247)" )
			)
			( pin "U7C1.AG66"
				( objectStatus "@baseboard_fab2_lib.baseboard_fab2(sch_1):page124_i17:vss(248)" )
			)
			( pin "U7C1.AG59"
				( objectStatus "@baseboard_fab2_lib.baseboard_fab2(sch_1):page124_i17:vss(249)" )
			)
			( pin "U7C1.AG56"
				( objectStatus "@baseboard_fab2_lib.baseboard_fab2(sch_1):page124_i17:vss(250)" )
			)
			( pin "U7C1.AG52"
				( objectStatus "@baseboard_fab2_lib.baseboard_fab2(sch_1):page124_i17:vss(251)" )
			)
			( pin "U7C1.AG43"
				( objectStatus "@baseboard_fab2_lib.baseboard_fab2(sch_1):page124_i17:vss(252)" )
			)
			( pin "U7C1.AG41"
				( objectStatus "@baseboard_fab2_lib.baseboard_fab2(sch_1):page124_i17:vss(253)" )
			)
			( pin "U7C1.AG30"
				( objectStatus "@baseboard_fab2_lib.baseboard_fab2(sch_1):page124_i17:vss(254)" )
			)
			( pin "U7C1.AG26"
				( objectStatus "@baseboard_fab2_lib.baseboard_fab2(sch_1):page124_i17:vss(255)" )
			)
			( pin "U7C1.AF68"
				( objectStatus "@baseboard_fab2_lib.baseboard_fab2(sch_1):page124_i17:vss(256)" )
			)
			( pin "U7C1.AF3"
				( objectStatus "@baseboard_fab2_lib.baseboard_fab2(sch_1):page124_i17:vss(257)" )
			)
			( pin "U7C1.AF24"
				( objectStatus "@baseboard_fab2_lib.baseboard_fab2(sch_1):page124_i17:vss(258)" )
			)
			( pin "U7C1.AF17"
				( objectStatus "@baseboard_fab2_lib.baseboard_fab2(sch_1):page124_i17:vss(259)" )
			)
			( pin "U7C1.AF9"
				( objectStatus "@baseboard_fab2_lib.baseboard_fab2(sch_1):page124_i17:vss(260)" )
			)
			( pin "U7C1.AF5"
				( objectStatus "@baseboard_fab2_lib.baseboard_fab2(sch_1):page124_i17:vss(261)" )
			)
			( pin "U7C1.AF13"
				( objectStatus "@baseboard_fab2_lib.baseboard_fab2(sch_1):page124_i17:vss(262)" )
			)
			( pin "U7C1.AF1"
				( objectStatus "@baseboard_fab2_lib.baseboard_fab2(sch_1):page124_i17:vss(263)" )
			)
			( pin "U7C1.AE66"
				( objectStatus "@baseboard_fab2_lib.baseboard_fab2(sch_1):page124_i17:vss(264)" )
			)
			( pin "U7C1.AE63"
				( objectStatus "@baseboard_fab2_lib.baseboard_fab2(sch_1):page124_i17:vss(265)" )
			)
			( pin "U7C1.AE59"
				( objectStatus "@baseboard_fab2_lib.baseboard_fab2(sch_1):page124_i17:vss(266)" )
			)
			( pin "U7C1.AE56"
				( objectStatus "@baseboard_fab2_lib.baseboard_fab2(sch_1):page124_i17:vss(267)" )
			)
			( pin "U7C1.AE52"
				( objectStatus "@baseboard_fab2_lib.baseboard_fab2(sch_1):page124_i17:vss(268)" )
			)
			( pin "U7C1.AE48"
				( objectStatus "@baseboard_fab2_lib.baseboard_fab2(sch_1):page124_i17:vss(269)" )
			)
			( pin "U7C1.J18"
				( objectStatus "@baseboard_fab2_lib.baseboard_fab2(sch_1):page124_i17:vss(270)" )
			)
			( pin "U7C1.AE29"
				( objectStatus "@baseboard_fab2_lib.baseboard_fab2(sch_1):page124_i17:vss(271)" )
			)
			( pin "U7C1.AD68"
				( objectStatus "@baseboard_fab2_lib.baseboard_fab2(sch_1):page124_i17:vss(272)" )
			)
			( pin "U7C1.AD65"
				( objectStatus "@baseboard_fab2_lib.baseboard_fab2(sch_1):page124_i17:vss(273)" )
			)
			( pin "U7C1.AD5"
				( objectStatus "@baseboard_fab2_lib.baseboard_fab2(sch_1):page124_i17:vss(274)" )
			)
			( pin "U7C1.AC7"
				( objectStatus "@baseboard_fab2_lib.baseboard_fab2(sch_1):page124_i17:vss(275)" )
			)
			( pin "U7C1.AC66"
				( objectStatus "@baseboard_fab2_lib.baseboard_fab2(sch_1):page124_i17:vss(276)" )
			)
			( pin "U7C1.AC63"
				( objectStatus "@baseboard_fab2_lib.baseboard_fab2(sch_1):page124_i17:vss(277)" )
			)
			( pin "U7C1.AC59"
				( objectStatus "@baseboard_fab2_lib.baseboard_fab2(sch_1):page124_i17:vss(278)" )
			)
			( pin "U7C1.AC52"
				( objectStatus "@baseboard_fab2_lib.baseboard_fab2(sch_1):page124_i17:vss(279)" )
			)
			( pin "U7C1.AC48"
				( objectStatus "@baseboard_fab2_lib.baseboard_fab2(sch_1):page124_i17:vss(280)" )
			)
			( pin "U7C1.AC46"
				( objectStatus "@baseboard_fab2_lib.baseboard_fab2(sch_1):page124_i17:vss(281)" )
			)
			( pin "U7C1.AC43"
				( objectStatus "@baseboard_fab2_lib.baseboard_fab2(sch_1):page124_i17:vss(282)" )
			)
			( pin "U7C1.AC27"
				( objectStatus "@baseboard_fab2_lib.baseboard_fab2(sch_1):page124_i17:vss(283)" )
			)
			( pin "U7C1.AD58"
				( objectStatus "@baseboard_fab2_lib.baseboard_fab2(sch_1):page124_i17:vss(284)" )
			)
			( pin "U7C1.AC45"
				( objectStatus "@baseboard_fab2_lib.baseboard_fab2(sch_1):page124_i17:vss(285)" )
			)
			( pin "U7C1.AC22"
				( objectStatus "@baseboard_fab2_lib.baseboard_fab2(sch_1):page124_i17:vss(286)" )
			)
			( pin "U7C1.AC18"
				( objectStatus "@baseboard_fab2_lib.baseboard_fab2(sch_1):page124_i17:vss(287)" )
			)
			( pin "U7C1.AC15"
				( objectStatus "@baseboard_fab2_lib.baseboard_fab2(sch_1):page124_i17:vss(288)" )
			)
			( pin "U7C1.AC11"
				( objectStatus "@baseboard_fab2_lib.baseboard_fab2(sch_1):page124_i17:vss(289)" )
			)
			( pin "U7C1.AB72"
				( objectStatus "@baseboard_fab2_lib.baseboard_fab2(sch_1):page124_i17:vss(290)" )
			)
			( pin "U7C1.AB70"
				( objectStatus "@baseboard_fab2_lib.baseboard_fab2(sch_1):page124_i17:vss(291)" )
			)
			( pin "U7C1.AB68"
				( objectStatus "@baseboard_fab2_lib.baseboard_fab2(sch_1):page124_i17:vss(292)" )
			)
			( pin "U7C1.AB5"
				( objectStatus "@baseboard_fab2_lib.baseboard_fab2(sch_1):page124_i17:vss(293)" )
			)
			( pin "U7C1.AA48"
				( objectStatus "@baseboard_fab2_lib.baseboard_fab2(sch_1):page124_i17:vss(294)" )
			)
			( pin "U7C1.AA43"
				( objectStatus "@baseboard_fab2_lib.baseboard_fab2(sch_1):page124_i17:vss(295)" )
			)
			( pin "U7C1.AA27"
				( objectStatus "@baseboard_fab2_lib.baseboard_fab2(sch_1):page124_i17:vss(296)" )
			)
			( pin "U7C1.AA26"
				( objectStatus "@baseboard_fab2_lib.baseboard_fab2(sch_1):page124_i17:vss(297)" )
			)
			( pin "U7C1.Y68"
				( objectStatus "@baseboard_fab2_lib.baseboard_fab2(sch_1):page124_i17:vss(298)" )
			)
			( pin "U7C1.Y63"
				( objectStatus "@baseboard_fab2_lib.baseboard_fab2(sch_1):page124_i17:vss(299)" )
			)
			( pin "U7C1.Y59"
				( objectStatus "@baseboard_fab2_lib.baseboard_fab2(sch_1):page124_i17:vss(300)" )
			)
			( pin "U7C1.Y52"
				( objectStatus "@baseboard_fab2_lib.baseboard_fab2(sch_1):page124_i17:vss(301)" )
			)
			( pin "U7C1.Y5"
				( objectStatus "@baseboard_fab2_lib.baseboard_fab2(sch_1):page124_i17:vss(302)" )
			)
			( pin "U7C1.Y48"
				( objectStatus "@baseboard_fab2_lib.baseboard_fab2(sch_1):page124_i17:vss(303)" )
			)
			( pin "U7C1.Y27"
				( objectStatus "@baseboard_fab2_lib.baseboard_fab2(sch_1):page124_i17:vss(304)" )
			)
			( pin "U7C1.Y22"
				( objectStatus "@baseboard_fab2_lib.baseboard_fab2(sch_1):page124_i17:vss(305)" )
			)
			( pin "U7C1.W9"
				( objectStatus "@baseboard_fab2_lib.baseboard_fab2(sch_1):page124_i17:vss(306)" )
			)
			( pin "U7C1.W61"
				( objectStatus "@baseboard_fab2_lib.baseboard_fab2(sch_1):page124_i17:vss(307)" )
			)
			( pin "U7C1.Y43"
				( objectStatus "@baseboard_fab2_lib.baseboard_fab2(sch_1):page124_i17:vss(308)" )
			)
			( pin "U7C1.AA50"
				( objectStatus "@baseboard_fab2_lib.baseboard_fab2(sch_1):page124_i17:vss(309)" )
			)
			( pin "U7C1.W24"
				( objectStatus "@baseboard_fab2_lib.baseboard_fab2(sch_1):page124_i17:vss(310)" )
			)
			( pin "U7C1.W20"
				( objectStatus "@baseboard_fab2_lib.baseboard_fab2(sch_1):page124_i17:vss(311)" )
			)
			( pin "U7C1.W17"
				( objectStatus "@baseboard_fab2_lib.baseboard_fab2(sch_1):page124_i17:vss(312)" )
			)
			( pin "U7C1.W13"
				( objectStatus "@baseboard_fab2_lib.baseboard_fab2(sch_1):page124_i17:vss(313)" )
			)
			( pin "U7C1.V68"
				( objectStatus "@baseboard_fab2_lib.baseboard_fab2(sch_1):page124_i17:vss(314)" )
			)
			( pin "U7C1.V66"
				( objectStatus "@baseboard_fab2_lib.baseboard_fab2(sch_1):page124_i17:vss(315)" )
			)
			( pin "U7C1.W58"
				( objectStatus "@baseboard_fab2_lib.baseboard_fab2(sch_1):page124_i17:vss(316)" )
			)
			( pin "U7C1.V52"
				( objectStatus "@baseboard_fab2_lib.baseboard_fab2(sch_1):page124_i17:vss(317)" )
			)
			( pin "U7C1.V5"
				( objectStatus "@baseboard_fab2_lib.baseboard_fab2(sch_1):page124_i17:vss(318)" )
			)
			( pin "U7C1.V48"
				( objectStatus "@baseboard_fab2_lib.baseboard_fab2(sch_1):page124_i17:vss(319)" )
			)
			( pin "U7C1.V26"
				( objectStatus "@baseboard_fab2_lib.baseboard_fab2(sch_1):page124_i17:vss(320)" )
			)
			( pin "U7C1.U58"
				( objectStatus "@baseboard_fab2_lib.baseboard_fab2(sch_1):page124_i17:vss(321)" )
			)
			( pin "U7C1.AG46"
				( objectStatus "@baseboard_fab2_lib.baseboard_fab2(sch_1):page124_i17:vss(322)" )
			)
			( pin "U7C1.AF50"
				( objectStatus "@baseboard_fab2_lib.baseboard_fab2(sch_1):page124_i17:vss(323)" )
			)
			( pin "U7C1.T7"
				( objectStatus "@baseboard_fab2_lib.baseboard_fab2(sch_1):page124_i17:vss(324)" )
			)
			( pin "U7C1.T66"
				( objectStatus "@baseboard_fab2_lib.baseboard_fab2(sch_1):page124_i17:vss(325)" )
			)
			( pin "U7C1.T52"
				( objectStatus "@baseboard_fab2_lib.baseboard_fab2(sch_1):page124_i17:vss(326)" )
			)
			( pin "U7C1.T48"
				( objectStatus "@baseboard_fab2_lib.baseboard_fab2(sch_1):page124_i17:vss(327)" )
			)
			( pin "U7C1.AJ45"
				( objectStatus "@baseboard_fab2_lib.baseboard_fab2(sch_1):page124_i17:vss(328)" )
			)
			( pin "U7C1.T40"
				( objectStatus "@baseboard_fab2_lib.baseboard_fab2(sch_1):page124_i17:vss(329)" )
			)
			( pin "U7C1.T37"
				( objectStatus "@baseboard_fab2_lib.baseboard_fab2(sch_1):page124_i17:vss(330)" )
			)
			( pin "U7C1.T33"
				( objectStatus "@baseboard_fab2_lib.baseboard_fab2(sch_1):page124_i17:vss(331)" )
			)
			( pin "U7C1.T29"
				( objectStatus "@baseboard_fab2_lib.baseboard_fab2(sch_1):page124_i17:vss(332)" )
			)
			( pin "U7C1.T26"
				( objectStatus "@baseboard_fab2_lib.baseboard_fab2(sch_1):page124_i17:vss(333)" )
			)
			( pin "U7C1.T22"
				( objectStatus "@baseboard_fab2_lib.baseboard_fab2(sch_1):page124_i17:vss(334)" )
			)
			( pin "U7C1.T18"
				( objectStatus "@baseboard_fab2_lib.baseboard_fab2(sch_1):page124_i17:vss(335)" )
			)
			( pin "U7C1.T15"
				( objectStatus "@baseboard_fab2_lib.baseboard_fab2(sch_1):page124_i17:vss(336)" )
			)
			( pin "U7C1.T11"
				( objectStatus "@baseboard_fab2_lib.baseboard_fab2(sch_1):page124_i17:vss(337)" )
			)
			( pin "U7C1.R68"
				( objectStatus "@baseboard_fab2_lib.baseboard_fab2(sch_1):page124_i17:vss(338)" )
			)
			( pin "U7C1.R58"
				( objectStatus "@baseboard_fab2_lib.baseboard_fab2(sch_1):page124_i17:vss(339)" )
			)
			( pin "U7C1.T56"
				( objectStatus "@baseboard_fab2_lib.baseboard_fab2(sch_1):page124_i17:vss(340)" )
			)
			( pin "U7C1.R54"
				( objectStatus "@baseboard_fab2_lib.baseboard_fab2(sch_1):page124_i17:vss(341)" )
			)
			( pin "U7C1.R50"
				( objectStatus "@baseboard_fab2_lib.baseboard_fab2(sch_1):page124_i17:vss(342)" )
			)
			( pin "U7C1.R5"
				( objectStatus "@baseboard_fab2_lib.baseboard_fab2(sch_1):page124_i17:vss(343)" )
			)
			( pin "U7C1.U42"
				( objectStatus "@baseboard_fab2_lib.baseboard_fab2(sch_1):page124_i17:vss(344)" )
			)
			( pin "U7C1.R27"
				( objectStatus "@baseboard_fab2_lib.baseboard_fab2(sch_1):page124_i17:vss(345)" )
			)
			( pin "U7C1.P63"
				( objectStatus "@baseboard_fab2_lib.baseboard_fab2(sch_1):page124_i17:vss(346)" )
			)
			( pin "U7C1.AE43"
				( objectStatus "@baseboard_fab2_lib.baseboard_fab2(sch_1):page124_i17:vss(347)" )
			)
			( pin "U7C1.N9"
				( objectStatus "@baseboard_fab2_lib.baseboard_fab2(sch_1):page124_i17:vss(348)" )
			)
			( pin "U7C1.N68"
				( objectStatus "@baseboard_fab2_lib.baseboard_fab2(sch_1):page124_i17:vss(349)" )
			)
			( pin "U7C1.R38"
				( objectStatus "@baseboard_fab2_lib.baseboard_fab2(sch_1):page124_i17:vss(350)" )
			)
			( pin "U7C1.N5"
				( objectStatus "@baseboard_fab2_lib.baseboard_fab2(sch_1):page124_i17:vss(351)" )
			)
			( pin "U7C1.N46"
				( objectStatus "@baseboard_fab2_lib.baseboard_fab2(sch_1):page124_i17:vss(352)" )
			)
			( pin "U7C1.N38"
				( objectStatus "@baseboard_fab2_lib.baseboard_fab2(sch_1):page124_i17:vss(353)" )
			)
			( pin "U7C1.N35"
				( objectStatus "@baseboard_fab2_lib.baseboard_fab2(sch_1):page124_i17:vss(354)" )
			)
			( pin "R2R11.1"
				( objectStatus "@baseboard_fab2_lib.baseboard_fab2(sch_1):page125_i11:a" )
			)
			( pin "R2R11.2"
				( objectStatus "@baseboard_fab2_lib.baseboard_fab2(sch_1):page125_i11:b" )
			)
			( pin "R8E6.1"
				( objectStatus "@baseboard_fab2_lib.baseboard_fab2(sch_1):page125_i21:a" )
			)
			( pin "R8E6.2"
				( objectStatus "@baseboard_fab2_lib.baseboard_fab2(sch_1):page125_i21:b" )
			)
			( pin "R8E4.1"
				( objectStatus "@baseboard_fab2_lib.baseboard_fab2(sch_1):page125_i24:a" )
			)
			( pin "R8E4.2"
				( objectStatus "@baseboard_fab2_lib.baseboard_fab2(sch_1):page125_i24:b" )
			)
			( pin "R8C18.1"
				( objectStatus "@baseboard_fab2_lib.baseboard_fab2(sch_1):page125_i40:a" )
			)
			( pin "R8C18.2"
				( objectStatus "@baseboard_fab2_lib.baseboard_fab2(sch_1):page125_i40:b" )
			)
			( pin "R8C17.1"
				( objectStatus "@baseboard_fab2_lib.baseboard_fab2(sch_1):page125_i41:a" )
			)
			( pin "R8C17.2"
				( objectStatus "@baseboard_fab2_lib.baseboard_fab2(sch_1):page125_i41:b" )
			)
			( pin "R8D5.1"
				( objectStatus "@baseboard_fab2_lib.baseboard_fab2(sch_1):page125_i50:a" )
			)
			( pin "R8D5.2"
				( objectStatus "@baseboard_fab2_lib.baseboard_fab2(sch_1):page125_i50:b" )
			)
			( pin "R7D13.1"
				( objectStatus "@baseboard_fab2_lib.baseboard_fab2(sch_1):page125_i60:a" )
			)
			( pin "R7D13.2"
				( objectStatus "@baseboard_fab2_lib.baseboard_fab2(sch_1):page125_i60:b" )
			)
			( pin "R25W141.1"
				( objectStatus "@baseboard_fab2_lib.baseboard_fab2(sch_1):page145_i160:a" )
			)
			( pin "R25W141.2"
				( objectStatus "@baseboard_fab2_lib.baseboard_fab2(sch_1):page145_i160:b" )
			)
			( pin "R3N2.1"
				( objectStatus "@baseboard_fab2_lib.baseboard_fab2(sch_1):page125_i72:a" )
			)
			( pin "R3N2.2"
				( objectStatus "@baseboard_fab2_lib.baseboard_fab2(sch_1):page125_i72:b" )
			)
			( pin "R3N17.1"
				( objectStatus "@baseboard_fab2_lib.baseboard_fab2(sch_1):page125_i78:a" )
			)
			( pin "R3N17.2"
				( objectStatus "@baseboard_fab2_lib.baseboard_fab2(sch_1):page125_i78:b" )
			)
			( pin "R2N14.1"
				( objectStatus "@baseboard_fab2_lib.baseboard_fab2(sch_1):page125_i83:a" )
			)
			( pin "R2N14.2"
				( objectStatus "@baseboard_fab2_lib.baseboard_fab2(sch_1):page125_i83:b" )
			)
			( pin "R7D19.1"
				( objectStatus "@baseboard_fab2_lib.baseboard_fab2(sch_1):page126_i6:a" )
			)
			( pin "R7D19.2"
				( objectStatus "@baseboard_fab2_lib.baseboard_fab2(sch_1):page126_i6:b" )
			)
			( pin "R12W20.1"
				( objectStatus "@baseboard_fab2_lib.baseboard_fab2(sch_1):page197_i110:\1\" )
			)
			( pin "R12W20.2"
				( objectStatus "@baseboard_fab2_lib.baseboard_fab2(sch_1):page197_i110:\2\" )
			)
			( pin "R1D35.1"
				( objectStatus "@baseboard_fab2_lib.baseboard_fab2(sch_1):page126_i12:a" )
			)
			( pin "R1D35.2"
				( objectStatus "@baseboard_fab2_lib.baseboard_fab2(sch_1):page126_i12:b" )
			)
			( pin "Q8E2.3"
				( objectStatus "@baseboard_fab2_lib.baseboard_fab2(sch_1):page126_i13:drn" )
			)
			( pin "Q8E2.1"
				( objectStatus "@baseboard_fab2_lib.baseboard_fab2(sch_1):page126_i13:gate" )
			)
			( pin "Q8E2.2"
				( objectStatus "@baseboard_fab2_lib.baseboard_fab2(sch_1):page126_i13:src" )
			)
			( pin "R8C9.1"
				( objectStatus "@baseboard_fab2_lib.baseboard_fab2(sch_1):page126_i20:a" )
			)
			( pin "R8C9.2"
				( objectStatus "@baseboard_fab2_lib.baseboard_fab2(sch_1):page126_i20:b" )
			)
			( pin "R3P62.1"
				( objectStatus "@baseboard_fab2_lib.baseboard_fab2(sch_1):page126_i22:a" )
			)
			( pin "R3P62.2"
				( objectStatus "@baseboard_fab2_lib.baseboard_fab2(sch_1):page126_i22:b" )
			)
			( pin "R3P64.1"
				( objectStatus "@baseboard_fab2_lib.baseboard_fab2(sch_1):page126_i23:a" )
			)
			( pin "R3P64.2"
				( objectStatus "@baseboard_fab2_lib.baseboard_fab2(sch_1):page126_i23:b" )
			)
			( pin "FB3M1.1"
				( objectStatus "@baseboard_fab2_lib.baseboard_fab2(sch_1):page127_i8:a" )
			)
			( pin "FB3M1.2"
				( objectStatus "@baseboard_fab2_lib.baseboard_fab2(sch_1):page127_i8:b" )
			)
			( pin "C3M21.1"
				( objectStatus "@baseboard_fab2_lib.baseboard_fab2(sch_1):page127_i9:a" )
			)
			( pin "C3M21.2"
				( objectStatus "@baseboard_fab2_lib.baseboard_fab2(sch_1):page127_i9:b" )
			)
			( pin "FB3M2.1"
				( objectStatus "@baseboard_fab2_lib.baseboard_fab2(sch_1):page127_i17:a" )
			)
			( pin "FB3M2.2"
				( objectStatus "@baseboard_fab2_lib.baseboard_fab2(sch_1):page127_i17:b" )
			)
			( pin "C3M22.1"
				( objectStatus "@baseboard_fab2_lib.baseboard_fab2(sch_1):page127_i18:a" )
			)
			( pin "C3M22.2"
				( objectStatus "@baseboard_fab2_lib.baseboard_fab2(sch_1):page127_i18:b" )
			)
			( pin "FB3M3.1"
				( objectStatus "@baseboard_fab2_lib.baseboard_fab2(sch_1):page127_i26:a" )
			)
			( pin "FB3M3.2"
				( objectStatus "@baseboard_fab2_lib.baseboard_fab2(sch_1):page127_i26:b" )
			)
			( pin "C3M30.1"
				( objectStatus "@baseboard_fab2_lib.baseboard_fab2(sch_1):page127_i27:a" )
			)
			( pin "C3M30.2"
				( objectStatus "@baseboard_fab2_lib.baseboard_fab2(sch_1):page127_i27:b" )
			)
			( pin "C2M5.1"
				( objectStatus "@baseboard_fab2_lib.baseboard_fab2(sch_1):page127_i43:a" )
			)
			( pin "C2M5.2"
				( objectStatus "@baseboard_fab2_lib.baseboard_fab2(sch_1):page127_i43:b" )
			)
			( pin "C2M7.1"
				( objectStatus "@baseboard_fab2_lib.baseboard_fab2(sch_1):page127_i44:a" )
			)
			( pin "C2M7.2"
				( objectStatus "@baseboard_fab2_lib.baseboard_fab2(sch_1):page127_i44:b" )
			)
			( pin "FB2M1.1"
				( objectStatus "@baseboard_fab2_lib.baseboard_fab2(sch_1):page127_i46:a" )
			)
			( pin "FB2M1.2"
				( objectStatus "@baseboard_fab2_lib.baseboard_fab2(sch_1):page127_i46:b" )
			)
			( pin "C2M10.1"
				( objectStatus "@baseboard_fab2_lib.baseboard_fab2(sch_1):page127_i49:a" )
			)
			( pin "C2M10.2"
				( objectStatus "@baseboard_fab2_lib.baseboard_fab2(sch_1):page127_i49:b" )
			)
			( pin "C2M9.1"
				( objectStatus "@baseboard_fab2_lib.baseboard_fab2(sch_1):page127_i50:a" )
			)
			( pin "C2M9.2"
				( objectStatus "@baseboard_fab2_lib.baseboard_fab2(sch_1):page127_i50:b" )
			)
			( pin "FB3M4.1"
				( objectStatus "@baseboard_fab2_lib.baseboard_fab2(sch_1):page127_i56:a" )
			)
			( pin "FB3M4.2"
				( objectStatus "@baseboard_fab2_lib.baseboard_fab2(sch_1):page127_i56:b" )
			)
			( pin "C3M31.1"
				( objectStatus "@baseboard_fab2_lib.baseboard_fab2(sch_1):page127_i57:a" )
			)
			( pin "C3M31.2"
				( objectStatus "@baseboard_fab2_lib.baseboard_fab2(sch_1):page127_i57:b" )
			)
			( pin "C2N6.1"
				( objectStatus "@baseboard_fab2_lib.baseboard_fab2(sch_1):page127_i64:a" )
			)
			( pin "C2N6.2"
				( objectStatus "@baseboard_fab2_lib.baseboard_fab2(sch_1):page127_i64:b" )
			)
			( pin "C2N5.1"
				( objectStatus "@baseboard_fab2_lib.baseboard_fab2(sch_1):page127_i65:a" )
			)
			( pin "C2N5.2"
				( objectStatus "@baseboard_fab2_lib.baseboard_fab2(sch_1):page127_i65:b" )
			)
			( pin "FB2M2.1"
				( objectStatus "@baseboard_fab2_lib.baseboard_fab2(sch_1):page127_i69:a" )
			)
			( pin "FB2M2.2"
				( objectStatus "@baseboard_fab2_lib.baseboard_fab2(sch_1):page127_i69:b" )
			)
			( pin "L2M1.1"
				( objectStatus "@baseboard_fab2_lib.baseboard_fab2(sch_1):page127_i71:ina" )
			)
			( pin "L2M1.2"
				( objectStatus "@baseboard_fab2_lib.baseboard_fab2(sch_1):page127_i71:inb" )
			)
			( pin "C2M8.1"
				( objectStatus "@baseboard_fab2_lib.baseboard_fab2(sch_1):page127_i74:a" )
			)
			( pin "C2M8.2"
				( objectStatus "@baseboard_fab2_lib.baseboard_fab2(sch_1):page127_i74:b" )
			)
			( pin "C2M6.1"
				( objectStatus "@baseboard_fab2_lib.baseboard_fab2(sch_1):page127_i76:a" )
			)
			( pin "C2M6.2"
				( objectStatus "@baseboard_fab2_lib.baseboard_fab2(sch_1):page127_i76:b" )
			)
			( pin "C2M25.1"
				( objectStatus "@baseboard_fab2_lib.baseboard_fab2(sch_1):page127_i78:a" )
			)
			( pin "C2M25.2"
				( objectStatus "@baseboard_fab2_lib.baseboard_fab2(sch_1):page127_i78:b" )
			)
			( pin "C3M29.1"
				( objectStatus "@baseboard_fab2_lib.baseboard_fab2(sch_1):page127_i80:a" )
			)
			( pin "C3M29.2"
				( objectStatus "@baseboard_fab2_lib.baseboard_fab2(sch_1):page127_i80:b" )
			)
			( pin "C3M24.1"
				( objectStatus "@baseboard_fab2_lib.baseboard_fab2(sch_1):page127_i81:a" )
			)
			( pin "C3M24.2"
				( objectStatus "@baseboard_fab2_lib.baseboard_fab2(sch_1):page127_i81:b" )
			)
			( pin "C3M23.1"
				( objectStatus "@baseboard_fab2_lib.baseboard_fab2(sch_1):page127_i82:a" )
			)
			( pin "C3M23.2"
				( objectStatus "@baseboard_fab2_lib.baseboard_fab2(sch_1):page127_i82:b" )
			)
			( pin "C3M27.1"
				( objectStatus "@baseboard_fab2_lib.baseboard_fab2(sch_1):page127_i83:a" )
			)
			( pin "C3M27.2"
				( objectStatus "@baseboard_fab2_lib.baseboard_fab2(sch_1):page127_i83:b" )
			)
			( pin "C3M20.1"
				( objectStatus "@baseboard_fab2_lib.baseboard_fab2(sch_1):page127_i84:a" )
			)
			( pin "C3M20.2"
				( objectStatus "@baseboard_fab2_lib.baseboard_fab2(sch_1):page127_i84:b" )
			)
			( pin "C3M18.1"
				( objectStatus "@baseboard_fab2_lib.baseboard_fab2(sch_1):page127_i85:a" )
			)
			( pin "C3M18.2"
				( objectStatus "@baseboard_fab2_lib.baseboard_fab2(sch_1):page127_i85:b" )
			)
			( pin "C3M17.1"
				( objectStatus "@baseboard_fab2_lib.baseboard_fab2(sch_1):page127_i86:a" )
			)
			( pin "C3M17.2"
				( objectStatus "@baseboard_fab2_lib.baseboard_fab2(sch_1):page127_i86:b" )
			)
			( pin "C3M19.1"
				( objectStatus "@baseboard_fab2_lib.baseboard_fab2(sch_1):page127_i87:a" )
			)
			( pin "C3M19.2"
				( objectStatus "@baseboard_fab2_lib.baseboard_fab2(sch_1):page127_i87:b" )
			)
			( pin "C7B25.1"
				( objectStatus "@baseboard_fab2_lib.baseboard_fab2(sch_1):page129_i35:a" )
			)
			( pin "C7B25.2"
				( objectStatus "@baseboard_fab2_lib.baseboard_fab2(sch_1):page129_i35:b" )
			)
			( pin "C7B27.1"
				( objectStatus "@baseboard_fab2_lib.baseboard_fab2(sch_1):page129_i69:a" )
			)
			( pin "C7B27.2"
				( objectStatus "@baseboard_fab2_lib.baseboard_fab2(sch_1):page129_i69:b" )
			)
			( pin "C7B28.1"
				( objectStatus "@baseboard_fab2_lib.baseboard_fab2(sch_1):page129_i70:a" )
			)
			( pin "C7B28.2"
				( objectStatus "@baseboard_fab2_lib.baseboard_fab2(sch_1):page129_i70:b" )
			)
			( pin "C7C2.1"
				( objectStatus "@baseboard_fab2_lib.baseboard_fab2(sch_1):page129_i71:a" )
			)
			( pin "C7C2.2"
				( objectStatus "@baseboard_fab2_lib.baseboard_fab2(sch_1):page129_i71:b" )
			)
			( pin "C3M40.1"
				( objectStatus "@baseboard_fab2_lib.baseboard_fab2(sch_1):page129_i72:a" )
			)
			( pin "C3M40.2"
				( objectStatus "@baseboard_fab2_lib.baseboard_fab2(sch_1):page129_i72:b" )
			)
			( pin "C3M37.1"
				( objectStatus "@baseboard_fab2_lib.baseboard_fab2(sch_1):page129_i73:a" )
			)
			( pin "C3M37.2"
				( objectStatus "@baseboard_fab2_lib.baseboard_fab2(sch_1):page129_i73:b" )
			)
			( pin "C3N9.1"
				( objectStatus "@baseboard_fab2_lib.baseboard_fab2(sch_1):page129_i74:a" )
			)
			( pin "C3N9.2"
				( objectStatus "@baseboard_fab2_lib.baseboard_fab2(sch_1):page129_i74:b" )
			)
			( pin "C3N8.1"
				( objectStatus "@baseboard_fab2_lib.baseboard_fab2(sch_1):page129_i75:a" )
			)
			( pin "C3N8.2"
				( objectStatus "@baseboard_fab2_lib.baseboard_fab2(sch_1):page129_i75:b" )
			)
			( pin "C7C3.1"
				( objectStatus "@baseboard_fab2_lib.baseboard_fab2(sch_1):page129_i76:a" )
			)
			( pin "C7C3.2"
				( objectStatus "@baseboard_fab2_lib.baseboard_fab2(sch_1):page129_i76:b" )
			)
			( pin "C7C1.1"
				( objectStatus "@baseboard_fab2_lib.baseboard_fab2(sch_1):page129_i77:a" )
			)
			( pin "C7C1.2"
				( objectStatus "@baseboard_fab2_lib.baseboard_fab2(sch_1):page129_i77:b" )
			)
			( pin "C7B29.1"
				( objectStatus "@baseboard_fab2_lib.baseboard_fab2(sch_1):page129_i78:a" )
			)
			( pin "C7B29.2"
				( objectStatus "@baseboard_fab2_lib.baseboard_fab2(sch_1):page129_i78:b" )
			)
			( pin "C7B26.1"
				( objectStatus "@baseboard_fab2_lib.baseboard_fab2(sch_1):page129_i79:a" )
			)
			( pin "C7B26.2"
				( objectStatus "@baseboard_fab2_lib.baseboard_fab2(sch_1):page129_i79:b" )
			)
			( pin "C3M44.1"
				( objectStatus "@baseboard_fab2_lib.baseboard_fab2(sch_1):page129_i80:a" )
			)
			( pin "C3M44.2"
				( objectStatus "@baseboard_fab2_lib.baseboard_fab2(sch_1):page129_i80:b" )
			)
			( pin "C3M41.1"
				( objectStatus "@baseboard_fab2_lib.baseboard_fab2(sch_1):page129_i81:a" )
			)
			( pin "C3M41.2"
				( objectStatus "@baseboard_fab2_lib.baseboard_fab2(sch_1):page129_i81:b" )
			)
			( pin "C3M45.1"
				( objectStatus "@baseboard_fab2_lib.baseboard_fab2(sch_1):page129_i82:a" )
			)
			( pin "C3M45.2"
				( objectStatus "@baseboard_fab2_lib.baseboard_fab2(sch_1):page129_i82:b" )
			)
			( pin "C3N13.1"
				( objectStatus "@baseboard_fab2_lib.baseboard_fab2(sch_1):page129_i83:a" )
			)
			( pin "C3N13.2"
				( objectStatus "@baseboard_fab2_lib.baseboard_fab2(sch_1):page129_i83:b" )
			)
			( pin "C7D2.1"
				( objectStatus "@baseboard_fab2_lib.baseboard_fab2(sch_1):page130_i2:a" )
			)
			( pin "C7D2.2"
				( objectStatus "@baseboard_fab2_lib.baseboard_fab2(sch_1):page130_i2:b" )
			)
			( pin "C2N26.1"
				( objectStatus "@baseboard_fab2_lib.baseboard_fab2(sch_1):page130_i4:a" )
			)
			( pin "C2N26.2"
				( objectStatus "@baseboard_fab2_lib.baseboard_fab2(sch_1):page130_i4:b" )
			)
			( pin "C2N19.1"
				( objectStatus "@baseboard_fab2_lib.baseboard_fab2(sch_1):page130_i7:a" )
			)
			( pin "C2N19.2"
				( objectStatus "@baseboard_fab2_lib.baseboard_fab2(sch_1):page130_i7:b" )
			)
			( pin "C2N24.1"
				( objectStatus "@baseboard_fab2_lib.baseboard_fab2(sch_1):page130_i8:a" )
			)
			( pin "C2N24.2"
				( objectStatus "@baseboard_fab2_lib.baseboard_fab2(sch_1):page130_i8:b" )
			)
			( pin "C2N22.1"
				( objectStatus "@baseboard_fab2_lib.baseboard_fab2(sch_1):page130_i9:a" )
			)
			( pin "C2N22.2"
				( objectStatus "@baseboard_fab2_lib.baseboard_fab2(sch_1):page130_i9:b" )
			)
			( pin "C2N20.1"
				( objectStatus "@baseboard_fab2_lib.baseboard_fab2(sch_1):page130_i12:a" )
			)
			( pin "C2N20.2"
				( objectStatus "@baseboard_fab2_lib.baseboard_fab2(sch_1):page130_i12:b" )
			)
			( pin "C2N21.1"
				( objectStatus "@baseboard_fab2_lib.baseboard_fab2(sch_1):page130_i15:a" )
			)
			( pin "C2N21.2"
				( objectStatus "@baseboard_fab2_lib.baseboard_fab2(sch_1):page130_i15:b" )
			)
			( pin "C3N29.1"
				( objectStatus "@baseboard_fab2_lib.baseboard_fab2(sch_1):page130_i16:a" )
			)
			( pin "C3N29.2"
				( objectStatus "@baseboard_fab2_lib.baseboard_fab2(sch_1):page130_i16:b" )
			)
			( pin "C8C3.1"
				( objectStatus "@baseboard_fab2_lib.baseboard_fab2(sch_1):page130_i19:a" )
			)
			( pin "C8C3.2"
				( objectStatus "@baseboard_fab2_lib.baseboard_fab2(sch_1):page130_i19:b" )
			)
			( pin "C8C4.1"
				( objectStatus "@baseboard_fab2_lib.baseboard_fab2(sch_1):page130_i20:a" )
			)
			( pin "C8C4.2"
				( objectStatus "@baseboard_fab2_lib.baseboard_fab2(sch_1):page130_i20:b" )
			)
			( pin "C8C5.1"
				( objectStatus "@baseboard_fab2_lib.baseboard_fab2(sch_1):page130_i21:a" )
			)
			( pin "C8C5.2"
				( objectStatus "@baseboard_fab2_lib.baseboard_fab2(sch_1):page130_i21:b" )
			)
			( pin "C8C6.1"
				( objectStatus "@baseboard_fab2_lib.baseboard_fab2(sch_1):page130_i22:a" )
			)
			( pin "C8C6.2"
				( objectStatus "@baseboard_fab2_lib.baseboard_fab2(sch_1):page130_i22:b" )
			)
			( pin "C2N23.1"
				( objectStatus "@baseboard_fab2_lib.baseboard_fab2(sch_1):page130_i24:a" )
			)
			( pin "C2N23.2"
				( objectStatus "@baseboard_fab2_lib.baseboard_fab2(sch_1):page130_i24:b" )
			)
			( pin "C2N14.1"
				( objectStatus "@baseboard_fab2_lib.baseboard_fab2(sch_1):page130_i25:a" )
			)
			( pin "C2N14.2"
				( objectStatus "@baseboard_fab2_lib.baseboard_fab2(sch_1):page130_i25:b" )
			)
			( pin "C2N17.1"
				( objectStatus "@baseboard_fab2_lib.baseboard_fab2(sch_1):page130_i28:a" )
			)
			( pin "C2N17.2"
				( objectStatus "@baseboard_fab2_lib.baseboard_fab2(sch_1):page130_i28:b" )
			)
			( pin "C2N18.1"
				( objectStatus "@baseboard_fab2_lib.baseboard_fab2(sch_1):page130_i29:a" )
			)
			( pin "C2N18.2"
				( objectStatus "@baseboard_fab2_lib.baseboard_fab2(sch_1):page130_i29:b" )
			)
			( pin "C8B2.1"
				( objectStatus "@baseboard_fab2_lib.baseboard_fab2(sch_1):page130_i30:a" )
			)
			( pin "C8B2.2"
				( objectStatus "@baseboard_fab2_lib.baseboard_fab2(sch_1):page130_i30:b" )
			)
			( pin "C8B3.1"
				( objectStatus "@baseboard_fab2_lib.baseboard_fab2(sch_1):page130_i32:a" )
			)
			( pin "C8B3.2"
				( objectStatus "@baseboard_fab2_lib.baseboard_fab2(sch_1):page130_i32:b" )
			)
			( pin "C2N25.1"
				( objectStatus "@baseboard_fab2_lib.baseboard_fab2(sch_1):page130_i34:a" )
			)
			( pin "C2N25.2"
				( objectStatus "@baseboard_fab2_lib.baseboard_fab2(sch_1):page130_i34:b" )
			)
			( pin "C2M16.1"
				( objectStatus "@baseboard_fab2_lib.baseboard_fab2(sch_1):page130_i37:a" )
			)
			( pin "C2M16.2"
				( objectStatus "@baseboard_fab2_lib.baseboard_fab2(sch_1):page130_i37:b" )
			)
			( pin "C7D3.1"
				( objectStatus "@baseboard_fab2_lib.baseboard_fab2(sch_1):page130_i38:a" )
			)
			( pin "C7D3.2"
				( objectStatus "@baseboard_fab2_lib.baseboard_fab2(sch_1):page130_i38:b" )
			)
			( pin "C8B4.1"
				( objectStatus "@baseboard_fab2_lib.baseboard_fab2(sch_1):page130_i39:a" )
			)
			( pin "C8B4.2"
				( objectStatus "@baseboard_fab2_lib.baseboard_fab2(sch_1):page130_i39:b" )
			)
			( pin "C8B1.1"
				( objectStatus "@baseboard_fab2_lib.baseboard_fab2(sch_1):page130_i41:a" )
			)
			( pin "C8B1.2"
				( objectStatus "@baseboard_fab2_lib.baseboard_fab2(sch_1):page130_i41:b" )
			)
			( pin "C3N23.1"
				( objectStatus "@baseboard_fab2_lib.baseboard_fab2(sch_1):page130_i42:a" )
			)
			( pin "C3N23.2"
				( objectStatus "@baseboard_fab2_lib.baseboard_fab2(sch_1):page130_i42:b" )
			)
			( pin "C2M1.1"
				( objectStatus "@baseboard_fab2_lib.baseboard_fab2(sch_1):page130_i43:a" )
			)
			( pin "C2M1.2"
				( objectStatus "@baseboard_fab2_lib.baseboard_fab2(sch_1):page130_i43:b" )
			)
			( pin "C2M2.1"
				( objectStatus "@baseboard_fab2_lib.baseboard_fab2(sch_1):page130_i45:a" )
			)
			( pin "C2M2.2"
				( objectStatus "@baseboard_fab2_lib.baseboard_fab2(sch_1):page130_i45:b" )
			)
			( pin "C2N15.1"
				( objectStatus "@baseboard_fab2_lib.baseboard_fab2(sch_1):page130_i47:a" )
			)
			( pin "C2N15.2"
				( objectStatus "@baseboard_fab2_lib.baseboard_fab2(sch_1):page130_i47:b" )
			)
			( pin "C3N21.1"
				( objectStatus "@baseboard_fab2_lib.baseboard_fab2(sch_1):page130_i49:a" )
			)
			( pin "C3N21.2"
				( objectStatus "@baseboard_fab2_lib.baseboard_fab2(sch_1):page130_i49:b" )
			)
			( pin "C3N25.1"
				( objectStatus "@baseboard_fab2_lib.baseboard_fab2(sch_1):page130_i50:a" )
			)
			( pin "C3N25.2"
				( objectStatus "@baseboard_fab2_lib.baseboard_fab2(sch_1):page130_i50:b" )
			)
			( pin "C2N16.1"
				( objectStatus "@baseboard_fab2_lib.baseboard_fab2(sch_1):page130_i52:a" )
			)
			( pin "C2N16.2"
				( objectStatus "@baseboard_fab2_lib.baseboard_fab2(sch_1):page130_i52:b" )
			)
			( pin "C3N22.1"
				( objectStatus "@baseboard_fab2_lib.baseboard_fab2(sch_1):page130_i53:a" )
			)
			( pin "C3N22.2"
				( objectStatus "@baseboard_fab2_lib.baseboard_fab2(sch_1):page130_i53:b" )
			)
			( pin "C7B15.1"
				( objectStatus "@baseboard_fab2_lib.baseboard_fab2(sch_1):page131_i1:a" )
			)
			( pin "C7B15.2"
				( objectStatus "@baseboard_fab2_lib.baseboard_fab2(sch_1):page131_i1:b" )
			)
			( pin "C7B19.1"
				( objectStatus "@baseboard_fab2_lib.baseboard_fab2(sch_1):page131_i2:a" )
			)
			( pin "C7B19.2"
				( objectStatus "@baseboard_fab2_lib.baseboard_fab2(sch_1):page131_i2:b" )
			)
			( pin "C7B16.1"
				( objectStatus "@baseboard_fab2_lib.baseboard_fab2(sch_1):page131_i3:a" )
			)
			( pin "C7B16.2"
				( objectStatus "@baseboard_fab2_lib.baseboard_fab2(sch_1):page131_i3:b" )
			)
			( pin "C7B21.1"
				( objectStatus "@baseboard_fab2_lib.baseboard_fab2(sch_1):page131_i4:a" )
			)
			( pin "C7B21.2"
				( objectStatus "@baseboard_fab2_lib.baseboard_fab2(sch_1):page131_i4:b" )
			)
			( pin "C7B20.1"
				( objectStatus "@baseboard_fab2_lib.baseboard_fab2(sch_1):page131_i6:a" )
			)
			( pin "C7B20.2"
				( objectStatus "@baseboard_fab2_lib.baseboard_fab2(sch_1):page131_i6:b" )
			)
			( pin "C7B23.1"
				( objectStatus "@baseboard_fab2_lib.baseboard_fab2(sch_1):page131_i7:a" )
			)
			( pin "C7B23.2"
				( objectStatus "@baseboard_fab2_lib.baseboard_fab2(sch_1):page131_i7:b" )
			)
			( pin "C8B10.1"
				( objectStatus "@baseboard_fab2_lib.baseboard_fab2(sch_1):page131_i8:a" )
			)
			( pin "C8B10.2"
				( objectStatus "@baseboard_fab2_lib.baseboard_fab2(sch_1):page131_i8:b" )
			)
			( pin "C7B22.1"
				( objectStatus "@baseboard_fab2_lib.baseboard_fab2(sch_1):page131_i10:a" )
			)
			( pin "C7B22.2"
				( objectStatus "@baseboard_fab2_lib.baseboard_fab2(sch_1):page131_i10:b" )
			)
			( pin "C7B24.1"
				( objectStatus "@baseboard_fab2_lib.baseboard_fab2(sch_1):page131_i11:a" )
			)
			( pin "C7B24.2"
				( objectStatus "@baseboard_fab2_lib.baseboard_fab2(sch_1):page131_i11:b" )
			)
			( pin "C7B18.1"
				( objectStatus "@baseboard_fab2_lib.baseboard_fab2(sch_1):page131_i12:a" )
			)
			( pin "C7B18.2"
				( objectStatus "@baseboard_fab2_lib.baseboard_fab2(sch_1):page131_i12:b" )
			)
			( pin "C8B9.1"
				( objectStatus "@baseboard_fab2_lib.baseboard_fab2(sch_1):page131_i14:a" )
			)
			( pin "C8B9.2"
				( objectStatus "@baseboard_fab2_lib.baseboard_fab2(sch_1):page131_i14:b" )
			)
			( pin "C8B11.1"
				( objectStatus "@baseboard_fab2_lib.baseboard_fab2(sch_1):page131_i15:a" )
			)
			( pin "C8B11.2"
				( objectStatus "@baseboard_fab2_lib.baseboard_fab2(sch_1):page131_i15:b" )
			)
			( pin "C8B14.1"
				( objectStatus "@baseboard_fab2_lib.baseboard_fab2(sch_1):page131_i16:a" )
			)
			( pin "C8B14.2"
				( objectStatus "@baseboard_fab2_lib.baseboard_fab2(sch_1):page131_i16:b" )
			)
			( pin "C7B17.1"
				( objectStatus "@baseboard_fab2_lib.baseboard_fab2(sch_1):page131_i18:a" )
			)
			( pin "C7B17.2"
				( objectStatus "@baseboard_fab2_lib.baseboard_fab2(sch_1):page131_i18:b" )
			)
			( pin "C8B13.1"
				( objectStatus "@baseboard_fab2_lib.baseboard_fab2(sch_1):page131_i20:a" )
			)
			( pin "C8B13.2"
				( objectStatus "@baseboard_fab2_lib.baseboard_fab2(sch_1):page131_i20:b" )
			)
			( pin "C8B16.1"
				( objectStatus "@baseboard_fab2_lib.baseboard_fab2(sch_1):page131_i22:a" )
			)
			( pin "C8B16.2"
				( objectStatus "@baseboard_fab2_lib.baseboard_fab2(sch_1):page131_i22:b" )
			)
			( pin "C8B15.1"
				( objectStatus "@baseboard_fab2_lib.baseboard_fab2(sch_1):page131_i24:a" )
			)
			( pin "C8B15.2"
				( objectStatus "@baseboard_fab2_lib.baseboard_fab2(sch_1):page131_i24:b" )
			)
			( pin "C2M22.1"
				( objectStatus "@baseboard_fab2_lib.baseboard_fab2(sch_1):page131_i27:a" )
			)
			( pin "C2M22.2"
				( objectStatus "@baseboard_fab2_lib.baseboard_fab2(sch_1):page131_i27:b" )
			)
			( pin "C2M21.1"
				( objectStatus "@baseboard_fab2_lib.baseboard_fab2(sch_1):page131_i28:a" )
			)
			( pin "C2M21.2"
				( objectStatus "@baseboard_fab2_lib.baseboard_fab2(sch_1):page131_i28:b" )
			)
			( pin "C2M18.1"
				( objectStatus "@baseboard_fab2_lib.baseboard_fab2(sch_1):page131_i29:a" )
			)
			( pin "C2M18.2"
				( objectStatus "@baseboard_fab2_lib.baseboard_fab2(sch_1):page131_i29:b" )
			)
			( pin "C2M19.1"
				( objectStatus "@baseboard_fab2_lib.baseboard_fab2(sch_1):page131_i31:a" )
			)
			( pin "C2M19.2"
				( objectStatus "@baseboard_fab2_lib.baseboard_fab2(sch_1):page131_i31:b" )
			)
			( pin "C3M38.1"
				( objectStatus "@baseboard_fab2_lib.baseboard_fab2(sch_1):page131_i32:a" )
			)
			( pin "C3M38.2"
				( objectStatus "@baseboard_fab2_lib.baseboard_fab2(sch_1):page131_i32:b" )
			)
			( pin "C2M17.1"
				( objectStatus "@baseboard_fab2_lib.baseboard_fab2(sch_1):page131_i34:a" )
			)
			( pin "C2M17.2"
				( objectStatus "@baseboard_fab2_lib.baseboard_fab2(sch_1):page131_i34:b" )
			)
			( pin "C2M11.1"
				( objectStatus "@baseboard_fab2_lib.baseboard_fab2(sch_1):page131_i35:a" )
			)
			( pin "C2M11.2"
				( objectStatus "@baseboard_fab2_lib.baseboard_fab2(sch_1):page131_i35:b" )
			)
			( pin "C8A13.1"
				( objectStatus "@baseboard_fab2_lib.baseboard_fab2(sch_1):page131_i37:a" )
			)
			( pin "C8A13.2"
				( objectStatus "@baseboard_fab2_lib.baseboard_fab2(sch_1):page131_i37:b" )
			)
			( pin "C2M20.1"
				( objectStatus "@baseboard_fab2_lib.baseboard_fab2(sch_1):page131_i39:a" )
			)
			( pin "C2M20.2"
				( objectStatus "@baseboard_fab2_lib.baseboard_fab2(sch_1):page131_i39:b" )
			)
			( pin "C2N13.1"
				( objectStatus "@baseboard_fab2_lib.baseboard_fab2(sch_1):page131_i40:a" )
			)
			( pin "C2N13.2"
				( objectStatus "@baseboard_fab2_lib.baseboard_fab2(sch_1):page131_i40:b" )
			)
			( pin "C2N2.1"
				( objectStatus "@baseboard_fab2_lib.baseboard_fab2(sch_1):page131_i41:a" )
			)
			( pin "C2N2.2"
				( objectStatus "@baseboard_fab2_lib.baseboard_fab2(sch_1):page131_i41:b" )
			)
			( pin "C3M43.1"
				( objectStatus "@baseboard_fab2_lib.baseboard_fab2(sch_1):page131_i42:a" )
			)
			( pin "C3M43.2"
				( objectStatus "@baseboard_fab2_lib.baseboard_fab2(sch_1):page131_i42:b" )
			)
			( pin "C2N7.1"
				( objectStatus "@baseboard_fab2_lib.baseboard_fab2(sch_1):page131_i43:a" )
			)
			( pin "C2N7.2"
				( objectStatus "@baseboard_fab2_lib.baseboard_fab2(sch_1):page131_i43:b" )
			)
			( pin "C3M39.1"
				( objectStatus "@baseboard_fab2_lib.baseboard_fab2(sch_1):page131_i44:a" )
			)
			( pin "C3M39.2"
				( objectStatus "@baseboard_fab2_lib.baseboard_fab2(sch_1):page131_i44:b" )
			)
			( pin "C3M42.1"
				( objectStatus "@baseboard_fab2_lib.baseboard_fab2(sch_1):page131_i45:a" )
			)
			( pin "C3M42.2"
				( objectStatus "@baseboard_fab2_lib.baseboard_fab2(sch_1):page131_i45:b" )
			)
			( pin "C2N8.1"
				( objectStatus "@baseboard_fab2_lib.baseboard_fab2(sch_1):page131_i47:a" )
			)
			( pin "C2N8.2"
				( objectStatus "@baseboard_fab2_lib.baseboard_fab2(sch_1):page131_i47:b" )
			)
			( pin "C2M13.1"
				( objectStatus "@baseboard_fab2_lib.baseboard_fab2(sch_1):page131_i48:a" )
			)
			( pin "C2M13.2"
				( objectStatus "@baseboard_fab2_lib.baseboard_fab2(sch_1):page131_i48:b" )
			)
			( pin "C2N10.1"
				( objectStatus "@baseboard_fab2_lib.baseboard_fab2(sch_1):page131_i50:a" )
			)
			( pin "C2N10.2"
				( objectStatus "@baseboard_fab2_lib.baseboard_fab2(sch_1):page131_i50:b" )
			)
			( pin "C2M12.1"
				( objectStatus "@baseboard_fab2_lib.baseboard_fab2(sch_1):page131_i52:a" )
			)
			( pin "C2M12.2"
				( objectStatus "@baseboard_fab2_lib.baseboard_fab2(sch_1):page131_i52:b" )
			)
			( pin "C3L25.1"
				( objectStatus "@baseboard_fab2_lib.baseboard_fab2(sch_1):page132_i1:a" )
			)
			( pin "C3L25.2"
				( objectStatus "@baseboard_fab2_lib.baseboard_fab2(sch_1):page132_i1:b" )
			)
			( pin "C3M7.1"
				( objectStatus "@baseboard_fab2_lib.baseboard_fab2(sch_1):page132_i2:a" )
			)
			( pin "C3M7.2"
				( objectStatus "@baseboard_fab2_lib.baseboard_fab2(sch_1):page132_i2:b" )
			)
			( pin "C3L26.1"
				( objectStatus "@baseboard_fab2_lib.baseboard_fab2(sch_1):page132_i3:a" )
			)
			( pin "C3L26.2"
				( objectStatus "@baseboard_fab2_lib.baseboard_fab2(sch_1):page132_i3:b" )
			)
			( pin "C3L27.1"
				( objectStatus "@baseboard_fab2_lib.baseboard_fab2(sch_1):page132_i4:a" )
			)
			( pin "C3L27.2"
				( objectStatus "@baseboard_fab2_lib.baseboard_fab2(sch_1):page132_i4:b" )
			)
			( pin "C3M6.1"
				( objectStatus "@baseboard_fab2_lib.baseboard_fab2(sch_1):page132_i6:a" )
			)
			( pin "C3M6.2"
				( objectStatus "@baseboard_fab2_lib.baseboard_fab2(sch_1):page132_i6:b" )
			)
			( pin "C7C9.1"
				( objectStatus "@baseboard_fab2_lib.baseboard_fab2(sch_1):page132_i7:a" )
			)
			( pin "C7C9.2"
				( objectStatus "@baseboard_fab2_lib.baseboard_fab2(sch_1):page132_i7:b" )
			)
			( pin "C3N27.1"
				( objectStatus "@baseboard_fab2_lib.baseboard_fab2(sch_1):page132_i8:a" )
			)
			( pin "C3N27.2"
				( objectStatus "@baseboard_fab2_lib.baseboard_fab2(sch_1):page132_i8:b" )
			)
			( pin "C3N30.1"
				( objectStatus "@baseboard_fab2_lib.baseboard_fab2(sch_1):page132_i9:a" )
			)
			( pin "C3N30.2"
				( objectStatus "@baseboard_fab2_lib.baseboard_fab2(sch_1):page132_i9:b" )
			)
			( pin "C7A36.1"
				( objectStatus "@baseboard_fab2_lib.baseboard_fab2(sch_1):page132_i11:a" )
			)
			( pin "C7A36.2"
				( objectStatus "@baseboard_fab2_lib.baseboard_fab2(sch_1):page132_i11:b" )
			)
			( pin "C3N12.1"
				( objectStatus "@baseboard_fab2_lib.baseboard_fab2(sch_1):page132_i12:a" )
			)
			( pin "C3N12.2"
				( objectStatus "@baseboard_fab2_lib.baseboard_fab2(sch_1):page132_i12:b" )
			)
			( pin "C3N10.1"
				( objectStatus "@baseboard_fab2_lib.baseboard_fab2(sch_1):page132_i13:a" )
			)
			( pin "C3N10.2"
				( objectStatus "@baseboard_fab2_lib.baseboard_fab2(sch_1):page132_i13:b" )
			)
			( pin "C3N24.1"
				( objectStatus "@baseboard_fab2_lib.baseboard_fab2(sch_1):page132_i16:a" )
			)
			( pin "C3N24.2"
				( objectStatus "@baseboard_fab2_lib.baseboard_fab2(sch_1):page132_i16:b" )
			)
			( pin "C3N28.1"
				( objectStatus "@baseboard_fab2_lib.baseboard_fab2(sch_1):page132_i17:a" )
			)
			( pin "C3N28.2"
				( objectStatus "@baseboard_fab2_lib.baseboard_fab2(sch_1):page132_i17:b" )
			)
			( pin "C3N11.1"
				( objectStatus "@baseboard_fab2_lib.baseboard_fab2(sch_1):page132_i19:a" )
			)
			( pin "C3N11.2"
				( objectStatus "@baseboard_fab2_lib.baseboard_fab2(sch_1):page132_i19:b" )
			)
			( pin "C3N31.1"
				( objectStatus "@baseboard_fab2_lib.baseboard_fab2(sch_1):page132_i20:a" )
			)
			( pin "C3N31.2"
				( objectStatus "@baseboard_fab2_lib.baseboard_fab2(sch_1):page132_i20:b" )
			)
			( pin "C7A33.1"
				( objectStatus "@baseboard_fab2_lib.baseboard_fab2(sch_1):page132_i23:a" )
			)
			( pin "C7A33.2"
				( objectStatus "@baseboard_fab2_lib.baseboard_fab2(sch_1):page132_i23:b" )
			)
			( pin "C7B4.1"
				( objectStatus "@baseboard_fab2_lib.baseboard_fab2(sch_1):page132_i24:a" )
			)
			( pin "C7B4.2"
				( objectStatus "@baseboard_fab2_lib.baseboard_fab2(sch_1):page132_i24:b" )
			)
			( pin "C2N9.1"
				( objectStatus "@baseboard_fab2_lib.baseboard_fab2(sch_1):page132_i26:a" )
			)
			( pin "C2N9.2"
				( objectStatus "@baseboard_fab2_lib.baseboard_fab2(sch_1):page132_i26:b" )
			)
			( pin "C2N3.1"
				( objectStatus "@baseboard_fab2_lib.baseboard_fab2(sch_1):page132_i27:a" )
			)
			( pin "C2N3.2"
				( objectStatus "@baseboard_fab2_lib.baseboard_fab2(sch_1):page132_i27:b" )
			)
			( pin "C2N4.1"
				( objectStatus "@baseboard_fab2_lib.baseboard_fab2(sch_1):page132_i28:a" )
			)
			( pin "C2N4.2"
				( objectStatus "@baseboard_fab2_lib.baseboard_fab2(sch_1):page132_i28:b" )
			)
			( pin "C2N12.1"
				( objectStatus "@baseboard_fab2_lib.baseboard_fab2(sch_1):page132_i29:a" )
			)
			( pin "C2N12.2"
				( objectStatus "@baseboard_fab2_lib.baseboard_fab2(sch_1):page132_i29:b" )
			)
			( pin "C2N11.1"
				( objectStatus "@baseboard_fab2_lib.baseboard_fab2(sch_1):page132_i30:a" )
			)
			( pin "C2N11.2"
				( objectStatus "@baseboard_fab2_lib.baseboard_fab2(sch_1):page132_i30:b" )
			)
			( pin "C3N19.1"
				( objectStatus "@baseboard_fab2_lib.baseboard_fab2(sch_1):page132_i31:a" )
			)
			( pin "C3N19.2"
				( objectStatus "@baseboard_fab2_lib.baseboard_fab2(sch_1):page132_i31:b" )
			)
			( pin "C3N3.1"
				( objectStatus "@baseboard_fab2_lib.baseboard_fab2(sch_1):page132_i32:a" )
			)
			( pin "C3N3.2"
				( objectStatus "@baseboard_fab2_lib.baseboard_fab2(sch_1):page132_i32:b" )
			)
			( pin "C3N1.1"
				( objectStatus "@baseboard_fab2_lib.baseboard_fab2(sch_1):page132_i34:a" )
			)
			( pin "C3N1.2"
				( objectStatus "@baseboard_fab2_lib.baseboard_fab2(sch_1):page132_i34:b" )
			)
			( pin "C3N7.1"
				( objectStatus "@baseboard_fab2_lib.baseboard_fab2(sch_1):page132_i35:a" )
			)
			( pin "C3N7.2"
				( objectStatus "@baseboard_fab2_lib.baseboard_fab2(sch_1):page132_i35:b" )
			)
			( pin "C3N16.1"
				( objectStatus "@baseboard_fab2_lib.baseboard_fab2(sch_1):page132_i36:a" )
			)
			( pin "C3N16.2"
				( objectStatus "@baseboard_fab2_lib.baseboard_fab2(sch_1):page132_i36:b" )
			)
			( pin "C7A32.1"
				( objectStatus "@baseboard_fab2_lib.baseboard_fab2(sch_1):page132_i38:a" )
			)
			( pin "C7A32.2"
				( objectStatus "@baseboard_fab2_lib.baseboard_fab2(sch_1):page132_i38:b" )
			)
			( pin "C7A31.1"
				( objectStatus "@baseboard_fab2_lib.baseboard_fab2(sch_1):page132_i40:a" )
			)
			( pin "C7A31.2"
				( objectStatus "@baseboard_fab2_lib.baseboard_fab2(sch_1):page132_i40:b" )
			)
			( pin "C3N18.1"
				( objectStatus "@baseboard_fab2_lib.baseboard_fab2(sch_1):page132_i42:a" )
			)
			( pin "C3N18.2"
				( objectStatus "@baseboard_fab2_lib.baseboard_fab2(sch_1):page132_i42:b" )
			)
			( pin "C3N2.1"
				( objectStatus "@baseboard_fab2_lib.baseboard_fab2(sch_1):page132_i43:a" )
			)
			( pin "C3N2.2"
				( objectStatus "@baseboard_fab2_lib.baseboard_fab2(sch_1):page132_i43:b" )
			)
			( pin "C3N6.1"
				( objectStatus "@baseboard_fab2_lib.baseboard_fab2(sch_1):page132_i44:a" )
			)
			( pin "C3N6.2"
				( objectStatus "@baseboard_fab2_lib.baseboard_fab2(sch_1):page132_i44:b" )
			)
			( pin "C3N17.1"
				( objectStatus "@baseboard_fab2_lib.baseboard_fab2(sch_1):page132_i45:a" )
			)
			( pin "C3N17.2"
				( objectStatus "@baseboard_fab2_lib.baseboard_fab2(sch_1):page132_i45:b" )
			)
			( pin "C3N4.1"
				( objectStatus "@baseboard_fab2_lib.baseboard_fab2(sch_1):page132_i46:a" )
			)
			( pin "C3N4.2"
				( objectStatus "@baseboard_fab2_lib.baseboard_fab2(sch_1):page132_i46:b" )
			)
			( pin "C3N5.1"
				( objectStatus "@baseboard_fab2_lib.baseboard_fab2(sch_1):page132_i48:a" )
			)
			( pin "C3N5.2"
				( objectStatus "@baseboard_fab2_lib.baseboard_fab2(sch_1):page132_i48:b" )
			)
			( pin "C3N15.1"
				( objectStatus "@baseboard_fab2_lib.baseboard_fab2(sch_1):page132_i49:a" )
			)
			( pin "C3N15.2"
				( objectStatus "@baseboard_fab2_lib.baseboard_fab2(sch_1):page132_i49:b" )
			)
			( pin "C3N20.1"
				( objectStatus "@baseboard_fab2_lib.baseboard_fab2(sch_1):page132_i51:a" )
			)
			( pin "C3N20.2"
				( objectStatus "@baseboard_fab2_lib.baseboard_fab2(sch_1):page132_i51:b" )
			)
			( pin "C3L23.1"
				( objectStatus "@baseboard_fab2_lib.baseboard_fab2(sch_1):page132_i52:a" )
			)
			( pin "C3L23.2"
				( objectStatus "@baseboard_fab2_lib.baseboard_fab2(sch_1):page132_i52:b" )
			)
			( pin "C3L22.1"
				( objectStatus "@baseboard_fab2_lib.baseboard_fab2(sch_1):page132_i54:a" )
			)
			( pin "C3L22.2"
				( objectStatus "@baseboard_fab2_lib.baseboard_fab2(sch_1):page132_i54:b" )
			)
			( pin "C3L24.1"
				( objectStatus "@baseboard_fab2_lib.baseboard_fab2(sch_1):page132_i56:a" )
			)
			( pin "C3L24.2"
				( objectStatus "@baseboard_fab2_lib.baseboard_fab2(sch_1):page132_i56:b" )
			)
			( pin "R3N3.1"
				( objectStatus "@baseboard_fab2_lib.baseboard_fab2(sch_1):page133_i120:a" )
			)
			( pin "R3N3.2"
				( objectStatus "@baseboard_fab2_lib.baseboard_fab2(sch_1):page133_i120:b" )
			)
			( pin "R2N12.1"
				( objectStatus "@baseboard_fab2_lib.baseboard_fab2(sch_1):page133_i122:a" )
			)
			( pin "R2N12.2"
				( objectStatus "@baseboard_fab2_lib.baseboard_fab2(sch_1):page133_i122:b" )
			)
			( pin "R7D8.1"
				( objectStatus "@baseboard_fab2_lib.baseboard_fab2(sch_1):page133_i200:a" )
			)
			( pin "R7D8.2"
				( objectStatus "@baseboard_fab2_lib.baseboard_fab2(sch_1):page133_i200:b" )
			)
			( pin "R7D10.1"
				( objectStatus "@baseboard_fab2_lib.baseboard_fab2(sch_1):page133_i202:a" )
			)
			( pin "R7D10.2"
				( objectStatus "@baseboard_fab2_lib.baseboard_fab2(sch_1):page133_i202:b" )
			)
			( pin "R7D12.1"
				( objectStatus "@baseboard_fab2_lib.baseboard_fab2(sch_1):page133_i237:a" )
			)
			( pin "R7D12.2"
				( objectStatus "@baseboard_fab2_lib.baseboard_fab2(sch_1):page133_i237:b" )
			)
			( pin "R7D3.1"
				( objectStatus "@baseboard_fab2_lib.baseboard_fab2(sch_1):page133_i243:a" )
			)
			( pin "R7D3.2"
				( objectStatus "@baseboard_fab2_lib.baseboard_fab2(sch_1):page133_i243:b" )
			)
			( pin "R7D4.1"
				( objectStatus "@baseboard_fab2_lib.baseboard_fab2(sch_1):page133_i245:a" )
			)
			( pin "R7D4.2"
				( objectStatus "@baseboard_fab2_lib.baseboard_fab2(sch_1):page133_i245:b" )
			)
			( pin "R2N16.1"
				( objectStatus "@baseboard_fab2_lib.baseboard_fab2(sch_1):page133_i247:a" )
			)
			( pin "R2N16.2"
				( objectStatus "@baseboard_fab2_lib.baseboard_fab2(sch_1):page133_i247:b" )
			)
			( pin "R2R5.1"
				( objectStatus "@baseboard_fab2_lib.baseboard_fab2(sch_1):page133_i258:a" )
			)
			( pin "R2R5.2"
				( objectStatus "@baseboard_fab2_lib.baseboard_fab2(sch_1):page133_i258:b" )
			)
			( pin "R2N9.1"
				( objectStatus "@baseboard_fab2_lib.baseboard_fab2(sch_1):page133_i267:a" )
			)
			( pin "R2N9.2"
				( objectStatus "@baseboard_fab2_lib.baseboard_fab2(sch_1):page133_i267:b" )
			)
			( pin "R8B23.1"
				( objectStatus "@baseboard_fab2_lib.baseboard_fab2(sch_1):page133_i280:a" )
			)
			( pin "R8B23.2"
				( objectStatus "@baseboard_fab2_lib.baseboard_fab2(sch_1):page133_i280:b" )
			)
			( pin "R8B30.1"
				( objectStatus "@baseboard_fab2_lib.baseboard_fab2(sch_1):page133_i282:a" )
			)
			( pin "R8B30.2"
				( objectStatus "@baseboard_fab2_lib.baseboard_fab2(sch_1):page133_i282:b" )
			)
			( pin "R2M4.1"
				( objectStatus "@baseboard_fab2_lib.baseboard_fab2(sch_1):page133_i284:a" )
			)
			( pin "R2M4.2"
				( objectStatus "@baseboard_fab2_lib.baseboard_fab2(sch_1):page133_i284:b" )
			)
			( pin "R8C4.1"
				( objectStatus "@baseboard_fab2_lib.baseboard_fab2(sch_1):page133_i286:a" )
			)
			( pin "R8C4.2"
				( objectStatus "@baseboard_fab2_lib.baseboard_fab2(sch_1):page133_i286:b" )
			)
			( pin "R7B6.1"
				( objectStatus "@baseboard_fab2_lib.baseboard_fab2(sch_1):page133_i295:a" )
			)
			( pin "R7B6.2"
				( objectStatus "@baseboard_fab2_lib.baseboard_fab2(sch_1):page133_i295:b" )
			)
			( pin "R7C8.1"
				( objectStatus "@baseboard_fab2_lib.baseboard_fab2(sch_1):page133_i296:a" )
			)
			( pin "R7C8.2"
				( objectStatus "@baseboard_fab2_lib.baseboard_fab2(sch_1):page133_i296:b" )
			)
			( pin "R7C5.1"
				( objectStatus "@baseboard_fab2_lib.baseboard_fab2(sch_1):page133_i297:a" )
			)
			( pin "R7C5.2"
				( objectStatus "@baseboard_fab2_lib.baseboard_fab2(sch_1):page133_i297:b" )
			)
			( pin "R8D14.1"
				( objectStatus "@baseboard_fab2_lib.baseboard_fab2(sch_1):page133_i301:a" )
			)
			( pin "R8D14.2"
				( objectStatus "@baseboard_fab2_lib.baseboard_fab2(sch_1):page133_i301:b" )
			)
			( pin "R8C6.1"
				( objectStatus "@baseboard_fab2_lib.baseboard_fab2(sch_1):page133_i303:a" )
			)
			( pin "R8C6.2"
				( objectStatus "@baseboard_fab2_lib.baseboard_fab2(sch_1):page133_i303:b" )
			)
			( pin "R8C2.1"
				( objectStatus "@baseboard_fab2_lib.baseboard_fab2(sch_1):page133_i304:a" )
			)
			( pin "R8C2.2"
				( objectStatus "@baseboard_fab2_lib.baseboard_fab2(sch_1):page133_i304:b" )
			)
			( pin "R7D6.1"
				( objectStatus "@baseboard_fab2_lib.baseboard_fab2(sch_1):page133_i306:a" )
			)
			( pin "R7D6.2"
				( objectStatus "@baseboard_fab2_lib.baseboard_fab2(sch_1):page133_i306:b" )
			)
			( pin "R8B31.1"
				( objectStatus "@baseboard_fab2_lib.baseboard_fab2(sch_1):page133_i307:a" )
			)
			( pin "R8B31.2"
				( objectStatus "@baseboard_fab2_lib.baseboard_fab2(sch_1):page133_i307:b" )
			)
			( pin "R2N7.1"
				( objectStatus "@baseboard_fab2_lib.baseboard_fab2(sch_1):page133_i309:a" )
			)
			( pin "R2N7.2"
				( objectStatus "@baseboard_fab2_lib.baseboard_fab2(sch_1):page133_i309:b" )
			)
			( pin "R3P8.1"
				( objectStatus "@baseboard_fab2_lib.baseboard_fab2(sch_1):page133_i322:a" )
			)
			( pin "R3P8.2"
				( objectStatus "@baseboard_fab2_lib.baseboard_fab2(sch_1):page133_i322:b" )
			)
			( pin "R8C1.1"
				( objectStatus "@baseboard_fab2_lib.baseboard_fab2(sch_1):page133_i326:a" )
			)
			( pin "R8C1.2"
				( objectStatus "@baseboard_fab2_lib.baseboard_fab2(sch_1):page133_i326:b" )
			)
			( pin "R8C7.1"
				( objectStatus "@baseboard_fab2_lib.baseboard_fab2(sch_1):page133_i327:a" )
			)
			( pin "R8C7.2"
				( objectStatus "@baseboard_fab2_lib.baseboard_fab2(sch_1):page133_i327:b" )
			)
			( pin "R7D7.1"
				( objectStatus "@baseboard_fab2_lib.baseboard_fab2(sch_1):page133_i331:a" )
			)
			( pin "R7D7.2"
				( objectStatus "@baseboard_fab2_lib.baseboard_fab2(sch_1):page133_i331:b" )
			)
			( pin "R7D2.1"
				( objectStatus "@baseboard_fab2_lib.baseboard_fab2(sch_1):page133_i332:a" )
			)
			( pin "R7D2.2"
				( objectStatus "@baseboard_fab2_lib.baseboard_fab2(sch_1):page133_i332:b" )
			)
			( pin "R8C25.1"
				( objectStatus "@baseboard_fab2_lib.baseboard_fab2(sch_1):page133_i333:a" )
			)
			( pin "R8C25.2"
				( objectStatus "@baseboard_fab2_lib.baseboard_fab2(sch_1):page133_i333:b" )
			)
			( pin "R2N32.1"
				( objectStatus "@baseboard_fab2_lib.baseboard_fab2(sch_1):page133_i341:a" )
			)
			( pin "R2N32.2"
				( objectStatus "@baseboard_fab2_lib.baseboard_fab2(sch_1):page133_i341:b" )
			)
			( pin "R2M8.1"
				( objectStatus "@baseboard_fab2_lib.baseboard_fab2(sch_1):page133_i349:a" )
			)
			( pin "R2M8.2"
				( objectStatus "@baseboard_fab2_lib.baseboard_fab2(sch_1):page133_i349:b" )
			)
			( pin "R2N29.1"
				( objectStatus "@baseboard_fab2_lib.baseboard_fab2(sch_1):page133_i352:a" )
			)
			( pin "R2N29.2"
				( objectStatus "@baseboard_fab2_lib.baseboard_fab2(sch_1):page133_i352:b" )
			)
			( pin "C5P29.1"
				( objectStatus "@baseboard_fab2_lib.baseboard_fab2(sch_1):page42_i220:a" )
			)
			( pin "C5P29.2"
				( objectStatus "@baseboard_fab2_lib.baseboard_fab2(sch_1):page42_i220:b" )
			)
			( pin "R7D44.1"
				( objectStatus "@baseboard_fab2_lib.baseboard_fab2(sch_1):page133_i356:a" )
			)
			( pin "R7D44.2"
				( objectStatus "@baseboard_fab2_lib.baseboard_fab2(sch_1):page133_i356:b" )
			)
			( pin "R2P22.1"
				( objectStatus "@baseboard_fab2_lib.baseboard_fab2(sch_1):page133_i360:a" )
			)
			( pin "R2P22.2"
				( objectStatus "@baseboard_fab2_lib.baseboard_fab2(sch_1):page133_i360:b" )
			)
			( pin "R8D44.1"
				( objectStatus "@baseboard_fab2_lib.baseboard_fab2(sch_1):page133_i362:a" )
			)
			( pin "R8D44.2"
				( objectStatus "@baseboard_fab2_lib.baseboard_fab2(sch_1):page133_i362:b" )
			)
			( pin "R2P17.1"
				( objectStatus "@baseboard_fab2_lib.baseboard_fab2(sch_1):page134_i3:a" )
			)
			( pin "R2P17.2"
				( objectStatus "@baseboard_fab2_lib.baseboard_fab2(sch_1):page134_i3:b" )
			)
			( pin "Q7E8.3"
				( objectStatus "@baseboard_fab2_lib.baseboard_fab2(sch_1):page95_i123:drn" )
			)
			( pin "Q7E8.1"
				( objectStatus "@baseboard_fab2_lib.baseboard_fab2(sch_1):page95_i123:gate" )
			)
			( pin "Q7E8.2"
				( objectStatus "@baseboard_fab2_lib.baseboard_fab2(sch_1):page95_i123:src" )
			)
			( pin "R7C21.1"
				( objectStatus "@baseboard_fab2_lib.baseboard_fab2(sch_1):page134_i9:a" )
			)
			( pin "R7C21.2"
				( objectStatus "@baseboard_fab2_lib.baseboard_fab2(sch_1):page134_i9:b" )
			)
			( pin "Q7E4.3"
				( objectStatus "@baseboard_fab2_lib.baseboard_fab2(sch_1):page95_i122:drn" )
			)
			( pin "Q7E4.1"
				( objectStatus "@baseboard_fab2_lib.baseboard_fab2(sch_1):page95_i122:gate" )
			)
			( pin "Q7E4.2"
				( objectStatus "@baseboard_fab2_lib.baseboard_fab2(sch_1):page95_i122:src" )
			)
			( pin "R7D18.1"
				( objectStatus "@baseboard_fab2_lib.baseboard_fab2(sch_1):page134_i11:a" )
			)
			( pin "R7D18.2"
				( objectStatus "@baseboard_fab2_lib.baseboard_fab2(sch_1):page134_i11:b" )
			)
			( pin "R2P19.1"
				( objectStatus "@baseboard_fab2_lib.baseboard_fab2(sch_1):page135_i107:a" )
			)
			( pin "R2P19.2"
				( objectStatus "@baseboard_fab2_lib.baseboard_fab2(sch_1):page135_i107:b" )
			)
			( pin "R2N23.1"
				( objectStatus "@baseboard_fab2_lib.baseboard_fab2(sch_1):page135_i112:a" )
			)
			( pin "R2N23.2"
				( objectStatus "@baseboard_fab2_lib.baseboard_fab2(sch_1):page135_i112:b" )
			)
			( pin "R2N24.1"
				( objectStatus "@baseboard_fab2_lib.baseboard_fab2(sch_1):page135_i113:a" )
			)
			( pin "R2N24.2"
				( objectStatus "@baseboard_fab2_lib.baseboard_fab2(sch_1):page135_i113:b" )
			)
			( pin "R9A12.1"
				( objectStatus "@baseboard_fab2_lib.baseboard_fab2(sch_1):page135_i117:a" )
			)
			( pin "R9A12.2"
				( objectStatus "@baseboard_fab2_lib.baseboard_fab2(sch_1):page135_i117:b" )
			)
			( pin "R9A13.1"
				( objectStatus "@baseboard_fab2_lib.baseboard_fab2(sch_1):page135_i118:a" )
			)
			( pin "R9A13.2"
				( objectStatus "@baseboard_fab2_lib.baseboard_fab2(sch_1):page135_i118:b" )
			)
			( pin "R8D21.1"
				( objectStatus "@baseboard_fab2_lib.baseboard_fab2(sch_1):page135_i120:a" )
			)
			( pin "R8D21.2"
				( objectStatus "@baseboard_fab2_lib.baseboard_fab2(sch_1):page135_i120:b" )
			)
			( pin "R7D30.1"
				( objectStatus "@baseboard_fab2_lib.baseboard_fab2(sch_1):page135_i121:a" )
			)
			( pin "R7D30.2"
				( objectStatus "@baseboard_fab2_lib.baseboard_fab2(sch_1):page135_i121:b" )
			)
			( pin "J8G2.1"
				( objectStatus "@baseboard_fab2_lib.baseboard_fab2(sch_1):page135_i124:io1" )
			)
			( pin "J8G2.2"
				( objectStatus "@baseboard_fab2_lib.baseboard_fab2(sch_1):page135_i124:io2" )
			)
			( pin "J8G2.3"
				( objectStatus "@baseboard_fab2_lib.baseboard_fab2(sch_1):page135_i124:io3" )
			)
			( pin "J8G2.4"
				( objectStatus "@baseboard_fab2_lib.baseboard_fab2(sch_1):page135_i124:io4" )
			)
			( pin "J8G2.5"
				( objectStatus "@baseboard_fab2_lib.baseboard_fab2(sch_1):page135_i124:io5" )
			)
			( pin "J8G2.6"
				( objectStatus "@baseboard_fab2_lib.baseboard_fab2(sch_1):page135_i124:io6" )
			)
			( pin "J8G2.7"
				( objectStatus "@baseboard_fab2_lib.baseboard_fab2(sch_1):page135_i124:io7" )
			)
			( pin "J8G2.8"
				( objectStatus "@baseboard_fab2_lib.baseboard_fab2(sch_1):page135_i124:io8" )
			)
			( pin "J8G2.9"
				( objectStatus "@baseboard_fab2_lib.baseboard_fab2(sch_1):page135_i124:io9" )
			)
			( pin "J8G2.10"
				( objectStatus "@baseboard_fab2_lib.baseboard_fab2(sch_1):page135_i124:io10" )
			)
			( pin "J8G2.11"
				( objectStatus "@baseboard_fab2_lib.baseboard_fab2(sch_1):page135_i124:io11" )
			)
			( pin "J8G2.12"
				( objectStatus "@baseboard_fab2_lib.baseboard_fab2(sch_1):page135_i124:io12" )
			)
			( pin "R9A16.1"
				( objectStatus "@baseboard_fab2_lib.baseboard_fab2(sch_1):page135_i129:a" )
			)
			( pin "R9A16.2"
				( objectStatus "@baseboard_fab2_lib.baseboard_fab2(sch_1):page135_i129:b" )
			)
			( pin "J9A1.1"
				( objectStatus "@baseboard_fab2_lib.baseboard_fab2(sch_1):page135_i131:io1" )
			)
			( pin "J9A1.2"
				( objectStatus "@baseboard_fab2_lib.baseboard_fab2(sch_1):page135_i131:io2" )
			)
			( pin "J9A1.3"
				( objectStatus "@baseboard_fab2_lib.baseboard_fab2(sch_1):page135_i131:io3" )
			)
			( pin "J9A1.4"
				( objectStatus "@baseboard_fab2_lib.baseboard_fab2(sch_1):page135_i131:io4" )
			)
			( pin "R7G26.1"
				( objectStatus "@baseboard_fab2_lib.baseboard_fab2(sch_1):page136_i101:a" )
			)
			( pin "R7G26.2"
				( objectStatus "@baseboard_fab2_lib.baseboard_fab2(sch_1):page136_i101:b" )
			)
			( pin "R7G28.1"
				( objectStatus "@baseboard_fab2_lib.baseboard_fab2(sch_1):page136_i102:a" )
			)
			( pin "R7G28.2"
				( objectStatus "@baseboard_fab2_lib.baseboard_fab2(sch_1):page136_i102:b" )
			)
			( pin "R8E20.1"
				( objectStatus "@baseboard_fab2_lib.baseboard_fab2(sch_1):page136_i126:a" )
			)
			( pin "R8E20.2"
				( objectStatus "@baseboard_fab2_lib.baseboard_fab2(sch_1):page136_i126:b" )
			)
			( pin "C8E8.1"
				( objectStatus "@baseboard_fab2_lib.baseboard_fab2(sch_1):page136_i128:a" )
			)
			( pin "C8E8.2"
				( objectStatus "@baseboard_fab2_lib.baseboard_fab2(sch_1):page136_i128:b" )
			)
			( pin "U8E3.2"
				( objectStatus "@baseboard_fab2_lib.baseboard_fab2(sch_1):page136_i130:a" )
			)
			( pin "U8E3.1"
				( objectStatus "@baseboard_fab2_lib.baseboard_fab2(sch_1):page136_i130:oe" )
			)
			( pin "U8E3.4"
				( objectStatus "@baseboard_fab2_lib.baseboard_fab2(sch_1):page136_i130:y" )
			)
			( pin "R8E14.1"
				( objectStatus "@baseboard_fab2_lib.baseboard_fab2(sch_1):page136_i133:a" )
			)
			( pin "R8E14.2"
				( objectStatus "@baseboard_fab2_lib.baseboard_fab2(sch_1):page136_i133:b" )
			)
			( pin "Q8E1.3"
				( objectStatus "@baseboard_fab2_lib.baseboard_fab2(sch_1):page136_i134:drn" )
			)
			( pin "Q8E1.1"
				( objectStatus "@baseboard_fab2_lib.baseboard_fab2(sch_1):page136_i134:gate" )
			)
			( pin "Q8E1.2"
				( objectStatus "@baseboard_fab2_lib.baseboard_fab2(sch_1):page136_i134:src" )
			)
			( pin "R7G31.1"
				( objectStatus "@baseboard_fab2_lib.baseboard_fab2(sch_1):page136_i139:a" )
			)
			( pin "R7G31.2"
				( objectStatus "@baseboard_fab2_lib.baseboard_fab2(sch_1):page136_i139:b" )
			)
			( pin "R8E16.1"
				( objectStatus "@baseboard_fab2_lib.baseboard_fab2(sch_1):page136_i140:a" )
			)
			( pin "R8E16.2"
				( objectStatus "@baseboard_fab2_lib.baseboard_fab2(sch_1):page136_i140:b" )
			)
			( pin "R2N28.1"
				( objectStatus "@baseboard_fab2_lib.baseboard_fab2(sch_1):page136_i147:a" )
			)
			( pin "R2N28.2"
				( objectStatus "@baseboard_fab2_lib.baseboard_fab2(sch_1):page136_i147:b" )
			)
			( pin "R7G29.1"
				( objectStatus "@baseboard_fab2_lib.baseboard_fab2(sch_1):page136_i148:a" )
			)
			( pin "R7G29.2"
				( objectStatus "@baseboard_fab2_lib.baseboard_fab2(sch_1):page136_i148:b" )
			)
			( pin "R7G27.1"
				( objectStatus "@baseboard_fab2_lib.baseboard_fab2(sch_1):page136_i155:a" )
			)
			( pin "R7G27.2"
				( objectStatus "@baseboard_fab2_lib.baseboard_fab2(sch_1):page136_i155:b" )
			)
			( pin "R3T14.1"
				( objectStatus "@baseboard_fab2_lib.baseboard_fab2(sch_1):page136_i156:a" )
			)
			( pin "R3T14.2"
				( objectStatus "@baseboard_fab2_lib.baseboard_fab2(sch_1):page136_i156:b" )
			)
			( pin "J7G3.1"
				( objectStatus "@baseboard_fab2_lib.baseboard_fab2(sch_1):page136_i174:io1" )
			)
			( pin "J7G3.2"
				( objectStatus "@baseboard_fab2_lib.baseboard_fab2(sch_1):page136_i174:io2" )
			)
			( pin "J7G3.3"
				( objectStatus "@baseboard_fab2_lib.baseboard_fab2(sch_1):page136_i174:io3" )
			)
			( pin "J7G3.4"
				( objectStatus "@baseboard_fab2_lib.baseboard_fab2(sch_1):page136_i174:io4" )
			)
			( pin "J7G3.5"
				( objectStatus "@baseboard_fab2_lib.baseboard_fab2(sch_1):page136_i174:io5" )
			)
			( pin "J7G3.6"
				( objectStatus "@baseboard_fab2_lib.baseboard_fab2(sch_1):page136_i174:io6" )
			)
			( pin "J7G3.7"
				( objectStatus "@baseboard_fab2_lib.baseboard_fab2(sch_1):page136_i174:io7" )
			)
			( pin "J7G3.8"
				( objectStatus "@baseboard_fab2_lib.baseboard_fab2(sch_1):page136_i174:io8" )
			)
			( pin "J7G3.9"
				( objectStatus "@baseboard_fab2_lib.baseboard_fab2(sch_1):page136_i174:io9" )
			)
			( pin "J7G3.10"
				( objectStatus "@baseboard_fab2_lib.baseboard_fab2(sch_1):page136_i174:io10" )
			)
			( pin "J7G3.11"
				( objectStatus "@baseboard_fab2_lib.baseboard_fab2(sch_1):page136_i174:io11" )
			)
			( pin "J7G3.12"
				( objectStatus "@baseboard_fab2_lib.baseboard_fab2(sch_1):page136_i174:io12" )
			)
			( pin "R7C11.1"
				( objectStatus "@baseboard_fab2_lib.baseboard_fab2(sch_1):page137_i11:a" )
			)
			( pin "R7C11.2"
				( objectStatus "@baseboard_fab2_lib.baseboard_fab2(sch_1):page137_i11:b" )
			)
			( pin "R7C10.1"
				( objectStatus "@baseboard_fab2_lib.baseboard_fab2(sch_1):page137_i13:a" )
			)
			( pin "R7C10.2"
				( objectStatus "@baseboard_fab2_lib.baseboard_fab2(sch_1):page137_i13:b" )
			)
			( pin "C7C19.1"
				( objectStatus "@baseboard_fab2_lib.baseboard_fab2(sch_1):page137_i14:a" )
			)
			( pin "C7C19.2"
				( objectStatus "@baseboard_fab2_lib.baseboard_fab2(sch_1):page137_i14:b" )
			)
			( pin "R1U63.1"
				( objectStatus "@baseboard_fab2_lib.baseboard_fab2(sch_1):page137_i15:a" )
			)
			( pin "R1U63.2"
				( objectStatus "@baseboard_fab2_lib.baseboard_fab2(sch_1):page137_i15:b" )
			)
			( pin "R3N4.1"
				( objectStatus "@baseboard_fab2_lib.baseboard_fab2(sch_1):page137_i19:a" )
			)
			( pin "R3N4.2"
				( objectStatus "@baseboard_fab2_lib.baseboard_fab2(sch_1):page137_i19:b" )
			)
			( pin "C3N32.1"
				( objectStatus "@baseboard_fab2_lib.baseboard_fab2(sch_1):page137_i20:a" )
			)
			( pin "C3N32.2"
				( objectStatus "@baseboard_fab2_lib.baseboard_fab2(sch_1):page137_i20:b" )
			)
			( pin "R7C13.1"
				( objectStatus "@baseboard_fab2_lib.baseboard_fab2(sch_1):page137_i67:a" )
			)
			( pin "R7C13.2"
				( objectStatus "@baseboard_fab2_lib.baseboard_fab2(sch_1):page137_i67:b" )
			)
			( pin "R1U64.1"
				( objectStatus "@baseboard_fab2_lib.baseboard_fab2(sch_1):page137_i69:a" )
			)
			( pin "R1U64.2"
				( objectStatus "@baseboard_fab2_lib.baseboard_fab2(sch_1):page137_i69:b" )
			)
			( pin "J9G1.1"
				( objectStatus "@baseboard_fab2_lib.baseboard_fab2(sch_1):page137_i128:io1" )
			)
			( pin "J9G1.2"
				( objectStatus "@baseboard_fab2_lib.baseboard_fab2(sch_1):page137_i128:io2" )
			)
			( pin "J9G1.3"
				( objectStatus "@baseboard_fab2_lib.baseboard_fab2(sch_1):page137_i128:io3" )
			)
			( pin "J9G1.4"
				( objectStatus "@baseboard_fab2_lib.baseboard_fab2(sch_1):page137_i128:io4" )
			)
			( pin "J9G1.5"
				( objectStatus "@baseboard_fab2_lib.baseboard_fab2(sch_1):page137_i128:io5" )
			)
			( pin "J9G1.6"
				( objectStatus "@baseboard_fab2_lib.baseboard_fab2(sch_1):page137_i128:io6" )
			)
			( pin "J9G1.7"
				( objectStatus "@baseboard_fab2_lib.baseboard_fab2(sch_1):page137_i128:io7" )
			)
			( pin "J9G1.8"
				( objectStatus "@baseboard_fab2_lib.baseboard_fab2(sch_1):page137_i128:io8" )
			)
			( pin "J9G1.9"
				( objectStatus "@baseboard_fab2_lib.baseboard_fab2(sch_1):page137_i128:io9" )
			)
			( pin "J9G1.10"
				( objectStatus "@baseboard_fab2_lib.baseboard_fab2(sch_1):page137_i128:io10" )
			)
			( pin "J9G1.11"
				( objectStatus "@baseboard_fab2_lib.baseboard_fab2(sch_1):page137_i128:io11" )
			)
			( pin "J9G1.12"
				( objectStatus "@baseboard_fab2_lib.baseboard_fab2(sch_1):page137_i128:io12" )
			)
			( pin "R2T53.1"
				( objectStatus "@baseboard_fab2_lib.baseboard_fab2(sch_1):page138_i83:a" )
			)
			( pin "R2T53.2"
				( objectStatus "@baseboard_fab2_lib.baseboard_fab2(sch_1):page138_i83:b" )
			)
			( pin "R2T54.1"
				( objectStatus "@baseboard_fab2_lib.baseboard_fab2(sch_1):page138_i84:a" )
			)
			( pin "R2T54.2"
				( objectStatus "@baseboard_fab2_lib.baseboard_fab2(sch_1):page138_i84:b" )
			)
			( pin "R8D17.1"
				( objectStatus "@baseboard_fab2_lib.baseboard_fab2(sch_1):page138_i87:a" )
			)
			( pin "R8D17.2"
				( objectStatus "@baseboard_fab2_lib.baseboard_fab2(sch_1):page138_i87:b" )
			)
			( pin "R8D15.1"
				( objectStatus "@baseboard_fab2_lib.baseboard_fab2(sch_1):page138_i88:a" )
			)
			( pin "R8D15.2"
				( objectStatus "@baseboard_fab2_lib.baseboard_fab2(sch_1):page138_i88:b" )
			)
			( pin "R2N8.1"
				( objectStatus "@baseboard_fab2_lib.baseboard_fab2(sch_1):page138_i89:a" )
			)
			( pin "R2N8.2"
				( objectStatus "@baseboard_fab2_lib.baseboard_fab2(sch_1):page138_i89:b" )
			)
			( pin "R2N5.1"
				( objectStatus "@baseboard_fab2_lib.baseboard_fab2(sch_1):page138_i90:a" )
			)
			( pin "R2N5.2"
				( objectStatus "@baseboard_fab2_lib.baseboard_fab2(sch_1):page138_i90:b" )
			)
			( pin "R2U11.1"
				( objectStatus "@baseboard_fab2_lib.baseboard_fab2(sch_1):page138_i97:a" )
			)
			( pin "R2U11.2"
				( objectStatus "@baseboard_fab2_lib.baseboard_fab2(sch_1):page138_i97:b" )
			)
			( pin "R2U3.1"
				( objectStatus "@baseboard_fab2_lib.baseboard_fab2(sch_1):page138_i98:a" )
			)
			( pin "R2U3.2"
				( objectStatus "@baseboard_fab2_lib.baseboard_fab2(sch_1):page138_i98:b" )
			)
			( pin "R2U8.1"
				( objectStatus "@baseboard_fab2_lib.baseboard_fab2(sch_1):page138_i158:a" )
			)
			( pin "R2U8.2"
				( objectStatus "@baseboard_fab2_lib.baseboard_fab2(sch_1):page138_i158:b" )
			)
			( pin "R2U12.1"
				( objectStatus "@baseboard_fab2_lib.baseboard_fab2(sch_1):page138_i159:a" )
			)
			( pin "R2U12.2"
				( objectStatus "@baseboard_fab2_lib.baseboard_fab2(sch_1):page138_i159:b" )
			)
			( pin "C6W4.1"
				( objectStatus "@baseboard_fab2_lib.baseboard_fab2(sch_1):page247_i105:a" )
			)
			( pin "C6W4.2"
				( objectStatus "@baseboard_fab2_lib.baseboard_fab2(sch_1):page247_i105:b" )
			)
			( pin "R8D7.1"
				( objectStatus "@baseboard_fab2_lib.baseboard_fab2(sch_1):page138_i163:a" )
			)
			( pin "R8D7.2"
				( objectStatus "@baseboard_fab2_lib.baseboard_fab2(sch_1):page138_i163:b" )
			)
			( pin "R8D4.1"
				( objectStatus "@baseboard_fab2_lib.baseboard_fab2(sch_1):page138_i164:a" )
			)
			( pin "R8D4.2"
				( objectStatus "@baseboard_fab2_lib.baseboard_fab2(sch_1):page138_i164:b" )
			)
			( pin "R2U9.1"
				( objectStatus "@baseboard_fab2_lib.baseboard_fab2(sch_1):page138_i165:a" )
			)
			( pin "R2U9.2"
				( objectStatus "@baseboard_fab2_lib.baseboard_fab2(sch_1):page138_i165:b" )
			)
			( pin "R2U6.1"
				( objectStatus "@baseboard_fab2_lib.baseboard_fab2(sch_1):page138_i166:a" )
			)
			( pin "R2U6.2"
				( objectStatus "@baseboard_fab2_lib.baseboard_fab2(sch_1):page138_i166:b" )
			)
			( pin "R8C20.1"
				( objectStatus "@baseboard_fab2_lib.baseboard_fab2(sch_1):page138_i167:a" )
			)
			( pin "R8C20.2"
				( objectStatus "@baseboard_fab2_lib.baseboard_fab2(sch_1):page138_i167:b" )
			)
			( pin "R8C14.1"
				( objectStatus "@baseboard_fab2_lib.baseboard_fab2(sch_1):page138_i168:a" )
			)
			( pin "R8C14.2"
				( objectStatus "@baseboard_fab2_lib.baseboard_fab2(sch_1):page138_i168:b" )
			)
			( pin "R8C11.1"
				( objectStatus "@baseboard_fab2_lib.baseboard_fab2(sch_1):page138_i169:a" )
			)
			( pin "R8C11.2"
				( objectStatus "@baseboard_fab2_lib.baseboard_fab2(sch_1):page138_i169:b" )
			)
			( pin "R8C12.1"
				( objectStatus "@baseboard_fab2_lib.baseboard_fab2(sch_1):page138_i170:a" )
			)
			( pin "R8C12.2"
				( objectStatus "@baseboard_fab2_lib.baseboard_fab2(sch_1):page138_i170:b" )
			)
			( pin "R2N20.1"
				( objectStatus "@baseboard_fab2_lib.baseboard_fab2(sch_1):page138_i171:a" )
			)
			( pin "R2N20.2"
				( objectStatus "@baseboard_fab2_lib.baseboard_fab2(sch_1):page138_i171:b" )
			)
			( pin "R2N21.1"
				( objectStatus "@baseboard_fab2_lib.baseboard_fab2(sch_1):page138_i175:a" )
			)
			( pin "R2N21.2"
				( objectStatus "@baseboard_fab2_lib.baseboard_fab2(sch_1):page138_i175:b" )
			)
			( pin "EU9E1.37"
				( objectStatus "@baseboard_fab2_lib.baseboard_fab2(sch_1):page139_i72:cbot" )
			)
			( pin "EU9E1.40"
				( objectStatus "@baseboard_fab2_lib.baseboard_fab2(sch_1):page139_i72:ctop" )
			)
			( pin "EU9E1.28"
				( objectStatus "@baseboard_fab2_lib.baseboard_fab2(sch_1):page139_i72:dev_off_n" )
			)
			( pin "EU9E1.65"
				( objectStatus "@baseboard_fab2_lib.baseboard_fab2(sch_1):page139_i72:gnd" )
			)
			( pin "EU9E1.19"
				( objectStatus "@baseboard_fab2_lib.baseboard_fab2(sch_1):page139_i72:jtag_clk" )
			)
			( pin "EU9E1.29"
				( objectStatus "@baseboard_fab2_lib.baseboard_fab2(sch_1):page139_i72:jtag_tdi" )
			)
			( pin "EU9E1.4"
				( objectStatus "@baseboard_fab2_lib.baseboard_fab2(sch_1):page139_i72:jtag_tdo" )
			)
			( pin "EU9E1.18"
				( objectStatus "@baseboard_fab2_lib.baseboard_fab2(sch_1):page139_i72:jtag_tms" )
			)
			( pin "EU9E1.1"
				( objectStatus "@baseboard_fab2_lib.baseboard_fab2(sch_1):page139_i72:lan_pwr_good" )
			)
			( pin "EU9E1.31"
				( objectStatus "@baseboard_fab2_lib.baseboard_fab2(sch_1):page139_i72:led0" )
			)
			( pin "EU9E1.30"
				( objectStatus "@baseboard_fab2_lib.baseboard_fab2(sch_1):page139_i72:led1" )
			)
			( pin "EU9E1.33"
				( objectStatus "@baseboard_fab2_lib.baseboard_fab2(sch_1):page139_i72:led2" )
			)
			( pin "EU9E1.57"
				( objectStatus "@baseboard_fab2_lib.baseboard_fab2(sch_1):page139_i72:mdi_minus0_sfp_i2c_data" )
			)
			( pin "EU9E1.54"
				( objectStatus "@baseboard_fab2_lib.baseboard_fab2(sch_1):page139_i72:mdi_minus1_srds_sig_det" )
			)
			( pin "EU9E1.52"
				( objectStatus "@baseboard_fab2_lib.baseboard_fab2(sch_1):page139_i72:mdi_minus2_setn" )
			)
			( pin "EU9E1.49"
				( objectStatus "@baseboard_fab2_lib.baseboard_fab2(sch_1):page139_i72:mdi_minus3_sern" )
			)
			( pin "EU9E1.58"
				( objectStatus "@baseboard_fab2_lib.baseboard_fab2(sch_1):page139_i72:mdi_plus0_nc" )
			)
			( pin "EU9E1.55"
				( objectStatus "@baseboard_fab2_lib.baseboard_fab2(sch_1):page139_i72:mdi_plus1_sfp_i2c_clk" )
			)
			( pin "EU9E1.53"
				( objectStatus "@baseboard_fab2_lib.baseboard_fab2(sch_1):page139_i72:mdi_plus2_setp" )
			)
			( pin "EU9E1.50"
				( objectStatus "@baseboard_fab2_lib.baseboard_fab2(sch_1):page139_i72:mdi_plus3_serp" )
			)
			( pin "EU9E1.22"
				( objectStatus "@baseboard_fab2_lib.baseboard_fab2(sch_1):page139_i72:nc" )
			)
			( pin "EU9E1.43"
				( objectStatus "@baseboard_fab2_lib.baseboard_fab2(sch_1):page139_i72:nc_si_arb_in" )
			)
			( pin "EU9E1.44"
				( objectStatus "@baseboard_fab2_lib.baseboard_fab2(sch_1):page139_i72:nc_si_arb_out" )
			)
			( pin "EU9E1.2"
				( objectStatus "@baseboard_fab2_lib.baseboard_fab2(sch_1):page139_i72:nc_si_clk_in" )
			)
			( pin "EU9E1.3"
				( objectStatus "@baseboard_fab2_lib.baseboard_fab2(sch_1):page139_i72:nc_si_crs_dv" )
			)
			( pin "EU9E1.6"
				( objectStatus "@baseboard_fab2_lib.baseboard_fab2(sch_1):page139_i72:nc_si_rxd0" )
			)
			( pin "EU9E1.5"
				( objectStatus "@baseboard_fab2_lib.baseboard_fab2(sch_1):page139_i72:nc_si_rxd1" )
			)
			( pin "EU9E1.7"
				( objectStatus "@baseboard_fab2_lib.baseboard_fab2(sch_1):page139_i72:nc_si_tx_en" )
			)
			( pin "EU9E1.9"
				( objectStatus "@baseboard_fab2_lib.baseboard_fab2(sch_1):page139_i72:nc_si_txd0" )
			)
			( pin "EU9E1.8"
				( objectStatus "@baseboard_fab2_lib.baseboard_fab2(sch_1):page139_i72:nc_si_txd1" )
			)
			( pin "EU9E1.15"
				( objectStatus "@baseboard_fab2_lib.baseboard_fab2(sch_1):page139_i72:nvm_cs_n" )
			)
			( pin "EU9E1.12"
				( objectStatus "@baseboard_fab2_lib.baseboard_fab2(sch_1):page139_i72:nvm_si" )
			)
			( pin "EU9E1.13"
				( objectStatus "@baseboard_fab2_lib.baseboard_fab2(sch_1):page139_i72:nvm_sk" )
			)
			( pin "EU9E1.14"
				( objectStatus "@baseboard_fab2_lib.baseboard_fab2(sch_1):page139_i72:nvm_so" )
			)
			( pin "EU9E1.23"
				( objectStatus "@baseboard_fab2_lib.baseboard_fab2(sch_1):page139_i72:pe_rn" )
			)
			( pin "EU9E1.24"
				( objectStatus "@baseboard_fab2_lib.baseboard_fab2(sch_1):page139_i72:pe_rp" )
			)
			( pin "EU9E1.17"
				( objectStatus "@baseboard_fab2_lib.baseboard_fab2(sch_1):page139_i72:pe_rst_n" )
			)
			( pin "EU9E1.20"
				( objectStatus "@baseboard_fab2_lib.baseboard_fab2(sch_1):page139_i72:pe_tn" )
			)
			( pin "EU9E1.21"
				( objectStatus "@baseboard_fab2_lib.baseboard_fab2(sch_1):page139_i72:pe_tp" )
			)
			( pin "EU9E1.16"
				( objectStatus "@baseboard_fab2_lib.baseboard_fab2(sch_1):page139_i72:pe_wake_n" )
			)
			( pin "EU9E1.25"
				( objectStatus "@baseboard_fab2_lib.baseboard_fab2(sch_1):page139_i72:peclkn" )
			)
			( pin "EU9E1.26"
				( objectStatus "@baseboard_fab2_lib.baseboard_fab2(sch_1):page139_i72:peclkp" )
			)
			( pin "EU9E1.48"
				( objectStatus "@baseboard_fab2_lib.baseboard_fab2(sch_1):page139_i72:rset" )
			)
			( pin "EU9E1.63"
				( objectStatus "@baseboard_fab2_lib.baseboard_fab2(sch_1):page139_i72:sdp0" )
			)
			( pin "EU9E1.61"
				( objectStatus "@baseboard_fab2_lib.baseboard_fab2(sch_1):page139_i72:sdp1_pcie_dis_sdp1" )
			)
			( pin "EU9E1.62"
				( objectStatus "@baseboard_fab2_lib.baseboard_fab2(sch_1):page139_i72:sdp2" )
			)
			( pin "EU9E1.60"
				( objectStatus "@baseboard_fab2_lib.baseboard_fab2(sch_1):page139_i72:sdp3" )
			)
			( pin "EU9E1.35"
				( objectStatus "@baseboard_fab2_lib.baseboard_fab2(sch_1):page139_i72:smb_alrt_n" )
			)
			( pin "EU9E1.34"
				( objectStatus "@baseboard_fab2_lib.baseboard_fab2(sch_1):page139_i72:smb_clk" )
			)
			( pin "EU9E1.36"
				( objectStatus "@baseboard_fab2_lib.baseboard_fab2(sch_1):page139_i72:smb_data" )
			)
			( pin "EU9E1.59"
				( objectStatus "@baseboard_fab2_lib.baseboard_fab2(sch_1):page139_i72:vdd0p9(0)" )
			)
			( pin "EU9E1.32"
				( objectStatus "@baseboard_fab2_lib.baseboard_fab2(sch_1):page139_i72:vdd0p9(1)" )
			)
			( pin "EU9E1.11"
				( objectStatus "@baseboard_fab2_lib.baseboard_fab2(sch_1):page139_i72:vdd0p9(2)" )
			)
			( pin "EU9E1.42"
				( objectStatus "@baseboard_fab2_lib.baseboard_fab2(sch_1):page139_i72:vdd0p9(3)" )
			)
			( pin "EU9E1.38"
				( objectStatus "@baseboard_fab2_lib.baseboard_fab2(sch_1):page139_i72:vdd0p9_out" )
			)
			( pin "EU9E1.56"
				( objectStatus "@baseboard_fab2_lib.baseboard_fab2(sch_1):page139_i72:vdd1p5(0)" )
			)
			( pin "EU9E1.47"
				( objectStatus "@baseboard_fab2_lib.baseboard_fab2(sch_1):page139_i72:vdd1p5(1)" )
			)
			( pin "EU9E1.39"
				( objectStatus "@baseboard_fab2_lib.baseboard_fab2(sch_1):page139_i72:vdd1p5_out" )
			)
			( pin "EU9E1.64"
				( objectStatus "@baseboard_fab2_lib.baseboard_fab2(sch_1):page139_i72:vdd3p3(0)" )
			)
			( pin "EU9E1.51"
				( objectStatus "@baseboard_fab2_lib.baseboard_fab2(sch_1):page139_i72:vdd3p3(1)" )
			)
			( pin "EU9E1.41"
				( objectStatus "@baseboard_fab2_lib.baseboard_fab2(sch_1):page139_i72:vdd3p3(2)" )
			)
			( pin "EU9E1.27"
				( objectStatus "@baseboard_fab2_lib.baseboard_fab2(sch_1):page139_i72:vdd3p3(3)" )
			)
			( pin "EU9E1.10"
				( objectStatus "@baseboard_fab2_lib.baseboard_fab2(sch_1):page139_i72:vdd3p3(4)" )
			)
			( pin "EU9E1.46"
				( objectStatus "@baseboard_fab2_lib.baseboard_fab2(sch_1):page139_i72:xtal1" )
			)
			( pin "EU9E1.45"
				( objectStatus "@baseboard_fab2_lib.baseboard_fab2(sch_1):page139_i72:xtal2" )
			)
			( pin "C9E7.1"
				( objectStatus "@baseboard_fab2_lib.baseboard_fab2(sch_1):page139_i76:a" )
			)
			( pin "C9E7.2"
				( objectStatus "@baseboard_fab2_lib.baseboard_fab2(sch_1):page139_i76:b" )
			)
			( pin "C9E5.1"
				( objectStatus "@baseboard_fab2_lib.baseboard_fab2(sch_1):page139_i87:a" )
			)
			( pin "C9E5.2"
				( objectStatus "@baseboard_fab2_lib.baseboard_fab2(sch_1):page139_i87:b" )
			)
			( pin "C9E4.1"
				( objectStatus "@baseboard_fab2_lib.baseboard_fab2(sch_1):page139_i88:a" )
			)
			( pin "C9E4.2"
				( objectStatus "@baseboard_fab2_lib.baseboard_fab2(sch_1):page139_i88:b" )
			)
			( pin "C2M23.1"
				( objectStatus "@baseboard_fab2_lib.baseboard_fab2(sch_1):page139_i89:a" )
			)
			( pin "C2M23.2"
				( objectStatus "@baseboard_fab2_lib.baseboard_fab2(sch_1):page139_i89:b" )
			)
			( pin "C2M24.1"
				( objectStatus "@baseboard_fab2_lib.baseboard_fab2(sch_1):page139_i90:a" )
			)
			( pin "C2M24.2"
				( objectStatus "@baseboard_fab2_lib.baseboard_fab2(sch_1):page139_i90:b" )
			)
			( pin "Y9E1.1"
				( objectStatus "@baseboard_fab2_lib.baseboard_fab2(sch_1):page139_i109:a" )
			)
			( pin "Y9E1.3"
				( objectStatus "@baseboard_fab2_lib.baseboard_fab2(sch_1):page139_i109:b" )
			)
			( pin "R9E20.1"
				( objectStatus "@baseboard_fab2_lib.baseboard_fab2(sch_1):page139_i110:a" )
			)
			( pin "R9E20.2"
				( objectStatus "@baseboard_fab2_lib.baseboard_fab2(sch_1):page139_i110:b" )
			)
			( pin "C32W5.1"
				( objectStatus "@baseboard_fab2_lib.baseboard_fab2(sch_1):page185_i217:a" )
			)
			( pin "C32W5.2"
				( objectStatus "@baseboard_fab2_lib.baseboard_fab2(sch_1):page185_i217:b" )
			)
			( pin "R9E9.1"
				( objectStatus "@baseboard_fab2_lib.baseboard_fab2(sch_1):page139_i128:a" )
			)
			( pin "R9E9.2"
				( objectStatus "@baseboard_fab2_lib.baseboard_fab2(sch_1):page139_i128:b" )
			)
			( pin "R9E5.1"
				( objectStatus "@baseboard_fab2_lib.baseboard_fab2(sch_1):page139_i129:a" )
			)
			( pin "R9E5.2"
				( objectStatus "@baseboard_fab2_lib.baseboard_fab2(sch_1):page139_i129:b" )
			)
			( pin "R9E8.1"
				( objectStatus "@baseboard_fab2_lib.baseboard_fab2(sch_1):page139_i130:a" )
			)
			( pin "R9E8.2"
				( objectStatus "@baseboard_fab2_lib.baseboard_fab2(sch_1):page139_i130:b" )
			)
			( pin "C1T4.1"
				( objectStatus "@baseboard_fab2_lib.baseboard_fab2(sch_1):page139_i134:a" )
			)
			( pin "C1T4.2"
				( objectStatus "@baseboard_fab2_lib.baseboard_fab2(sch_1):page139_i134:b" )
			)
			( pin "C1R30.1"
				( objectStatus "@baseboard_fab2_lib.baseboard_fab2(sch_1):page139_i135:a" )
			)
			( pin "C1R30.2"
				( objectStatus "@baseboard_fab2_lib.baseboard_fab2(sch_1):page139_i135:b" )
			)
			( pin "C1R22.1"
				( objectStatus "@baseboard_fab2_lib.baseboard_fab2(sch_1):page139_i136:a" )
			)
			( pin "C1R22.2"
				( objectStatus "@baseboard_fab2_lib.baseboard_fab2(sch_1):page139_i136:b" )
			)
			( pin "C1R13.1"
				( objectStatus "@baseboard_fab2_lib.baseboard_fab2(sch_1):page139_i142:a" )
			)
			( pin "C1R13.2"
				( objectStatus "@baseboard_fab2_lib.baseboard_fab2(sch_1):page139_i142:b" )
			)
			( pin "C1R20.1"
				( objectStatus "@baseboard_fab2_lib.baseboard_fab2(sch_1):page139_i143:a" )
			)
			( pin "C1R20.2"
				( objectStatus "@baseboard_fab2_lib.baseboard_fab2(sch_1):page139_i143:b" )
			)
			( pin "C1T3.1"
				( objectStatus "@baseboard_fab2_lib.baseboard_fab2(sch_1):page139_i144:a" )
			)
			( pin "C1T3.2"
				( objectStatus "@baseboard_fab2_lib.baseboard_fab2(sch_1):page139_i144:b" )
			)
			( pin "C1R14.1"
				( objectStatus "@baseboard_fab2_lib.baseboard_fab2(sch_1):page139_i145:a" )
			)
			( pin "C1R14.2"
				( objectStatus "@baseboard_fab2_lib.baseboard_fab2(sch_1):page139_i145:b" )
			)
			( pin "C1R21.1"
				( objectStatus "@baseboard_fab2_lib.baseboard_fab2(sch_1):page139_i146:a" )
			)
			( pin "C1R21.2"
				( objectStatus "@baseboard_fab2_lib.baseboard_fab2(sch_1):page139_i146:b" )
			)
			( pin "C1R26.1"
				( objectStatus "@baseboard_fab2_lib.baseboard_fab2(sch_1):page139_i149:a" )
			)
			( pin "C1R26.2"
				( objectStatus "@baseboard_fab2_lib.baseboard_fab2(sch_1):page139_i149:b" )
			)
			( pin "C1R29.1"
				( objectStatus "@baseboard_fab2_lib.baseboard_fab2(sch_1):page139_i150:a" )
			)
			( pin "C1R29.2"
				( objectStatus "@baseboard_fab2_lib.baseboard_fab2(sch_1):page139_i150:b" )
			)
			( pin "C1R19.1"
				( objectStatus "@baseboard_fab2_lib.baseboard_fab2(sch_1):page139_i151:a" )
			)
			( pin "C1R19.2"
				( objectStatus "@baseboard_fab2_lib.baseboard_fab2(sch_1):page139_i151:b" )
			)
			( pin "C1R31.1"
				( objectStatus "@baseboard_fab2_lib.baseboard_fab2(sch_1):page139_i152:a" )
			)
			( pin "C1R31.2"
				( objectStatus "@baseboard_fab2_lib.baseboard_fab2(sch_1):page139_i152:b" )
			)
			( pin "C1R17.1"
				( objectStatus "@baseboard_fab2_lib.baseboard_fab2(sch_1):page139_i153:a" )
			)
			( pin "C1R17.2"
				( objectStatus "@baseboard_fab2_lib.baseboard_fab2(sch_1):page139_i153:b" )
			)
			( pin "C1R18.1"
				( objectStatus "@baseboard_fab2_lib.baseboard_fab2(sch_1):page139_i157:a" )
			)
			( pin "C1R18.2"
				( objectStatus "@baseboard_fab2_lib.baseboard_fab2(sch_1):page139_i157:b" )
			)
			( pin "C1T5.1"
				( objectStatus "@baseboard_fab2_lib.baseboard_fab2(sch_1):page139_i158:a" )
			)
			( pin "C1T5.2"
				( objectStatus "@baseboard_fab2_lib.baseboard_fab2(sch_1):page139_i158:b" )
			)
			( pin "C1R24.1"
				( objectStatus "@baseboard_fab2_lib.baseboard_fab2(sch_1):page139_i159:a" )
			)
			( pin "C1R24.2"
				( objectStatus "@baseboard_fab2_lib.baseboard_fab2(sch_1):page139_i159:b" )
			)
			( pin "C1R15.1"
				( objectStatus "@baseboard_fab2_lib.baseboard_fab2(sch_1):page139_i160:a" )
			)
			( pin "C1R15.2"
				( objectStatus "@baseboard_fab2_lib.baseboard_fab2(sch_1):page139_i160:b" )
			)
			( pin "C1R16.1"
				( objectStatus "@baseboard_fab2_lib.baseboard_fab2(sch_1):page139_i161:a" )
			)
			( pin "C1R16.2"
				( objectStatus "@baseboard_fab2_lib.baseboard_fab2(sch_1):page139_i161:b" )
			)
			( pin "C9E1.1"
				( objectStatus "@baseboard_fab2_lib.baseboard_fab2(sch_1):page139_i163:a" )
			)
			( pin "C9E1.2"
				( objectStatus "@baseboard_fab2_lib.baseboard_fab2(sch_1):page139_i163:b" )
			)
			( pin "R9F5.1"
				( objectStatus "@baseboard_fab2_lib.baseboard_fab2(sch_1):page139_i173:a" )
			)
			( pin "R9F5.2"
				( objectStatus "@baseboard_fab2_lib.baseboard_fab2(sch_1):page139_i173:b" )
			)
			( pin "R9E23.1"
				( objectStatus "@baseboard_fab2_lib.baseboard_fab2(sch_1):page139_i174:a" )
			)
			( pin "R9E23.2"
				( objectStatus "@baseboard_fab2_lib.baseboard_fab2(sch_1):page139_i174:b" )
			)
			( pin "R9E2.1"
				( objectStatus "@baseboard_fab2_lib.baseboard_fab2(sch_1):page139_i177:a" )
			)
			( pin "R9E2.2"
				( objectStatus "@baseboard_fab2_lib.baseboard_fab2(sch_1):page139_i177:b" )
			)
			( pin "R9E3.1"
				( objectStatus "@baseboard_fab2_lib.baseboard_fab2(sch_1):page139_i178:a" )
			)
			( pin "R9E3.2"
				( objectStatus "@baseboard_fab2_lib.baseboard_fab2(sch_1):page139_i178:b" )
			)
			( pin "R9E1.1"
				( objectStatus "@baseboard_fab2_lib.baseboard_fab2(sch_1):page139_i179:a" )
			)
			( pin "R9E1.2"
				( objectStatus "@baseboard_fab2_lib.baseboard_fab2(sch_1):page139_i179:b" )
			)
			( pin "R9E22.1"
				( objectStatus "@baseboard_fab2_lib.baseboard_fab2(sch_1):page139_i181:a" )
			)
			( pin "R9E22.2"
				( objectStatus "@baseboard_fab2_lib.baseboard_fab2(sch_1):page139_i181:b" )
			)
			( pin "R9E7.1"
				( objectStatus "@baseboard_fab2_lib.baseboard_fab2(sch_1):page139_i193:a" )
			)
			( pin "R9E7.2"
				( objectStatus "@baseboard_fab2_lib.baseboard_fab2(sch_1):page139_i193:b" )
			)
			( pin "R1R1.1"
				( objectStatus "@baseboard_fab2_lib.baseboard_fab2(sch_1):page139_i195:a" )
			)
			( pin "R1R1.2"
				( objectStatus "@baseboard_fab2_lib.baseboard_fab2(sch_1):page139_i195:b" )
			)
			( pin "R9E4.1"
				( objectStatus "@baseboard_fab2_lib.baseboard_fab2(sch_1):page139_i200:a" )
			)
			( pin "R9E4.2"
				( objectStatus "@baseboard_fab2_lib.baseboard_fab2(sch_1):page139_i200:b" )
			)
			( pin "R9E18.1"
				( objectStatus "@baseboard_fab2_lib.baseboard_fab2(sch_1):page139_i201:a" )
			)
			( pin "R9E18.2"
				( objectStatus "@baseboard_fab2_lib.baseboard_fab2(sch_1):page139_i201:b" )
			)
			( pin "R9E13.1"
				( objectStatus "@baseboard_fab2_lib.baseboard_fab2(sch_1):page139_i212:a" )
			)
			( pin "R9E13.2"
				( objectStatus "@baseboard_fab2_lib.baseboard_fab2(sch_1):page139_i212:b" )
			)
			( pin "R1R12.1"
				( objectStatus "@baseboard_fab2_lib.baseboard_fab2(sch_1):page139_i213:a" )
			)
			( pin "R1R12.2"
				( objectStatus "@baseboard_fab2_lib.baseboard_fab2(sch_1):page139_i213:b" )
			)
			( pin "R1T1.1"
				( objectStatus "@baseboard_fab2_lib.baseboard_fab2(sch_1):page139_i214:a" )
			)
			( pin "R1T1.2"
				( objectStatus "@baseboard_fab2_lib.baseboard_fab2(sch_1):page139_i214:b" )
			)
			( pin "R9F1.1"
				( objectStatus "@baseboard_fab2_lib.baseboard_fab2(sch_1):page139_i225:a" )
			)
			( pin "R9F1.2"
				( objectStatus "@baseboard_fab2_lib.baseboard_fab2(sch_1):page139_i225:b" )
			)
			( pin "R9E19.1"
				( objectStatus "@baseboard_fab2_lib.baseboard_fab2(sch_1):page139_i228:a" )
			)
			( pin "R9E19.2"
				( objectStatus "@baseboard_fab2_lib.baseboard_fab2(sch_1):page139_i228:b" )
			)
			( pin "R9E17.1"
				( objectStatus "@baseboard_fab2_lib.baseboard_fab2(sch_1):page139_i229:a" )
			)
			( pin "R9E17.2"
				( objectStatus "@baseboard_fab2_lib.baseboard_fab2(sch_1):page139_i229:b" )
			)
			( pin "R9E16.1"
				( objectStatus "@baseboard_fab2_lib.baseboard_fab2(sch_1):page139_i235:a" )
			)
			( pin "R9E16.2"
				( objectStatus "@baseboard_fab2_lib.baseboard_fab2(sch_1):page139_i235:b" )
			)
			( pin "R1R15.1"
				( objectStatus "@baseboard_fab2_lib.baseboard_fab2(sch_1):page139_i237:a" )
			)
			( pin "R1R15.2"
				( objectStatus "@baseboard_fab2_lib.baseboard_fab2(sch_1):page139_i237:b" )
			)
			( pin "R1T32.1"
				( objectStatus "@baseboard_fab2_lib.baseboard_fab2(sch_1):page139_i238:a" )
			)
			( pin "R1T32.2"
				( objectStatus "@baseboard_fab2_lib.baseboard_fab2(sch_1):page139_i238:b" )
			)
			( pin "R1T34.1"
				( objectStatus "@baseboard_fab2_lib.baseboard_fab2(sch_1):page139_i239:a" )
			)
			( pin "R1T34.2"
				( objectStatus "@baseboard_fab2_lib.baseboard_fab2(sch_1):page139_i239:b" )
			)
			( pin "R1T33.1"
				( objectStatus "@baseboard_fab2_lib.baseboard_fab2(sch_1):page139_i240:a" )
			)
			( pin "R1T33.2"
				( objectStatus "@baseboard_fab2_lib.baseboard_fab2(sch_1):page139_i240:b" )
			)
			( pin "C9E12.1"
				( objectStatus "@baseboard_fab2_lib.baseboard_fab2(sch_1):page139_i241:a" )
			)
			( pin "C9E12.2"
				( objectStatus "@baseboard_fab2_lib.baseboard_fab2(sch_1):page139_i241:b" )
			)
			( pin "U9E1.6"
				( objectStatus "@baseboard_fab2_lib.baseboard_fab2(sch_1):page140_i1:c" )
			)
			( pin "U9E1.5"
				( objectStatus "@baseboard_fab2_lib.baseboard_fab2(sch_1):page140_i1:dq0" )
			)
			( pin "U9E1.2"
				( objectStatus "@baseboard_fab2_lib.baseboard_fab2(sch_1):page140_i1:dq1" )
			)
			( pin "U9E1.7"
				( objectStatus "@baseboard_fab2_lib.baseboard_fab2(sch_1):page140_i1:reset_n" )
			)
			( pin "U9E1.1"
				( objectStatus "@baseboard_fab2_lib.baseboard_fab2(sch_1):page140_i1:s_n" )
			)
			( pin "U9E1.8"
				( objectStatus "@baseboard_fab2_lib.baseboard_fab2(sch_1):page140_i1:vcc" )
			)
			( pin "U9E1.4"
				( objectStatus "@baseboard_fab2_lib.baseboard_fab2(sch_1):page140_i1:vss" )
			)
			( pin "U9E1.3"
				( objectStatus "@baseboard_fab2_lib.baseboard_fab2(sch_1):page140_i1:w_n" )
			)
			( pin "C1R25.1"
				( objectStatus "@baseboard_fab2_lib.baseboard_fab2(sch_1):page140_i3:a" )
			)
			( pin "C1R25.2"
				( objectStatus "@baseboard_fab2_lib.baseboard_fab2(sch_1):page140_i3:b" )
			)
			( pin "R1R9.1"
				( objectStatus "@baseboard_fab2_lib.baseboard_fab2(sch_1):page140_i10:a" )
			)
			( pin "R1R9.2"
				( objectStatus "@baseboard_fab2_lib.baseboard_fab2(sch_1):page140_i10:b" )
			)
			( pin "R1R3.1"
				( objectStatus "@baseboard_fab2_lib.baseboard_fab2(sch_1):page140_i11:a" )
			)
			( pin "R1R3.2"
				( objectStatus "@baseboard_fab2_lib.baseboard_fab2(sch_1):page140_i11:b" )
			)
			( pin "R1R7.1"
				( objectStatus "@baseboard_fab2_lib.baseboard_fab2(sch_1):page140_i12:a" )
			)
			( pin "R1R7.2"
				( objectStatus "@baseboard_fab2_lib.baseboard_fab2(sch_1):page140_i12:b" )
			)
			( pin "R1R6.1"
				( objectStatus "@baseboard_fab2_lib.baseboard_fab2(sch_1):page140_i14:a" )
			)
			( pin "R1R6.2"
				( objectStatus "@baseboard_fab2_lib.baseboard_fab2(sch_1):page140_i14:b" )
			)
			( pin "R9E6.1"
				( objectStatus "@baseboard_fab2_lib.baseboard_fab2(sch_1):page140_i17:a" )
			)
			( pin "R9E6.2"
				( objectStatus "@baseboard_fab2_lib.baseboard_fab2(sch_1):page140_i17:b" )
			)
			( pin "C9G4.1"
				( objectStatus "@baseboard_fab2_lib.baseboard_fab2(sch_1):page141_i46:a" )
			)
			( pin "C9G4.2"
				( objectStatus "@baseboard_fab2_lib.baseboard_fab2(sch_1):page141_i46:b" )
			)
			( pin "C9G6.1"
				( objectStatus "@baseboard_fab2_lib.baseboard_fab2(sch_1):page141_i47:a" )
			)
			( pin "C9G6.2"
				( objectStatus "@baseboard_fab2_lib.baseboard_fab2(sch_1):page141_i47:b" )
			)
			( pin "C9G5.1"
				( objectStatus "@baseboard_fab2_lib.baseboard_fab2(sch_1):page141_i48:a" )
			)
			( pin "C9G5.2"
				( objectStatus "@baseboard_fab2_lib.baseboard_fab2(sch_1):page141_i48:b" )
			)
			( pin "R9G9.1"
				( objectStatus "@baseboard_fab2_lib.baseboard_fab2(sch_1):page141_i75:a" )
			)
			( pin "R9G9.2"
				( objectStatus "@baseboard_fab2_lib.baseboard_fab2(sch_1):page141_i75:b" )
			)
			( pin "R9G11.1"
				( objectStatus "@baseboard_fab2_lib.baseboard_fab2(sch_1):page141_i76:a" )
			)
			( pin "R9G11.2"
				( objectStatus "@baseboard_fab2_lib.baseboard_fab2(sch_1):page141_i76:b" )
			)
			( pin "R9G18.1"
				( objectStatus "@baseboard_fab2_lib.baseboard_fab2(sch_1):page141_i77:a" )
			)
			( pin "R9G18.2"
				( objectStatus "@baseboard_fab2_lib.baseboard_fab2(sch_1):page141_i77:b" )
			)
			( pin "R9G17.1"
				( objectStatus "@baseboard_fab2_lib.baseboard_fab2(sch_1):page141_i78:a" )
			)
			( pin "R9G17.2"
				( objectStatus "@baseboard_fab2_lib.baseboard_fab2(sch_1):page141_i78:b" )
			)
			( pin "R9G19.1"
				( objectStatus "@baseboard_fab2_lib.baseboard_fab2(sch_1):page141_i79:a" )
			)
			( pin "R9G19.2"
				( objectStatus "@baseboard_fab2_lib.baseboard_fab2(sch_1):page141_i79:b" )
			)
			( pin "R9G20.1"
				( objectStatus "@baseboard_fab2_lib.baseboard_fab2(sch_1):page141_i80:a" )
			)
			( pin "R9G20.2"
				( objectStatus "@baseboard_fab2_lib.baseboard_fab2(sch_1):page141_i80:b" )
			)
			( pin "R9G24.1"
				( objectStatus "@baseboard_fab2_lib.baseboard_fab2(sch_1):page141_i81:a" )
			)
			( pin "R9G24.2"
				( objectStatus "@baseboard_fab2_lib.baseboard_fab2(sch_1):page141_i81:b" )
			)
			( pin "R9G22.1"
				( objectStatus "@baseboard_fab2_lib.baseboard_fab2(sch_1):page141_i82:a" )
			)
			( pin "R9G22.2"
				( objectStatus "@baseboard_fab2_lib.baseboard_fab2(sch_1):page141_i82:b" )
			)
			( pin "C9G9.1"
				( objectStatus "@baseboard_fab2_lib.baseboard_fab2(sch_1):page141_i99:a" )
			)
			( pin "C9G9.2"
				( objectStatus "@baseboard_fab2_lib.baseboard_fab2(sch_1):page141_i99:b" )
			)
			( pin "C9G12.1"
				( objectStatus "@baseboard_fab2_lib.baseboard_fab2(sch_1):page141_i100:a" )
			)
			( pin "C9G12.2"
				( objectStatus "@baseboard_fab2_lib.baseboard_fab2(sch_1):page141_i100:b" )
			)
			( pin "C9G16.1"
				( objectStatus "@baseboard_fab2_lib.baseboard_fab2(sch_1):page141_i101:a" )
			)
			( pin "C9G16.2"
				( objectStatus "@baseboard_fab2_lib.baseboard_fab2(sch_1):page141_i101:b" )
			)
			( pin "C9G13.1"
				( objectStatus "@baseboard_fab2_lib.baseboard_fab2(sch_1):page141_i102:a" )
			)
			( pin "C9G13.2"
				( objectStatus "@baseboard_fab2_lib.baseboard_fab2(sch_1):page141_i102:b" )
			)
			( pin "C3W1.1"
				( objectStatus "@baseboard_fab2_lib.baseboard_fab2(sch_1):page114_i193:a" )
			)
			( pin "C3W1.2"
				( objectStatus "@baseboard_fab2_lib.baseboard_fab2(sch_1):page114_i193:b" )
			)
			( pin "U8E4.2"
				( objectStatus "@baseboard_fab2_lib.baseboard_fab2(sch_1):page142_i1:a" )
			)
			( pin "U8E4.1"
				( objectStatus "@baseboard_fab2_lib.baseboard_fab2(sch_1):page142_i1:oe" )
			)
			( pin "U8E4.4"
				( objectStatus "@baseboard_fab2_lib.baseboard_fab2(sch_1):page142_i1:y" )
			)
			( pin "R8E17.1"
				( objectStatus "@baseboard_fab2_lib.baseboard_fab2(sch_1):page142_i2:a" )
			)
			( pin "R8E17.2"
				( objectStatus "@baseboard_fab2_lib.baseboard_fab2(sch_1):page142_i2:b" )
			)
			( pin "R8E23.1"
				( objectStatus "@baseboard_fab2_lib.baseboard_fab2(sch_1):page142_i3:a" )
			)
			( pin "R8E23.2"
				( objectStatus "@baseboard_fab2_lib.baseboard_fab2(sch_1):page142_i3:b" )
			)
			( pin "R8E29.1"
				( objectStatus "@baseboard_fab2_lib.baseboard_fab2(sch_1):page142_i18:a" )
			)
			( pin "R8E29.2"
				( objectStatus "@baseboard_fab2_lib.baseboard_fab2(sch_1):page142_i18:b" )
			)
			( pin "C8E5.1"
				( objectStatus "@baseboard_fab2_lib.baseboard_fab2(sch_1):page142_i20:a" )
			)
			( pin "C8E5.2"
				( objectStatus "@baseboard_fab2_lib.baseboard_fab2(sch_1):page142_i20:b" )
			)
			( pin "R7D33.1"
				( objectStatus "@baseboard_fab2_lib.baseboard_fab2(sch_1):page92_i111:\1\" )
			)
			( pin "R7D33.2"
				( objectStatus "@baseboard_fab2_lib.baseboard_fab2(sch_1):page92_i111:\2\" )
			)
			( pin "R3P45.1"
				( objectStatus "@baseboard_fab2_lib.baseboard_fab2(sch_1):page92_i110:\1\" )
			)
			( pin "R3P45.2"
				( objectStatus "@baseboard_fab2_lib.baseboard_fab2(sch_1):page92_i110:\2\" )
			)
			( pin "R8E26.1"
				( objectStatus "@baseboard_fab2_lib.baseboard_fab2(sch_1):page142_i30:a" )
			)
			( pin "R8E26.2"
				( objectStatus "@baseboard_fab2_lib.baseboard_fab2(sch_1):page142_i30:b" )
			)
			( pin "R8E28.1"
				( objectStatus "@baseboard_fab2_lib.baseboard_fab2(sch_1):page142_i31:a" )
			)
			( pin "R8E28.2"
				( objectStatus "@baseboard_fab2_lib.baseboard_fab2(sch_1):page142_i31:b" )
			)
			( pin "R8E27.1"
				( objectStatus "@baseboard_fab2_lib.baseboard_fab2(sch_1):page142_i32:a" )
			)
			( pin "R8E27.2"
				( objectStatus "@baseboard_fab2_lib.baseboard_fab2(sch_1):page142_i32:b" )
			)
			( pin "R8E21.1"
				( objectStatus "@baseboard_fab2_lib.baseboard_fab2(sch_1):page142_i33:a" )
			)
			( pin "R8E21.2"
				( objectStatus "@baseboard_fab2_lib.baseboard_fab2(sch_1):page142_i33:b" )
			)
			( pin "U25W4.W18"
				( objectStatus "@baseboard_fab2_lib.baseboard_fab2(sch_1):page145_i117:clkin" )
			)
			( pin "U25W4.B14"
				( objectStatus "@baseboard_fab2_lib.baseboard_fab2(sch_1):page145_i117:gpioa0_mac1link" )
			)
			( pin "U25W4.D14"
				( objectStatus "@baseboard_fab2_lib.baseboard_fab2(sch_1):page145_i117:gpioa1_mac2link" )
			)
			( pin "U25W4.D13"
				( objectStatus "@baseboard_fab2_lib.baseboard_fab2(sch_1):page145_i117:\gpioa2_timer3_spi1cs1#\" )
			)
			( pin "U25W4.E13"
				( objectStatus "@baseboard_fab2_lib.baseboard_fab2(sch_1):page145_i117:gpioa3_timer4" )
			)
			( pin "U25W4.C12"
				( objectStatus "@baseboard_fab2_lib.baseboard_fab2(sch_1):page145_i117:gpioc0_sd1clk_scl10" )
			)
			( pin "U25W4.A12"
				( objectStatus "@baseboard_fab2_lib.baseboard_fab2(sch_1):page145_i117:gpioc1_sd1cmd_sda10" )
			)
			( pin "U25W4.B12"
				( objectStatus "@baseboard_fab2_lib.baseboard_fab2(sch_1):page145_i117:gpioc2_sd1dat0_scl11" )
			)
			( pin "U25W4.D9"
				( objectStatus "@baseboard_fab2_lib.baseboard_fab2(sch_1):page145_i117:gpioc3_sd1dat1_sda11" )
			)
			( pin "U25W4.D10"
				( objectStatus "@baseboard_fab2_lib.baseboard_fab2(sch_1):page145_i117:gpioc4_sd1dat2_scl12" )
			)
			( pin "U25W4.E12"
				( objectStatus "@baseboard_fab2_lib.baseboard_fab2(sch_1):page145_i117:gpioc5_sd1dat3_sda12" )
			)
			( pin "U25W4.C11"
				( objectStatus "@baseboard_fab2_lib.baseboard_fab2(sch_1):page145_i117:\gpioc6_sd1cd#_scl13\" )
			)
			( pin "U25W4.B11"
				( objectStatus "@baseboard_fab2_lib.baseboard_fab2(sch_1):page145_i117:\gpioc7_sd1wp#_sda13\" )
			)
			( pin "U25W4.F19"
				( objectStatus "@baseboard_fab2_lib.baseboard_fab2(sch_1):page145_i117:gpiod0_sd2clk" )
			)
			( pin "U25W4.E21"
				( objectStatus "@baseboard_fab2_lib.baseboard_fab2(sch_1):page145_i117:gpiod1_sd2cmd" )
			)
			( pin "U25W4.F20"
				( objectStatus "@baseboard_fab2_lib.baseboard_fab2(sch_1):page145_i117:gpiod2_sd2dat0" )
			)
			( pin "U25W4.D20"
				( objectStatus "@baseboard_fab2_lib.baseboard_fab2(sch_1):page145_i117:gpiod3_sd2dat1" )
			)
			( pin "U25W4.D21"
				( objectStatus "@baseboard_fab2_lib.baseboard_fab2(sch_1):page145_i117:gpiod4_sd2dat2" )
			)
			( pin "U25W4.E20"
				( objectStatus "@baseboard_fab2_lib.baseboard_fab2(sch_1):page145_i117:gpiod5_sd2dat3" )
			)
			( pin "U25W4.G18"
				( objectStatus "@baseboard_fab2_lib.baseboard_fab2(sch_1):page145_i117:\gpiod6_sd2cd#\" )
			)
			( pin "U25W4.C21"
				( objectStatus "@baseboard_fab2_lib.baseboard_fab2(sch_1):page145_i117:\gpiod7_sd2wp#\" )
			)
			( pin "U25W4.B20"
				( objectStatus "@baseboard_fab2_lib.baseboard_fab2(sch_1):page145_i117:gpioe0_ncts3" )
			)
			( pin "U25W4.C20"
				( objectStatus "@baseboard_fab2_lib.baseboard_fab2(sch_1):page145_i117:gpioe1_ndcd3" )
			)
			( pin "U25W4.F18"
				( objectStatus "@baseboard_fab2_lib.baseboard_fab2(sch_1):page145_i117:gpioe2_ndsr3" )
			)
			( pin "U25W4.F17"
				( objectStatus "@baseboard_fab2_lib.baseboard_fab2(sch_1):page145_i117:gpioe3_nri3" )
			)
			( pin "U25W4.E18"
				( objectStatus "@baseboard_fab2_lib.baseboard_fab2(sch_1):page145_i117:gpioe4_ndtr3" )
			)
			( pin "U25W4.D19"
				( objectStatus "@baseboard_fab2_lib.baseboard_fab2(sch_1):page145_i117:gpioe5_nrts3" )
			)
			( pin "U25W4.A20"
				( objectStatus "@baseboard_fab2_lib.baseboard_fab2(sch_1):page145_i117:gpioe6_txd3" )
			)
			( pin "U25W4.B19"
				( objectStatus "@baseboard_fab2_lib.baseboard_fab2(sch_1):page145_i117:gpioe7_rxd3" )
			)
			( pin "U25W4.J19"
				( objectStatus "@baseboard_fab2_lib.baseboard_fab2(sch_1):page145_i117:gpiof0_ncts4_lhad0" )
			)
			( pin "U25W4.J18"
				( objectStatus "@baseboard_fab2_lib.baseboard_fab2(sch_1):page145_i117:gpiof1_ndcd4_lhad1" )
			)
			( pin "U25W4.B22"
				( objectStatus "@baseboard_fab2_lib.baseboard_fab2(sch_1):page145_i117:gpiof2_ndsr4_lhad2" )
			)
			( pin "U25W4.B21"
				( objectStatus "@baseboard_fab2_lib.baseboard_fab2(sch_1):page145_i117:gpiof3_nri4_lhad3" )
			)
			( pin "U25W4.A21"
				( objectStatus "@baseboard_fab2_lib.baseboard_fab2(sch_1):page145_i117:gpiof4_ndtr4_lhclk" )
			)
			( pin "U25W4.H19"
				( objectStatus "@baseboard_fab2_lib.baseboard_fab2(sch_1):page145_i117:\gpiof5_nrts4_lhframe#\" )
			)
			( pin "U25W4.G17"
				( objectStatus "@baseboard_fab2_lib.baseboard_fab2(sch_1):page145_i117:\gpiof6_txd4_lhsirq#\" )
			)
			( pin "U25W4.H18"
				( objectStatus "@baseboard_fab2_lib.baseboard_fab2(sch_1):page145_i117:\gpiof7_rxd4_lhrst#\" )
			)
			( pin "U25W4.E17"
				( objectStatus "@baseboard_fab2_lib.baseboard_fab2(sch_1):page145_i117:gpiog4_sgps2ck_salt1" )
			)
			( pin "U25W4.D16"
				( objectStatus "@baseboard_fab2_lib.baseboard_fab2(sch_1):page145_i117:gpiog5_sgps2ld_salt2" )
			)
			( pin "U25W4.D15"
				( objectStatus "@baseboard_fab2_lib.baseboard_fab2(sch_1):page145_i117:gpiog6_sgps2i0_salt3" )
			)
			( pin "U25W4.E14"
				( objectStatus "@baseboard_fab2_lib.baseboard_fab2(sch_1):page145_i117:gpiog7_sgps2i1_salt4" )
			)
			( pin "U25W4.T2"
				( objectStatus "@baseboard_fab2_lib.baseboard_fab2(sch_1):page145_i117:gpiol0_ncts1" )
			)
			( pin "U25W4.T1"
				( objectStatus "@baseboard_fab2_lib.baseboard_fab2(sch_1):page145_i117:gpiol1_ndcd1_vpide" )
			)
			( pin "U25W4.U1"
				( objectStatus "@baseboard_fab2_lib.baseboard_fab2(sch_1):page145_i117:gpiol2_ndsr1" )
			)
			( pin "U25W4.U2"
				( objectStatus "@baseboard_fab2_lib.baseboard_fab2(sch_1):page145_i117:gpiol3_nri1_vpihs" )
			)
			( pin "U25W4.P4"
				( objectStatus "@baseboard_fab2_lib.baseboard_fab2(sch_1):page145_i117:gpiol4_ndtr1_vpivs" )
			)
			( pin "U25W4.P3"
				( objectStatus "@baseboard_fab2_lib.baseboard_fab2(sch_1):page145_i117:gpiol5_nrts1_vpiclk" )
			)
			( pin "U25W4.V1"
				( objectStatus "@baseboard_fab2_lib.baseboard_fab2(sch_1):page145_i117:gpiol6_txd1" )
			)
			( pin "U25W4.W1"
				( objectStatus "@baseboard_fab2_lib.baseboard_fab2(sch_1):page145_i117:gpiol7_rxd1" )
			)
			( pin "U25W4.Y1"
				( objectStatus "@baseboard_fab2_lib.baseboard_fab2(sch_1):page145_i117:gpiom0_ncts2_vpib2" )
			)
			( pin "U25W4.AB2"
				( objectStatus "@baseboard_fab2_lib.baseboard_fab2(sch_1):page145_i117:gpiom1_ndcd2_vpib3" )
			)
			( pin "U25W4.AA1"
				( objectStatus "@baseboard_fab2_lib.baseboard_fab2(sch_1):page145_i117:gpiom2_ndsr2_vpib4" )
			)
			( pin "U25W4.Y2"
				( objectStatus "@baseboard_fab2_lib.baseboard_fab2(sch_1):page145_i117:gpiom3_nri2_vpib5" )
			)
			( pin "U25W4.AA2"
				( objectStatus "@baseboard_fab2_lib.baseboard_fab2(sch_1):page145_i117:gpiom4_ndtr2_vpib6" )
			)
			( pin "U25W4.P5"
				( objectStatus "@baseboard_fab2_lib.baseboard_fab2(sch_1):page145_i117:gpiom5_nrts2_vpib7" )
			)
			( pin "U25W4.R5"
				( objectStatus "@baseboard_fab2_lib.baseboard_fab2(sch_1):page145_i117:gpiom6_txd2_vpib8" )
			)
			( pin "U25W4.T5"
				( objectStatus "@baseboard_fab2_lib.baseboard_fab2(sch_1):page145_i117:gpiom7_rxd2_vpib9" )
			)
			( pin "U25W4.P21"
				( objectStatus "@baseboard_fab2_lib.baseboard_fab2(sch_1):page145_i117:\gpioy3_sioonctrl#\" )
			)
			( pin "U25W4.AB18"
				( objectStatus "@baseboard_fab2_lib.baseboard_fab2(sch_1):page145_i117:peci" )
			)
			( pin "U25W4.K22"
				( objectStatus "@baseboard_fab2_lib.baseboard_fab2(sch_1):page145_i117:perefclkn" )
			)
			( pin "U25W4.K21"
				( objectStatus "@baseboard_fab2_lib.baseboard_fab2(sch_1):page145_i117:perefclkp" )
			)
			( pin "U25W4.K20"
				( objectStatus "@baseboard_fab2_lib.baseboard_fab2(sch_1):page145_i117:perext" )
			)
			( pin "U25W4.L20"
				( objectStatus "@baseboard_fab2_lib.baseboard_fab2(sch_1):page145_i117:\perst#\" )
			)
			( pin "U25W4.M22"
				( objectStatus "@baseboard_fab2_lib.baseboard_fab2(sch_1):page145_i117:perxn" )
			)
			( pin "U25W4.M21"
				( objectStatus "@baseboard_fab2_lib.baseboard_fab2(sch_1):page145_i117:perxp" )
			)
			( pin "U25W4.L22"
				( objectStatus "@baseboard_fab2_lib.baseboard_fab2(sch_1):page145_i117:petxn" )
			)
			( pin "U25W4.L21"
				( objectStatus "@baseboard_fab2_lib.baseboard_fab2(sch_1):page145_i117:petxp" )
			)
			( pin "U25W4.K2"
				( objectStatus "@baseboard_fab2_lib.baseboard_fab2(sch_1):page145_i117:rxd5" )
			)
			( pin "U25W4.U18"
				( objectStatus "@baseboard_fab2_lib.baseboard_fab2(sch_1):page145_i117:\srst#\" )
			)
			( pin "U25W4.K1"
				( objectStatus "@baseboard_fab2_lib.baseboard_fab2(sch_1):page145_i117:txd5" )
			)
			( pin "C25W4.1"
				( objectStatus "@baseboard_fab2_lib.baseboard_fab2(sch_1):page151_i141:a" )
			)
			( pin "C25W4.2"
				( objectStatus "@baseboard_fab2_lib.baseboard_fab2(sch_1):page151_i141:b" )
			)
			( pin "C25W3.1"
				( objectStatus "@baseboard_fab2_lib.baseboard_fab2(sch_1):page151_i140:a" )
			)
			( pin "C25W3.2"
				( objectStatus "@baseboard_fab2_lib.baseboard_fab2(sch_1):page151_i140:b" )
			)
			( pin "C25W2.1"
				( objectStatus "@baseboard_fab2_lib.baseboard_fab2(sch_1):page151_i139:a" )
			)
			( pin "C25W2.2"
				( objectStatus "@baseboard_fab2_lib.baseboard_fab2(sch_1):page151_i139:b" )
			)
			( pin "R1T27.1"
				( objectStatus "@baseboard_fab2_lib.baseboard_fab2(sch_1):page143_i58:a" )
			)
			( pin "R1T27.2"
				( objectStatus "@baseboard_fab2_lib.baseboard_fab2(sch_1):page143_i58:b" )
			)
			( pin "C25W5.1"
				( objectStatus "@baseboard_fab2_lib.baseboard_fab2(sch_1):page151_i142:a" )
			)
			( pin "C25W5.2"
				( objectStatus "@baseboard_fab2_lib.baseboard_fab2(sch_1):page151_i142:b" )
			)
			( pin "C25W6.1"
				( objectStatus "@baseboard_fab2_lib.baseboard_fab2(sch_1):page151_i143:a" )
			)
			( pin "C25W6.2"
				( objectStatus "@baseboard_fab2_lib.baseboard_fab2(sch_1):page151_i143:b" )
			)
			( pin "R25W32.1"
				( objectStatus "@baseboard_fab2_lib.baseboard_fab2(sch_1):page151_i227:\1\" )
			)
			( pin "R25W32.2"
				( objectStatus "@baseboard_fab2_lib.baseboard_fab2(sch_1):page151_i227:\2\" )
			)
			( pin "R25W31.1"
				( objectStatus "@baseboard_fab2_lib.baseboard_fab2(sch_1):page151_i226:\1\" )
			)
			( pin "R25W31.2"
				( objectStatus "@baseboard_fab2_lib.baseboard_fab2(sch_1):page151_i226:\2\" )
			)
			( pin "C9E9.1"
				( objectStatus "@baseboard_fab2_lib.baseboard_fab2(sch_1):page139_i249:a" )
			)
			( pin "C9E9.2"
				( objectStatus "@baseboard_fab2_lib.baseboard_fab2(sch_1):page139_i249:b" )
			)
			( pin "CR10W2.2"
				( objectStatus "@baseboard_fab2_lib.baseboard_fab2(sch_1):page251_i10:a" )
			)
			( pin "CR10W2.1"
				( objectStatus "@baseboard_fab2_lib.baseboard_fab2(sch_1):page251_i10:c" )
			)
			( pin "Q6W4.3"
				( objectStatus "@baseboard_fab2_lib.baseboard_fab2(sch_1):page168_i43:drn" )
			)
			( pin "Q6W4.1"
				( objectStatus "@baseboard_fab2_lib.baseboard_fab2(sch_1):page168_i43:gate" )
			)
			( pin "Q6W4.2"
				( objectStatus "@baseboard_fab2_lib.baseboard_fab2(sch_1):page168_i43:src" )
			)
			( pin "R9F20.1"
				( objectStatus "@baseboard_fab2_lib.baseboard_fab2(sch_1):page145_i22:a" )
			)
			( pin "R9F20.2"
				( objectStatus "@baseboard_fab2_lib.baseboard_fab2(sch_1):page145_i22:b" )
			)
			( pin "R2T41.1"
				( objectStatus "@baseboard_fab2_lib.baseboard_fab2(sch_1):page145_i136:a" )
			)
			( pin "R2T41.2"
				( objectStatus "@baseboard_fab2_lib.baseboard_fab2(sch_1):page145_i136:b" )
			)
			( pin "R8B25.1"
				( objectStatus "@baseboard_fab2_lib.baseboard_fab2(sch_1):page151_i175:a" )
			)
			( pin "R8B25.2"
				( objectStatus "@baseboard_fab2_lib.baseboard_fab2(sch_1):page151_i175:b" )
			)
			( pin "U9G1.13"
				( objectStatus "@baseboard_fab2_lib.baseboard_fab2(sch_1):page152_i1:a0" )
			)
			( pin "U9G1.12"
				( objectStatus "@baseboard_fab2_lib.baseboard_fab2(sch_1):page152_i1:a1" )
			)
			( pin "U9G1.10"
				( objectStatus "@baseboard_fab2_lib.baseboard_fab2(sch_1):page152_i1:a2" )
			)
			( pin "U9G1.9"
				( objectStatus "@baseboard_fab2_lib.baseboard_fab2(sch_1):page152_i1:a3" )
			)
			( pin "U9G1.2"
				( objectStatus "@baseboard_fab2_lib.baseboard_fab2(sch_1):page152_i1:b0" )
			)
			( pin "U9G1.3"
				( objectStatus "@baseboard_fab2_lib.baseboard_fab2(sch_1):page152_i1:b1" )
			)
			( pin "U9G1.5"
				( objectStatus "@baseboard_fab2_lib.baseboard_fab2(sch_1):page152_i1:b2" )
			)
			( pin "U9G1.6"
				( objectStatus "@baseboard_fab2_lib.baseboard_fab2(sch_1):page152_i1:b3" )
			)
			( pin "U9G1.1"
				( objectStatus "@baseboard_fab2_lib.baseboard_fab2(sch_1):page152_i1:dir" )
			)
			( pin "U9G1.7"
				( objectStatus "@baseboard_fab2_lib.baseboard_fab2(sch_1):page152_i1:gnd(0)" )
			)
			( pin "U9G1.8"
				( objectStatus "@baseboard_fab2_lib.baseboard_fab2(sch_1):page152_i1:gnd(1)" )
			)
			( pin "U9G1.11"
				( objectStatus "@baseboard_fab2_lib.baseboard_fab2(sch_1):page152_i1:gnd(2)" )
			)
			( pin "U9G1.14"
				( objectStatus "@baseboard_fab2_lib.baseboard_fab2(sch_1):page152_i1:vcc" )
			)
			( pin "U9G1.4"
				( objectStatus "@baseboard_fab2_lib.baseboard_fab2(sch_1):page152_i1:vref" )
			)
			( pin "R1U30.1"
				( objectStatus "@baseboard_fab2_lib.baseboard_fab2(sch_1):page152_i2:a" )
			)
			( pin "R1U30.2"
				( objectStatus "@baseboard_fab2_lib.baseboard_fab2(sch_1):page152_i2:b" )
			)
			( pin "R1U46.1"
				( objectStatus "@baseboard_fab2_lib.baseboard_fab2(sch_1):page152_i6:a" )
			)
			( pin "R1U46.2"
				( objectStatus "@baseboard_fab2_lib.baseboard_fab2(sch_1):page152_i6:b" )
			)
			( pin "R9G31.1"
				( objectStatus "@baseboard_fab2_lib.baseboard_fab2(sch_1):page152_i14:a" )
			)
			( pin "R9G31.2"
				( objectStatus "@baseboard_fab2_lib.baseboard_fab2(sch_1):page152_i14:b" )
			)
			( pin "R1U36.1"
				( objectStatus "@baseboard_fab2_lib.baseboard_fab2(sch_1):page152_i15:a" )
			)
			( pin "R1U36.2"
				( objectStatus "@baseboard_fab2_lib.baseboard_fab2(sch_1):page152_i15:b" )
			)
			( pin "R1U34.1"
				( objectStatus "@baseboard_fab2_lib.baseboard_fab2(sch_1):page152_i16:a" )
			)
			( pin "R1U34.2"
				( objectStatus "@baseboard_fab2_lib.baseboard_fab2(sch_1):page152_i16:b" )
			)
			( pin "C1U19.1"
				( objectStatus "@baseboard_fab2_lib.baseboard_fab2(sch_1):page152_i18:a" )
			)
			( pin "C1U19.2"
				( objectStatus "@baseboard_fab2_lib.baseboard_fab2(sch_1):page152_i18:b" )
			)
			( pin "R1U37.1"
				( objectStatus "@baseboard_fab2_lib.baseboard_fab2(sch_1):page152_i26:a" )
			)
			( pin "R1U37.2"
				( objectStatus "@baseboard_fab2_lib.baseboard_fab2(sch_1):page152_i26:b" )
			)
			( pin "C1U22.1"
				( objectStatus "@baseboard_fab2_lib.baseboard_fab2(sch_1):page152_i27:a" )
			)
			( pin "C1U22.2"
				( objectStatus "@baseboard_fab2_lib.baseboard_fab2(sch_1):page152_i27:b" )
			)
			( pin "R9G34.1"
				( objectStatus "@baseboard_fab2_lib.baseboard_fab2(sch_1):page152_i45:a" )
			)
			( pin "R9G34.2"
				( objectStatus "@baseboard_fab2_lib.baseboard_fab2(sch_1):page152_i45:b" )
			)
			( pin "R9G27.1"
				( objectStatus "@baseboard_fab2_lib.baseboard_fab2(sch_1):page152_i47:a" )
			)
			( pin "R9G27.2"
				( objectStatus "@baseboard_fab2_lib.baseboard_fab2(sch_1):page152_i47:b" )
			)
			( pin "R1U58.1"
				( objectStatus "@baseboard_fab2_lib.baseboard_fab2(sch_1):page152_i49:a" )
			)
			( pin "R1U58.2"
				( objectStatus "@baseboard_fab2_lib.baseboard_fab2(sch_1):page152_i49:b" )
			)
			( pin "R1U56.1"
				( objectStatus "@baseboard_fab2_lib.baseboard_fab2(sch_1):page152_i50:a" )
			)
			( pin "R1U56.2"
				( objectStatus "@baseboard_fab2_lib.baseboard_fab2(sch_1):page152_i50:b" )
			)
			( pin "R2U51.1"
				( objectStatus "@baseboard_fab2_lib.baseboard_fab2(sch_1):page152_i51:a" )
			)
			( pin "R2U51.2"
				( objectStatus "@baseboard_fab2_lib.baseboard_fab2(sch_1):page152_i51:b" )
			)
			( pin "R2U40.1"
				( objectStatus "@baseboard_fab2_lib.baseboard_fab2(sch_1):page152_i53:a" )
			)
			( pin "R2U40.2"
				( objectStatus "@baseboard_fab2_lib.baseboard_fab2(sch_1):page152_i53:b" )
			)
			( pin "R2U41.1"
				( objectStatus "@baseboard_fab2_lib.baseboard_fab2(sch_1):page152_i54:a" )
			)
			( pin "R2U41.2"
				( objectStatus "@baseboard_fab2_lib.baseboard_fab2(sch_1):page152_i54:b" )
			)
			( pin "R1U41.1"
				( objectStatus "@baseboard_fab2_lib.baseboard_fab2(sch_1):page152_i56:a" )
			)
			( pin "R1U41.2"
				( objectStatus "@baseboard_fab2_lib.baseboard_fab2(sch_1):page152_i56:b" )
			)
			( pin "R1U35.1"
				( objectStatus "@baseboard_fab2_lib.baseboard_fab2(sch_1):page152_i57:a" )
			)
			( pin "R1U35.2"
				( objectStatus "@baseboard_fab2_lib.baseboard_fab2(sch_1):page152_i57:b" )
			)
			( pin "R4P17.1"
				( objectStatus "@baseboard_fab2_lib.baseboard_fab2(sch_1):page152_i58:a" )
			)
			( pin "R4P17.2"
				( objectStatus "@baseboard_fab2_lib.baseboard_fab2(sch_1):page152_i58:b" )
			)
			( pin "R4P20.1"
				( objectStatus "@baseboard_fab2_lib.baseboard_fab2(sch_1):page152_i59:a" )
			)
			( pin "R4P20.2"
				( objectStatus "@baseboard_fab2_lib.baseboard_fab2(sch_1):page152_i59:b" )
			)
			( pin "R7P5.1"
				( objectStatus "@baseboard_fab2_lib.baseboard_fab2(sch_1):page152_i61:a" )
			)
			( pin "R7P5.2"
				( objectStatus "@baseboard_fab2_lib.baseboard_fab2(sch_1):page152_i61:b" )
			)
			( pin "R7P21.1"
				( objectStatus "@baseboard_fab2_lib.baseboard_fab2(sch_1):page152_i62:a" )
			)
			( pin "R7P21.2"
				( objectStatus "@baseboard_fab2_lib.baseboard_fab2(sch_1):page152_i62:b" )
			)
			( pin "R1U53.1"
				( objectStatus "@baseboard_fab2_lib.baseboard_fab2(sch_1):page152_i64:a" )
			)
			( pin "R1U53.2"
				( objectStatus "@baseboard_fab2_lib.baseboard_fab2(sch_1):page152_i64:b" )
			)
			( pin "R1U60.1"
				( objectStatus "@baseboard_fab2_lib.baseboard_fab2(sch_1):page152_i65:a" )
			)
			( pin "R1U60.2"
				( objectStatus "@baseboard_fab2_lib.baseboard_fab2(sch_1):page152_i65:b" )
			)
			( pin "R2U49.1"
				( objectStatus "@baseboard_fab2_lib.baseboard_fab2(sch_1):page152_i66:a" )
			)
			( pin "R2U49.2"
				( objectStatus "@baseboard_fab2_lib.baseboard_fab2(sch_1):page152_i66:b" )
			)
			( pin "R1U55.1"
				( objectStatus "@baseboard_fab2_lib.baseboard_fab2(sch_1):page152_i67:a" )
			)
			( pin "R1U55.2"
				( objectStatus "@baseboard_fab2_lib.baseboard_fab2(sch_1):page152_i67:b" )
			)
			( pin "R1U62.1"
				( objectStatus "@baseboard_fab2_lib.baseboard_fab2(sch_1):page152_i68:a" )
			)
			( pin "R1U62.2"
				( objectStatus "@baseboard_fab2_lib.baseboard_fab2(sch_1):page152_i68:b" )
			)
			( pin "R1U57.1"
				( objectStatus "@baseboard_fab2_lib.baseboard_fab2(sch_1):page152_i69:a" )
			)
			( pin "R1U57.2"
				( objectStatus "@baseboard_fab2_lib.baseboard_fab2(sch_1):page152_i69:b" )
			)
			( pin "R1U61.1"
				( objectStatus "@baseboard_fab2_lib.baseboard_fab2(sch_1):page152_i70:a" )
			)
			( pin "R1U61.2"
				( objectStatus "@baseboard_fab2_lib.baseboard_fab2(sch_1):page152_i70:b" )
			)
			( pin "R9G28.1"
				( objectStatus "@baseboard_fab2_lib.baseboard_fab2(sch_1):page152_i71:a" )
			)
			( pin "R9G28.2"
				( objectStatus "@baseboard_fab2_lib.baseboard_fab2(sch_1):page152_i71:b" )
			)
			( pin "R9G32.1"
				( objectStatus "@baseboard_fab2_lib.baseboard_fab2(sch_1):page152_i72:a" )
			)
			( pin "R9G32.2"
				( objectStatus "@baseboard_fab2_lib.baseboard_fab2(sch_1):page152_i72:b" )
			)
			( pin "R9G33.1"
				( objectStatus "@baseboard_fab2_lib.baseboard_fab2(sch_1):page152_i73:a" )
			)
			( pin "R9G33.2"
				( objectStatus "@baseboard_fab2_lib.baseboard_fab2(sch_1):page152_i73:b" )
			)
			( pin "R1U59.1"
				( objectStatus "@baseboard_fab2_lib.baseboard_fab2(sch_1):page152_i74:a" )
			)
			( pin "R1U59.2"
				( objectStatus "@baseboard_fab2_lib.baseboard_fab2(sch_1):page152_i74:b" )
			)
			( pin "R2U47.1"
				( objectStatus "@baseboard_fab2_lib.baseboard_fab2(sch_1):page152_i79:a" )
			)
			( pin "R2U47.2"
				( objectStatus "@baseboard_fab2_lib.baseboard_fab2(sch_1):page152_i79:b" )
			)
			( pin "R9G29.1"
				( objectStatus "@baseboard_fab2_lib.baseboard_fab2(sch_1):page152_i92:a" )
			)
			( pin "R9G29.2"
				( objectStatus "@baseboard_fab2_lib.baseboard_fab2(sch_1):page152_i92:b" )
			)
			( pin "R1U54.1"
				( objectStatus "@baseboard_fab2_lib.baseboard_fab2(sch_1):page152_i93:a" )
			)
			( pin "R1U54.2"
				( objectStatus "@baseboard_fab2_lib.baseboard_fab2(sch_1):page152_i93:b" )
			)
			( pin "R2U46.1"
				( objectStatus "@baseboard_fab2_lib.baseboard_fab2(sch_1):page152_i94:a" )
			)
			( pin "R2U46.2"
				( objectStatus "@baseboard_fab2_lib.baseboard_fab2(sch_1):page152_i94:b" )
			)
			( pin "R3N30.1"
				( objectStatus "@baseboard_fab2_lib.baseboard_fab2(sch_1):page152_i95:a" )
			)
			( pin "R3N30.2"
				( objectStatus "@baseboard_fab2_lib.baseboard_fab2(sch_1):page152_i95:b" )
			)
			( pin "R9G30.1"
				( objectStatus "@baseboard_fab2_lib.baseboard_fab2(sch_1):page152_i98:a" )
			)
			( pin "R9G30.2"
				( objectStatus "@baseboard_fab2_lib.baseboard_fab2(sch_1):page152_i98:b" )
			)
			( pin "R3P63.1"
				( objectStatus "@baseboard_fab2_lib.baseboard_fab2(sch_1):page152_i100:a" )
			)
			( pin "R3P63.2"
				( objectStatus "@baseboard_fab2_lib.baseboard_fab2(sch_1):page152_i100:b" )
			)
			( pin "R2U45.1"
				( objectStatus "@baseboard_fab2_lib.baseboard_fab2(sch_1):page152_i102:a" )
			)
			( pin "R2U45.2"
				( objectStatus "@baseboard_fab2_lib.baseboard_fab2(sch_1):page152_i102:b" )
			)
			( pin "R7F6.1"
				( objectStatus "@baseboard_fab2_lib.baseboard_fab2(sch_1):page153_i90:a" )
			)
			( pin "R7F6.2"
				( objectStatus "@baseboard_fab2_lib.baseboard_fab2(sch_1):page153_i90:b" )
			)
			( pin "R7F5.1"
				( objectStatus "@baseboard_fab2_lib.baseboard_fab2(sch_1):page153_i94:a" )
			)
			( pin "R7F5.2"
				( objectStatus "@baseboard_fab2_lib.baseboard_fab2(sch_1):page153_i94:b" )
			)
			( pin "R7F4.1"
				( objectStatus "@baseboard_fab2_lib.baseboard_fab2(sch_1):page153_i98:a" )
			)
			( pin "R7F4.2"
				( objectStatus "@baseboard_fab2_lib.baseboard_fab2(sch_1):page153_i98:b" )
			)
			( pin "R7F37.1"
				( objectStatus "@baseboard_fab2_lib.baseboard_fab2(sch_1):page153_i108:a" )
			)
			( pin "R7F37.2"
				( objectStatus "@baseboard_fab2_lib.baseboard_fab2(sch_1):page153_i108:b" )
			)
			( pin "R7F3.1"
				( objectStatus "@baseboard_fab2_lib.baseboard_fab2(sch_1):page153_i109:a" )
			)
			( pin "R7F3.2"
				( objectStatus "@baseboard_fab2_lib.baseboard_fab2(sch_1):page153_i109:b" )
			)
			( pin "C7F2.1"
				( objectStatus "@baseboard_fab2_lib.baseboard_fab2(sch_1):page153_i130:a" )
			)
			( pin "C7F2.2"
				( objectStatus "@baseboard_fab2_lib.baseboard_fab2(sch_1):page153_i130:b" )
			)
			( pin "C7F1.1"
				( objectStatus "@baseboard_fab2_lib.baseboard_fab2(sch_1):page153_i131:a" )
			)
			( pin "C7F1.2"
				( objectStatus "@baseboard_fab2_lib.baseboard_fab2(sch_1):page153_i131:b" )
			)
			( pin "C3T5.1"
				( objectStatus "@baseboard_fab2_lib.baseboard_fab2(sch_1):page153_i136:a" )
			)
			( pin "C3T5.2"
				( objectStatus "@baseboard_fab2_lib.baseboard_fab2(sch_1):page153_i136:b" )
			)
			( pin "C3T4.1"
				( objectStatus "@baseboard_fab2_lib.baseboard_fab2(sch_1):page153_i138:a" )
			)
			( pin "C3T4.2"
				( objectStatus "@baseboard_fab2_lib.baseboard_fab2(sch_1):page153_i138:b" )
			)
			( pin "R7F32.1"
				( objectStatus "@baseboard_fab2_lib.baseboard_fab2(sch_1):page153_i140:a" )
			)
			( pin "R7F32.2"
				( objectStatus "@baseboard_fab2_lib.baseboard_fab2(sch_1):page153_i140:b" )
			)
			( pin "U7F1.16"
				( objectStatus "@baseboard_fab2_lib.baseboard_fab2(sch_1):page153_i146:clk" )
			)
			( pin "U7F1.7"
				( objectStatus "@baseboard_fab2_lib.baseboard_fab2(sch_1):page153_i146:cs_n" )
			)
			( pin "U7F1.15"
				( objectStatus "@baseboard_fab2_lib.baseboard_fab2(sch_1):page153_i146:di_io(0)" )
			)
			( pin "U7F1.8"
				( objectStatus "@baseboard_fab2_lib.baseboard_fab2(sch_1):page153_i146:do_io(1)" )
			)
			( pin "U7F1.10"
				( objectStatus "@baseboard_fab2_lib.baseboard_fab2(sch_1):page153_i146:gnd" )
			)
			( pin "U7F1.1"
				( objectStatus "@baseboard_fab2_lib.baseboard_fab2(sch_1):page153_i146:hold_n_io(3)" )
			)
			( pin "U7F1.14"
				( objectStatus "@baseboard_fab2_lib.baseboard_fab2(sch_1):page153_i146:nc(0)" )
			)
			( pin "U7F1.13"
				( objectStatus "@baseboard_fab2_lib.baseboard_fab2(sch_1):page153_i146:nc(1)" )
			)
			( pin "U7F1.12"
				( objectStatus "@baseboard_fab2_lib.baseboard_fab2(sch_1):page153_i146:nc(2)" )
			)
			( pin "U7F1.11"
				( objectStatus "@baseboard_fab2_lib.baseboard_fab2(sch_1):page153_i146:nc(3)" )
			)
			( pin "U7F1.6"
				( objectStatus "@baseboard_fab2_lib.baseboard_fab2(sch_1):page153_i146:nc(4)" )
			)
			( pin "U7F1.5"
				( objectStatus "@baseboard_fab2_lib.baseboard_fab2(sch_1):page153_i146:nc(5)" )
			)
			( pin "U7F1.4"
				( objectStatus "@baseboard_fab2_lib.baseboard_fab2(sch_1):page153_i146:nc(6)" )
			)
			( pin "U7F1.3"
				( objectStatus "@baseboard_fab2_lib.baseboard_fab2(sch_1):page153_i146:reset_n" )
			)
			( pin "U7F1.2"
				( objectStatus "@baseboard_fab2_lib.baseboard_fab2(sch_1):page153_i146:vcc" )
			)
			( pin "U7F1.9"
				( objectStatus "@baseboard_fab2_lib.baseboard_fab2(sch_1):page153_i146:wp_n_io(2)" )
			)
			( pin "R3T3.1"
				( objectStatus "@baseboard_fab2_lib.baseboard_fab2(sch_1):page153_i150:a" )
			)
			( pin "R3T3.2"
				( objectStatus "@baseboard_fab2_lib.baseboard_fab2(sch_1):page153_i150:b" )
			)
			( pin "R3T5.1"
				( objectStatus "@baseboard_fab2_lib.baseboard_fab2(sch_1):page153_i152:a" )
			)
			( pin "R3T5.2"
				( objectStatus "@baseboard_fab2_lib.baseboard_fab2(sch_1):page153_i152:b" )
			)
			( pin "R3T2.1"
				( objectStatus "@baseboard_fab2_lib.baseboard_fab2(sch_1):page153_i155:a" )
			)
			( pin "R3T2.2"
				( objectStatus "@baseboard_fab2_lib.baseboard_fab2(sch_1):page153_i155:b" )
			)
			( pin "R3U1.1"
				( objectStatus "@baseboard_fab2_lib.baseboard_fab2(sch_1):page153_i156:a" )
			)
			( pin "R3U1.2"
				( objectStatus "@baseboard_fab2_lib.baseboard_fab2(sch_1):page153_i156:b" )
			)
			( pin "R3T1.1"
				( objectStatus "@baseboard_fab2_lib.baseboard_fab2(sch_1):page153_i157:a" )
			)
			( pin "R3T1.2"
				( objectStatus "@baseboard_fab2_lib.baseboard_fab2(sch_1):page153_i157:b" )
			)
			( pin "R8F8.1"
				( objectStatus "@baseboard_fab2_lib.baseboard_fab2(sch_1):page153_i166:a" )
			)
			( pin "R8F8.2"
				( objectStatus "@baseboard_fab2_lib.baseboard_fab2(sch_1):page153_i166:b" )
			)
			( pin "R8F7.1"
				( objectStatus "@baseboard_fab2_lib.baseboard_fab2(sch_1):page153_i167:a" )
			)
			( pin "R8F7.2"
				( objectStatus "@baseboard_fab2_lib.baseboard_fab2(sch_1):page153_i167:b" )
			)
			( pin "R7F28.1"
				( objectStatus "@baseboard_fab2_lib.baseboard_fab2(sch_1):page153_i168:a" )
			)
			( pin "R7F28.2"
				( objectStatus "@baseboard_fab2_lib.baseboard_fab2(sch_1):page153_i168:b" )
			)
			( pin "R7F30.1"
				( objectStatus "@baseboard_fab2_lib.baseboard_fab2(sch_1):page153_i170:a" )
			)
			( pin "R7F30.2"
				( objectStatus "@baseboard_fab2_lib.baseboard_fab2(sch_1):page153_i170:b" )
			)
			( pin "R3T4.1"
				( objectStatus "@baseboard_fab2_lib.baseboard_fab2(sch_1):page153_i174:a" )
			)
			( pin "R3T4.2"
				( objectStatus "@baseboard_fab2_lib.baseboard_fab2(sch_1):page153_i174:b" )
			)
			( pin "R3T12.1"
				( objectStatus "@baseboard_fab2_lib.baseboard_fab2(sch_1):page153_i178:a" )
			)
			( pin "R3T12.2"
				( objectStatus "@baseboard_fab2_lib.baseboard_fab2(sch_1):page153_i178:b" )
			)
			( pin "R3T9.1"
				( objectStatus "@baseboard_fab2_lib.baseboard_fab2(sch_1):page153_i179:a" )
			)
			( pin "R3T9.2"
				( objectStatus "@baseboard_fab2_lib.baseboard_fab2(sch_1):page153_i179:b" )
			)
			( pin "R7F29.1"
				( objectStatus "@baseboard_fab2_lib.baseboard_fab2(sch_1):page153_i181:a" )
			)
			( pin "R7F29.2"
				( objectStatus "@baseboard_fab2_lib.baseboard_fab2(sch_1):page153_i181:b" )
			)
			( pin "R3T10.1"
				( objectStatus "@baseboard_fab2_lib.baseboard_fab2(sch_1):page153_i184:a" )
			)
			( pin "R3T10.2"
				( objectStatus "@baseboard_fab2_lib.baseboard_fab2(sch_1):page153_i184:b" )
			)
			( pin "C8E18.1"
				( objectStatus "@baseboard_fab2_lib.baseboard_fab2(sch_1):page154_i14:a" )
			)
			( pin "C8E18.2"
				( objectStatus "@baseboard_fab2_lib.baseboard_fab2(sch_1):page154_i14:b" )
			)
			( pin "R2T9.1"
				( objectStatus "@baseboard_fab2_lib.baseboard_fab2(sch_1):page154_i62:a" )
			)
			( pin "R2T9.2"
				( objectStatus "@baseboard_fab2_lib.baseboard_fab2(sch_1):page154_i62:b" )
			)
			( pin "U8F1.15"
				( objectStatus "@baseboard_fab2_lib.baseboard_fab2(sch_1):page154_i74:en" )
			)
			( pin "U8F1.8"
				( objectStatus "@baseboard_fab2_lib.baseboard_fab2(sch_1):page154_i74:gnd" )
			)
			( pin "U8F1.2"
				( objectStatus "@baseboard_fab2_lib.baseboard_fab2(sch_1):page154_i74:ia0" )
			)
			( pin "U8F1.3"
				( objectStatus "@baseboard_fab2_lib.baseboard_fab2(sch_1):page154_i74:ia1" )
			)
			( pin "U8F1.5"
				( objectStatus "@baseboard_fab2_lib.baseboard_fab2(sch_1):page154_i74:ib0" )
			)
			( pin "U8F1.6"
				( objectStatus "@baseboard_fab2_lib.baseboard_fab2(sch_1):page154_i74:ib1" )
			)
			( pin "U8F1.11"
				( objectStatus "@baseboard_fab2_lib.baseboard_fab2(sch_1):page154_i74:ic0" )
			)
			( pin "U8F1.10"
				( objectStatus "@baseboard_fab2_lib.baseboard_fab2(sch_1):page154_i74:ic1" )
			)
			( pin "U8F1.14"
				( objectStatus "@baseboard_fab2_lib.baseboard_fab2(sch_1):page154_i74:id0" )
			)
			( pin "U8F1.13"
				( objectStatus "@baseboard_fab2_lib.baseboard_fab2(sch_1):page154_i74:id1" )
			)
			( pin "U8F1.1"
				( objectStatus "@baseboard_fab2_lib.baseboard_fab2(sch_1):page154_i74:s" )
			)
			( pin "U8F1.16"
				( objectStatus "@baseboard_fab2_lib.baseboard_fab2(sch_1):page154_i74:vcc" )
			)
			( pin "U8F1.4"
				( objectStatus "@baseboard_fab2_lib.baseboard_fab2(sch_1):page154_i74:ya" )
			)
			( pin "U8F1.7"
				( objectStatus "@baseboard_fab2_lib.baseboard_fab2(sch_1):page154_i74:yb" )
			)
			( pin "U8F1.9"
				( objectStatus "@baseboard_fab2_lib.baseboard_fab2(sch_1):page154_i74:yc" )
			)
			( pin "U8F1.12"
				( objectStatus "@baseboard_fab2_lib.baseboard_fab2(sch_1):page154_i74:yd" )
			)
			( pin "U2T1.15"
				( objectStatus "@baseboard_fab2_lib.baseboard_fab2(sch_1):page154_i75:en" )
			)
			( pin "U2T1.8"
				( objectStatus "@baseboard_fab2_lib.baseboard_fab2(sch_1):page154_i75:gnd" )
			)
			( pin "U2T1.2"
				( objectStatus "@baseboard_fab2_lib.baseboard_fab2(sch_1):page154_i75:ia0" )
			)
			( pin "U2T1.3"
				( objectStatus "@baseboard_fab2_lib.baseboard_fab2(sch_1):page154_i75:ia1" )
			)
			( pin "U2T1.5"
				( objectStatus "@baseboard_fab2_lib.baseboard_fab2(sch_1):page154_i75:ib0" )
			)
			( pin "U2T1.6"
				( objectStatus "@baseboard_fab2_lib.baseboard_fab2(sch_1):page154_i75:ib1" )
			)
			( pin "U2T1.11"
				( objectStatus "@baseboard_fab2_lib.baseboard_fab2(sch_1):page154_i75:ic0" )
			)
			( pin "U2T1.10"
				( objectStatus "@baseboard_fab2_lib.baseboard_fab2(sch_1):page154_i75:ic1" )
			)
			( pin "U2T1.14"
				( objectStatus "@baseboard_fab2_lib.baseboard_fab2(sch_1):page154_i75:id0" )
			)
			( pin "U2T1.13"
				( objectStatus "@baseboard_fab2_lib.baseboard_fab2(sch_1):page154_i75:id1" )
			)
			( pin "U2T1.1"
				( objectStatus "@baseboard_fab2_lib.baseboard_fab2(sch_1):page154_i75:s" )
			)
			( pin "U2T1.16"
				( objectStatus "@baseboard_fab2_lib.baseboard_fab2(sch_1):page154_i75:vcc" )
			)
			( pin "U2T1.4"
				( objectStatus "@baseboard_fab2_lib.baseboard_fab2(sch_1):page154_i75:ya" )
			)
			( pin "U2T1.7"
				( objectStatus "@baseboard_fab2_lib.baseboard_fab2(sch_1):page154_i75:yb" )
			)
			( pin "U2T1.9"
				( objectStatus "@baseboard_fab2_lib.baseboard_fab2(sch_1):page154_i75:yc" )
			)
			( pin "U2T1.12"
				( objectStatus "@baseboard_fab2_lib.baseboard_fab2(sch_1):page154_i75:yd" )
			)
			( pin "R2T2.1"
				( objectStatus "@baseboard_fab2_lib.baseboard_fab2(sch_1):page154_i92:a" )
			)
			( pin "R2T2.2"
				( objectStatus "@baseboard_fab2_lib.baseboard_fab2(sch_1):page154_i92:b" )
			)
			( pin "R2R12.1"
				( objectStatus "@baseboard_fab2_lib.baseboard_fab2(sch_1):page154_i93:a" )
			)
			( pin "R2R12.2"
				( objectStatus "@baseboard_fab2_lib.baseboard_fab2(sch_1):page154_i93:b" )
			)
			( pin "C2T1.1"
				( objectStatus "@baseboard_fab2_lib.baseboard_fab2(sch_1):page154_i94:a" )
			)
			( pin "C2T1.2"
				( objectStatus "@baseboard_fab2_lib.baseboard_fab2(sch_1):page154_i94:b" )
			)
			( pin "U2T3.1"
				( objectStatus "@baseboard_fab2_lib.baseboard_fab2(sch_1):page154_i99:a" )
			)
			( pin "U2T3.2"
				( objectStatus "@baseboard_fab2_lib.baseboard_fab2(sch_1):page154_i99:b" )
			)
			( pin "U2T3.4"
				( objectStatus "@baseboard_fab2_lib.baseboard_fab2(sch_1):page154_i99:y" )
			)
			( pin "U2T2.1"
				( objectStatus "@baseboard_fab2_lib.baseboard_fab2(sch_1):page154_i100:a" )
			)
			( pin "U2T2.2"
				( objectStatus "@baseboard_fab2_lib.baseboard_fab2(sch_1):page154_i100:b" )
			)
			( pin "U2T2.4"
				( objectStatus "@baseboard_fab2_lib.baseboard_fab2(sch_1):page154_i100:y" )
			)
			( pin "R2T13.1"
				( objectStatus "@baseboard_fab2_lib.baseboard_fab2(sch_1):page154_i101:a" )
			)
			( pin "R2T13.2"
				( objectStatus "@baseboard_fab2_lib.baseboard_fab2(sch_1):page154_i101:b" )
			)
			( pin "R2T11.1"
				( objectStatus "@baseboard_fab2_lib.baseboard_fab2(sch_1):page154_i105:a" )
			)
			( pin "R2T11.2"
				( objectStatus "@baseboard_fab2_lib.baseboard_fab2(sch_1):page154_i105:b" )
			)
			( pin "R2T8.1"
				( objectStatus "@baseboard_fab2_lib.baseboard_fab2(sch_1):page154_i106:a" )
			)
			( pin "R2T8.2"
				( objectStatus "@baseboard_fab2_lib.baseboard_fab2(sch_1):page154_i106:b" )
			)
			( pin "R8F6.1"
				( objectStatus "@baseboard_fab2_lib.baseboard_fab2(sch_1):page154_i119:a" )
			)
			( pin "R8F6.2"
				( objectStatus "@baseboard_fab2_lib.baseboard_fab2(sch_1):page154_i119:b" )
			)
			( pin "Q8F1.3"
				( objectStatus "@baseboard_fab2_lib.baseboard_fab2(sch_1):page154_i126:drn" )
			)
			( pin "Q8F1.1"
				( objectStatus "@baseboard_fab2_lib.baseboard_fab2(sch_1):page154_i126:gate" )
			)
			( pin "Q8F1.2"
				( objectStatus "@baseboard_fab2_lib.baseboard_fab2(sch_1):page154_i126:src" )
			)
			( pin "R2T6.1"
				( objectStatus "@baseboard_fab2_lib.baseboard_fab2(sch_1):page154_i127:a" )
			)
			( pin "R2T6.2"
				( objectStatus "@baseboard_fab2_lib.baseboard_fab2(sch_1):page154_i127:b" )
			)
			( pin "R1U6.1"
				( objectStatus "@baseboard_fab2_lib.baseboard_fab2(sch_1):page154_i128:a" )
			)
			( pin "R1U6.2"
				( objectStatus "@baseboard_fab2_lib.baseboard_fab2(sch_1):page154_i128:b" )
			)
			( pin "C2T12.1"
				( objectStatus "@baseboard_fab2_lib.baseboard_fab2(sch_1):page154_i132:a" )
			)
			( pin "C2T12.2"
				( objectStatus "@baseboard_fab2_lib.baseboard_fab2(sch_1):page154_i132:b" )
			)
			( pin "C2T8.1"
				( objectStatus "@baseboard_fab2_lib.baseboard_fab2(sch_1):page154_i135:a" )
			)
			( pin "C2T8.2"
				( objectStatus "@baseboard_fab2_lib.baseboard_fab2(sch_1):page154_i135:b" )
			)
			( pin "R9A8.1"
				( objectStatus "@baseboard_fab2_lib.baseboard_fab2(sch_1):page155_i53:a" )
			)
			( pin "R9A8.2"
				( objectStatus "@baseboard_fab2_lib.baseboard_fab2(sch_1):page155_i53:b" )
			)
			( pin "R1L32.1"
				( objectStatus "@baseboard_fab2_lib.baseboard_fab2(sch_1):page155_i65:a" )
			)
			( pin "R1L32.2"
				( objectStatus "@baseboard_fab2_lib.baseboard_fab2(sch_1):page155_i65:b" )
			)
			( pin "R1L30.1"
				( objectStatus "@baseboard_fab2_lib.baseboard_fab2(sch_1):page155_i66:a" )
			)
			( pin "R1L30.2"
				( objectStatus "@baseboard_fab2_lib.baseboard_fab2(sch_1):page155_i66:b" )
			)
			( pin "R1L25.1"
				( objectStatus "@baseboard_fab2_lib.baseboard_fab2(sch_1):page155_i67:a" )
			)
			( pin "R1L25.2"
				( objectStatus "@baseboard_fab2_lib.baseboard_fab2(sch_1):page155_i67:b" )
			)
			( pin "R1L24.1"
				( objectStatus "@baseboard_fab2_lib.baseboard_fab2(sch_1):page155_i68:a" )
			)
			( pin "R1L24.2"
				( objectStatus "@baseboard_fab2_lib.baseboard_fab2(sch_1):page155_i68:b" )
			)
			( pin "R1L20.1"
				( objectStatus "@baseboard_fab2_lib.baseboard_fab2(sch_1):page155_i73:a" )
			)
			( pin "R1L20.2"
				( objectStatus "@baseboard_fab2_lib.baseboard_fab2(sch_1):page155_i73:b" )
			)
			( pin "R1L18.1"
				( objectStatus "@baseboard_fab2_lib.baseboard_fab2(sch_1):page155_i74:a" )
			)
			( pin "R1L18.2"
				( objectStatus "@baseboard_fab2_lib.baseboard_fab2(sch_1):page155_i74:b" )
			)
			( pin "R1L14.1"
				( objectStatus "@baseboard_fab2_lib.baseboard_fab2(sch_1):page155_i75:a" )
			)
			( pin "R1L14.2"
				( objectStatus "@baseboard_fab2_lib.baseboard_fab2(sch_1):page155_i75:b" )
			)
			( pin "R1L11.1"
				( objectStatus "@baseboard_fab2_lib.baseboard_fab2(sch_1):page155_i76:a" )
			)
			( pin "R1L11.2"
				( objectStatus "@baseboard_fab2_lib.baseboard_fab2(sch_1):page155_i76:b" )
			)
			( pin "R9A7.1"
				( objectStatus "@baseboard_fab2_lib.baseboard_fab2(sch_1):page155_i80:a" )
			)
			( pin "R9A7.2"
				( objectStatus "@baseboard_fab2_lib.baseboard_fab2(sch_1):page155_i80:b" )
			)
			( pin "C9A1.1"
				( objectStatus "@baseboard_fab2_lib.baseboard_fab2(sch_1):page155_i127:a" )
			)
			( pin "C9A1.2"
				( objectStatus "@baseboard_fab2_lib.baseboard_fab2(sch_1):page155_i127:b" )
			)
			( pin "F1L1.1"
				( objectStatus "@baseboard_fab2_lib.baseboard_fab2(sch_1):page155_i129:a(0)" )
			)
			( pin "F1L1.2"
				( objectStatus "@baseboard_fab2_lib.baseboard_fab2(sch_1):page155_i129:b(0)" )
			)
			( pin "R1L9.1"
				( objectStatus "@baseboard_fab2_lib.baseboard_fab2(sch_1):page155_i130:a" )
			)
			( pin "R1L9.2"
				( objectStatus "@baseboard_fab2_lib.baseboard_fab2(sch_1):page155_i130:b" )
			)
			( pin "J9A2.1"
				( objectStatus "@baseboard_fab2_lib.baseboard_fab2(sch_1):page155_i171:io1" )
			)
			( pin "J9A2.2"
				( objectStatus "@baseboard_fab2_lib.baseboard_fab2(sch_1):page155_i171:io2" )
			)
			( pin "J9A2.3"
				( objectStatus "@baseboard_fab2_lib.baseboard_fab2(sch_1):page155_i171:io3" )
			)
			( pin "J9A2.4"
				( objectStatus "@baseboard_fab2_lib.baseboard_fab2(sch_1):page155_i171:io4" )
			)
			( pin "J9A2.5"
				( objectStatus "@baseboard_fab2_lib.baseboard_fab2(sch_1):page155_i171:io5" )
			)
			( pin "J9A2.6"
				( objectStatus "@baseboard_fab2_lib.baseboard_fab2(sch_1):page155_i171:io6" )
			)
			( pin "J9A2.7"
				( objectStatus "@baseboard_fab2_lib.baseboard_fab2(sch_1):page155_i171:io7" )
			)
			( pin "J9A2.8"
				( objectStatus "@baseboard_fab2_lib.baseboard_fab2(sch_1):page155_i171:io8" )
			)
			( pin "J9A2.9"
				( objectStatus "@baseboard_fab2_lib.baseboard_fab2(sch_1):page155_i171:io9" )
			)
			( pin "J9A2.10"
				( objectStatus "@baseboard_fab2_lib.baseboard_fab2(sch_1):page155_i171:io10" )
			)
			( pin "J9A2.11"
				( objectStatus "@baseboard_fab2_lib.baseboard_fab2(sch_1):page155_i171:io11" )
			)
			( pin "J9A2.12"
				( objectStatus "@baseboard_fab2_lib.baseboard_fab2(sch_1):page155_i171:io12" )
			)
			( pin "J9A2.13"
				( objectStatus "@baseboard_fab2_lib.baseboard_fab2(sch_1):page155_i171:io13" )
			)
			( pin "J9A2.14"
				( objectStatus "@baseboard_fab2_lib.baseboard_fab2(sch_1):page155_i171:io14" )
			)
			( pin "U9A1.2"
				( objectStatus "@baseboard_fab2_lib.baseboard_fab2(sch_1):page155_i178:a" )
			)
			( pin "U9A1.4"
				( objectStatus "@baseboard_fab2_lib.baseboard_fab2(sch_1):page155_i178:y" )
			)
			( pin "C1T56.1"
				( objectStatus "@baseboard_fab2_lib.baseboard_fab2(sch_1):page155_i184:a" )
			)
			( pin "C1T56.2"
				( objectStatus "@baseboard_fab2_lib.baseboard_fab2(sch_1):page155_i184:b" )
			)
			( pin "R1L2.1"
				( objectStatus "@baseboard_fab2_lib.baseboard_fab2(sch_1):page155_i186:a" )
			)
			( pin "R1L2.2"
				( objectStatus "@baseboard_fab2_lib.baseboard_fab2(sch_1):page155_i186:b" )
			)
			( pin "Q1L2.3"
				( objectStatus "@baseboard_fab2_lib.baseboard_fab2(sch_1):page155_i187:drain(0)" )
			)
			( pin "Q1L2.5"
				( objectStatus "@baseboard_fab2_lib.baseboard_fab2(sch_1):page155_i187:gate(0)" )
			)
			( pin "Q1L2.4"
				( objectStatus "@baseboard_fab2_lib.baseboard_fab2(sch_1):page155_i187:source(0)" )
			)
			( pin "Q1L2.6"
				( objectStatus "@baseboard_fab2_lib.baseboard_fab2(sch_1):page155_i188:drain(0)" )
			)
			( pin "Q1L2.2"
				( objectStatus "@baseboard_fab2_lib.baseboard_fab2(sch_1):page155_i188:gate(0)" )
			)
			( pin "Q1L2.1"
				( objectStatus "@baseboard_fab2_lib.baseboard_fab2(sch_1):page155_i188:source(0)" )
			)
			( pin "R2T34.1"
				( objectStatus "@baseboard_fab2_lib.baseboard_fab2(sch_1):page156_i206:a" )
			)
			( pin "R2T34.2"
				( objectStatus "@baseboard_fab2_lib.baseboard_fab2(sch_1):page156_i206:b" )
			)
			( pin "R2T35.1"
				( objectStatus "@baseboard_fab2_lib.baseboard_fab2(sch_1):page156_i207:a" )
			)
			( pin "R2T35.2"
				( objectStatus "@baseboard_fab2_lib.baseboard_fab2(sch_1):page156_i207:b" )
			)
			( pin "R2T22.1"
				( objectStatus "@baseboard_fab2_lib.baseboard_fab2(sch_1):page156_i210:a" )
			)
			( pin "R2T22.2"
				( objectStatus "@baseboard_fab2_lib.baseboard_fab2(sch_1):page156_i210:b" )
			)
			( pin "R8F26.1"
				( objectStatus "@baseboard_fab2_lib.baseboard_fab2(sch_1):page156_i211:a" )
			)
			( pin "R8F26.2"
				( objectStatus "@baseboard_fab2_lib.baseboard_fab2(sch_1):page156_i211:b" )
			)
			( pin "R8E24.1"
				( objectStatus "@baseboard_fab2_lib.baseboard_fab2(sch_1):page156_i214:a" )
			)
			( pin "R8E24.2"
				( objectStatus "@baseboard_fab2_lib.baseboard_fab2(sch_1):page156_i214:b" )
			)
			( pin "R8E22.1"
				( objectStatus "@baseboard_fab2_lib.baseboard_fab2(sch_1):page156_i215:a" )
			)
			( pin "R8E22.2"
				( objectStatus "@baseboard_fab2_lib.baseboard_fab2(sch_1):page156_i215:b" )
			)
			( pin "R2U2.1"
				( objectStatus "@baseboard_fab2_lib.baseboard_fab2(sch_1):page156_i265:a" )
			)
			( pin "R2U2.2"
				( objectStatus "@baseboard_fab2_lib.baseboard_fab2(sch_1):page156_i265:b" )
			)
			( pin "R8G2.1"
				( objectStatus "@baseboard_fab2_lib.baseboard_fab2(sch_1):page156_i267:a" )
			)
			( pin "R8G2.2"
				( objectStatus "@baseboard_fab2_lib.baseboard_fab2(sch_1):page156_i267:b" )
			)
			( pin "C2T35.1"
				( objectStatus "@baseboard_fab2_lib.baseboard_fab2(sch_1):page156_i273:a" )
			)
			( pin "C2T35.2"
				( objectStatus "@baseboard_fab2_lib.baseboard_fab2(sch_1):page156_i273:b" )
			)
			( pin "C8F16.1"
				( objectStatus "@baseboard_fab2_lib.baseboard_fab2(sch_1):page156_i275:a" )
			)
			( pin "C8F16.2"
				( objectStatus "@baseboard_fab2_lib.baseboard_fab2(sch_1):page156_i275:b" )
			)
			( pin "R8E11.1"
				( objectStatus "@baseboard_fab2_lib.baseboard_fab2(sch_1):page156_i279:a" )
			)
			( pin "R8E11.2"
				( objectStatus "@baseboard_fab2_lib.baseboard_fab2(sch_1):page156_i279:b" )
			)
			( pin "J9B2.1"
				( objectStatus "@baseboard_fab2_lib.baseboard_fab2(sch_1):page156_i281:io1" )
			)
			( pin "J9B2.2"
				( objectStatus "@baseboard_fab2_lib.baseboard_fab2(sch_1):page156_i281:io2" )
			)
			( pin "J9B2.3"
				( objectStatus "@baseboard_fab2_lib.baseboard_fab2(sch_1):page156_i281:io3" )
			)
			( pin "J8C1.1"
				( objectStatus "@baseboard_fab2_lib.baseboard_fab2(sch_1):page156_i285:io1" )
			)
			( pin "J8C1.2"
				( objectStatus "@baseboard_fab2_lib.baseboard_fab2(sch_1):page156_i285:io2" )
			)
			( pin "J8C1.3"
				( objectStatus "@baseboard_fab2_lib.baseboard_fab2(sch_1):page156_i285:io3" )
			)
			( pin "R2T18.1"
				( objectStatus "@baseboard_fab2_lib.baseboard_fab2(sch_1):page156_i288:a" )
			)
			( pin "R2T18.2"
				( objectStatus "@baseboard_fab2_lib.baseboard_fab2(sch_1):page156_i288:b" )
			)
			( pin "R2T28.1"
				( objectStatus "@baseboard_fab2_lib.baseboard_fab2(sch_1):page156_i289:a" )
			)
			( pin "R2T28.2"
				( objectStatus "@baseboard_fab2_lib.baseboard_fab2(sch_1):page156_i289:b" )
			)
			( pin "R6D16.1"
				( objectStatus "@baseboard_fab2_lib.baseboard_fab2(sch_1):page156_i299:a" )
			)
			( pin "R6D16.2"
				( objectStatus "@baseboard_fab2_lib.baseboard_fab2(sch_1):page156_i299:b" )
			)
			( pin "R3D31.1"
				( objectStatus "@baseboard_fab2_lib.baseboard_fab2(sch_1):page156_i300:a" )
			)
			( pin "R3D31.2"
				( objectStatus "@baseboard_fab2_lib.baseboard_fab2(sch_1):page156_i300:b" )
			)
			( pin "R6N14.1"
				( objectStatus "@baseboard_fab2_lib.baseboard_fab2(sch_1):page156_i302:a" )
			)
			( pin "R6N14.2"
				( objectStatus "@baseboard_fab2_lib.baseboard_fab2(sch_1):page156_i302:b" )
			)
			( pin "R6N13.1"
				( objectStatus "@baseboard_fab2_lib.baseboard_fab2(sch_1):page156_i303:a" )
			)
			( pin "R6N13.2"
				( objectStatus "@baseboard_fab2_lib.baseboard_fab2(sch_1):page156_i303:b" )
			)
			( pin "R6N15.1"
				( objectStatus "@baseboard_fab2_lib.baseboard_fab2(sch_1):page156_i304:a" )
			)
			( pin "R6N15.2"
				( objectStatus "@baseboard_fab2_lib.baseboard_fab2(sch_1):page156_i304:b" )
			)
			( pin "R1C32.1"
				( objectStatus "@baseboard_fab2_lib.baseboard_fab2(sch_1):page156_i312:a" )
			)
			( pin "R1C32.2"
				( objectStatus "@baseboard_fab2_lib.baseboard_fab2(sch_1):page156_i312:b" )
			)
			( pin "R1C33.1"
				( objectStatus "@baseboard_fab2_lib.baseboard_fab2(sch_1):page156_i313:a" )
			)
			( pin "R1C33.2"
				( objectStatus "@baseboard_fab2_lib.baseboard_fab2(sch_1):page156_i313:b" )
			)
			( pin "R1C34.1"
				( objectStatus "@baseboard_fab2_lib.baseboard_fab2(sch_1):page156_i320:a" )
			)
			( pin "R1C34.2"
				( objectStatus "@baseboard_fab2_lib.baseboard_fab2(sch_1):page156_i320:b" )
			)
			( pin "R9M21.1"
				( objectStatus "@baseboard_fab2_lib.baseboard_fab2(sch_1):page156_i321:a" )
			)
			( pin "R9M21.2"
				( objectStatus "@baseboard_fab2_lib.baseboard_fab2(sch_1):page156_i321:b" )
			)
			( pin "R4A8.1"
				( objectStatus "@baseboard_fab2_lib.baseboard_fab2(sch_1):page156_i322:a" )
			)
			( pin "R4A8.2"
				( objectStatus "@baseboard_fab2_lib.baseboard_fab2(sch_1):page156_i322:b" )
			)
			( pin "R9M20.1"
				( objectStatus "@baseboard_fab2_lib.baseboard_fab2(sch_1):page156_i323:a" )
			)
			( pin "R9M20.2"
				( objectStatus "@baseboard_fab2_lib.baseboard_fab2(sch_1):page156_i323:b" )
			)
			( pin "R4A9.1"
				( objectStatus "@baseboard_fab2_lib.baseboard_fab2(sch_1):page156_i324:a" )
			)
			( pin "R4A9.2"
				( objectStatus "@baseboard_fab2_lib.baseboard_fab2(sch_1):page156_i324:b" )
			)
			( pin "R3P54.1"
				( objectStatus "@baseboard_fab2_lib.baseboard_fab2(sch_1):page156_i331:a" )
			)
			( pin "R3P54.2"
				( objectStatus "@baseboard_fab2_lib.baseboard_fab2(sch_1):page156_i331:b" )
			)
			( pin "R3P56.1"
				( objectStatus "@baseboard_fab2_lib.baseboard_fab2(sch_1):page156_i333:a" )
			)
			( pin "R3P56.2"
				( objectStatus "@baseboard_fab2_lib.baseboard_fab2(sch_1):page156_i333:b" )
			)
			( pin "R1C35.1"
				( objectStatus "@baseboard_fab2_lib.baseboard_fab2(sch_1):page156_i336:a" )
			)
			( pin "R1C35.2"
				( objectStatus "@baseboard_fab2_lib.baseboard_fab2(sch_1):page156_i336:b" )
			)
			( pin "R1C36.1"
				( objectStatus "@baseboard_fab2_lib.baseboard_fab2(sch_1):page156_i337:a" )
			)
			( pin "R1C36.2"
				( objectStatus "@baseboard_fab2_lib.baseboard_fab2(sch_1):page156_i337:b" )
			)
			( pin "R2N27.1"
				( objectStatus "@baseboard_fab2_lib.baseboard_fab2(sch_1):page157_i97:a" )
			)
			( pin "R2N27.2"
				( objectStatus "@baseboard_fab2_lib.baseboard_fab2(sch_1):page157_i97:b" )
			)
			( pin "R8F23.1"
				( objectStatus "@baseboard_fab2_lib.baseboard_fab2(sch_1):page157_i296:a" )
			)
			( pin "R8F23.2"
				( objectStatus "@baseboard_fab2_lib.baseboard_fab2(sch_1):page157_i296:b" )
			)
			( pin "R2T29.1"
				( objectStatus "@baseboard_fab2_lib.baseboard_fab2(sch_1):page157_i298:a" )
			)
			( pin "R2T29.2"
				( objectStatus "@baseboard_fab2_lib.baseboard_fab2(sch_1):page157_i298:b" )
			)
			( pin "R2N25.1"
				( objectStatus "@baseboard_fab2_lib.baseboard_fab2(sch_1):page157_i302:a" )
			)
			( pin "R2N25.2"
				( objectStatus "@baseboard_fab2_lib.baseboard_fab2(sch_1):page157_i302:b" )
			)
			( pin "R8F24.1"
				( objectStatus "@baseboard_fab2_lib.baseboard_fab2(sch_1):page157_i316:a" )
			)
			( pin "R8F24.2"
				( objectStatus "@baseboard_fab2_lib.baseboard_fab2(sch_1):page157_i316:b" )
			)
			( pin "R2T5.1"
				( objectStatus "@baseboard_fab2_lib.baseboard_fab2(sch_1):page157_i326:a" )
			)
			( pin "R2T5.2"
				( objectStatus "@baseboard_fab2_lib.baseboard_fab2(sch_1):page157_i326:b" )
			)
			( pin "R2T7.1"
				( objectStatus "@baseboard_fab2_lib.baseboard_fab2(sch_1):page157_i327:a" )
			)
			( pin "R2T7.2"
				( objectStatus "@baseboard_fab2_lib.baseboard_fab2(sch_1):page157_i327:b" )
			)
			( pin "Q2T1.1"
				( objectStatus "@baseboard_fab2_lib.baseboard_fab2(sch_1):page157_i330:b" )
			)
			( pin "Q2T1.3"
				( objectStatus "@baseboard_fab2_lib.baseboard_fab2(sch_1):page157_i330:c" )
			)
			( pin "Q2T1.2"
				( objectStatus "@baseboard_fab2_lib.baseboard_fab2(sch_1):page157_i330:e" )
			)
			( pin "R8D25.1"
				( objectStatus "@baseboard_fab2_lib.baseboard_fab2(sch_1):page157_i335:a" )
			)
			( pin "R8D25.2"
				( objectStatus "@baseboard_fab2_lib.baseboard_fab2(sch_1):page157_i335:b" )
			)
			( pin "Q2T2.3"
				( objectStatus "@baseboard_fab2_lib.baseboard_fab2(sch_1):page157_i340:drn" )
			)
			( pin "Q2T2.1"
				( objectStatus "@baseboard_fab2_lib.baseboard_fab2(sch_1):page157_i340:gate" )
			)
			( pin "Q2T2.2"
				( objectStatus "@baseboard_fab2_lib.baseboard_fab2(sch_1):page157_i340:src" )
			)
			( pin "R3N12.1"
				( objectStatus "@baseboard_fab2_lib.baseboard_fab2(sch_1):page157_i342:a" )
			)
			( pin "R3N12.2"
				( objectStatus "@baseboard_fab2_lib.baseboard_fab2(sch_1):page157_i342:b" )
			)
			( pin "R3N11.1"
				( objectStatus "@baseboard_fab2_lib.baseboard_fab2(sch_1):page157_i344:a" )
			)
			( pin "R3N11.2"
				( objectStatus "@baseboard_fab2_lib.baseboard_fab2(sch_1):page157_i344:b" )
			)
			( pin "R2M2.1"
				( objectStatus "@baseboard_fab2_lib.baseboard_fab2(sch_1):page157_i346:a" )
			)
			( pin "R2M2.2"
				( objectStatus "@baseboard_fab2_lib.baseboard_fab2(sch_1):page157_i346:b" )
			)
			( pin "R2M5.1"
				( objectStatus "@baseboard_fab2_lib.baseboard_fab2(sch_1):page157_i348:a" )
			)
			( pin "R2M5.2"
				( objectStatus "@baseboard_fab2_lib.baseboard_fab2(sch_1):page157_i348:b" )
			)
			( pin "S8E1.1"
				( objectStatus "@baseboard_fab2_lib.baseboard_fab2(sch_1):page157_i351:a" )
			)
			( pin "S8E1.2"
				( objectStatus "@baseboard_fab2_lib.baseboard_fab2(sch_1):page157_i351:b" )
			)
			( pin "R2R9.1"
				( objectStatus "@baseboard_fab2_lib.baseboard_fab2(sch_1):page157_i352:a" )
			)
			( pin "R2R9.2"
				( objectStatus "@baseboard_fab2_lib.baseboard_fab2(sch_1):page157_i352:b" )
			)
			( pin "C2R12.1"
				( objectStatus "@baseboard_fab2_lib.baseboard_fab2(sch_1):page157_i353:a" )
			)
			( pin "C2R12.2"
				( objectStatus "@baseboard_fab2_lib.baseboard_fab2(sch_1):page157_i353:b" )
			)
			( pin "U9A3.1"
				( objectStatus "@baseboard_fab2_lib.baseboard_fab2(sch_1):page175_i93:\1a\" )
			)
			( pin "U9A3.6"
				( objectStatus "@baseboard_fab2_lib.baseboard_fab2(sch_1):page175_i93:\1y\" )
			)
			( pin "U9A3.3"
				( objectStatus "@baseboard_fab2_lib.baseboard_fab2(sch_1):page175_i93:\2a\" )
			)
			( pin "U9A3.4"
				( objectStatus "@baseboard_fab2_lib.baseboard_fab2(sch_1):page175_i93:\2y\" )
			)
			( pin "U9A3.2"
				( objectStatus "@baseboard_fab2_lib.baseboard_fab2(sch_1):page175_i93:gnd" )
			)
			( pin "U9A3.5"
				( objectStatus "@baseboard_fab2_lib.baseboard_fab2(sch_1):page175_i93:vcc" )
			)
			( pin "R8E19.1"
				( objectStatus "@baseboard_fab2_lib.baseboard_fab2(sch_1):page157_i361:a" )
			)
			( pin "R8E19.2"
				( objectStatus "@baseboard_fab2_lib.baseboard_fab2(sch_1):page157_i361:b" )
			)
			( pin "R2U4.1"
				( objectStatus "@baseboard_fab2_lib.baseboard_fab2(sch_1):page157_i367:a" )
			)
			( pin "R2U4.2"
				( objectStatus "@baseboard_fab2_lib.baseboard_fab2(sch_1):page157_i367:b" )
			)
			( pin "R4R1.1"
				( objectStatus "@baseboard_fab2_lib.baseboard_fab2(sch_1):page157_i368:a" )
			)
			( pin "R4R1.2"
				( objectStatus "@baseboard_fab2_lib.baseboard_fab2(sch_1):page157_i368:b" )
			)
			( pin "C2T3.1"
				( objectStatus "@baseboard_fab2_lib.baseboard_fab2(sch_1):page157_i370:a" )
			)
			( pin "C2T3.2"
				( objectStatus "@baseboard_fab2_lib.baseboard_fab2(sch_1):page157_i370:b" )
			)
			( pin "U8D2.2"
				( objectStatus "@baseboard_fab2_lib.baseboard_fab2(sch_1):page157_i374:a" )
			)
			( pin "U8D2.4"
				( objectStatus "@baseboard_fab2_lib.baseboard_fab2(sch_1):page157_i374:y" )
			)
			( pin "C8D1.1"
				( objectStatus "@baseboard_fab2_lib.baseboard_fab2(sch_1):page157_i376:a" )
			)
			( pin "C8D1.2"
				( objectStatus "@baseboard_fab2_lib.baseboard_fab2(sch_1):page157_i376:b" )
			)
			( pin "R1L7.1"
				( objectStatus "@baseboard_fab2_lib.baseboard_fab2(sch_1):page157_i382:a" )
			)
			( pin "R1L7.2"
				( objectStatus "@baseboard_fab2_lib.baseboard_fab2(sch_1):page157_i382:b" )
			)
			( pin "R8E32.1"
				( objectStatus "@baseboard_fab2_lib.baseboard_fab2(sch_1):page157_i385:a" )
			)
			( pin "R8E32.2"
				( objectStatus "@baseboard_fab2_lib.baseboard_fab2(sch_1):page157_i385:b" )
			)
			( pin "R8D22.1"
				( objectStatus "@baseboard_fab2_lib.baseboard_fab2(sch_1):page157_i386:a" )
			)
			( pin "R8D22.2"
				( objectStatus "@baseboard_fab2_lib.baseboard_fab2(sch_1):page157_i386:b" )
			)
			( pin "R8D36.1"
				( objectStatus "@baseboard_fab2_lib.baseboard_fab2(sch_1):page157_i388:a" )
			)
			( pin "R8D36.2"
				( objectStatus "@baseboard_fab2_lib.baseboard_fab2(sch_1):page157_i388:b" )
			)
			( pin "C1T10.1"
				( objectStatus "@baseboard_fab2_lib.baseboard_fab2(sch_1):page158_i70:a" )
			)
			( pin "C1T10.2"
				( objectStatus "@baseboard_fab2_lib.baseboard_fab2(sch_1):page158_i70:b" )
			)
			( pin "U9F2.7"
				( objectStatus "@baseboard_fab2_lib.baseboard_fab2(sch_1):page158_i74:a" )
			)
			( pin "U9F2.1"
				( objectStatus "@baseboard_fab2_lib.baseboard_fab2(sch_1):page158_i74:b0" )
			)
			( pin "U9F2.2"
				( objectStatus "@baseboard_fab2_lib.baseboard_fab2(sch_1):page158_i74:b1" )
			)
			( pin "U9F2.3"
				( objectStatus "@baseboard_fab2_lib.baseboard_fab2(sch_1):page158_i74:b2" )
			)
			( pin "U9F2.4"
				( objectStatus "@baseboard_fab2_lib.baseboard_fab2(sch_1):page158_i74:gnd" )
			)
			( pin "U9F2.6"
				( objectStatus "@baseboard_fab2_lib.baseboard_fab2(sch_1):page158_i74:s1" )
			)
			( pin "U9F2.5"
				( objectStatus "@baseboard_fab2_lib.baseboard_fab2(sch_1):page158_i74:s2" )
			)
			( pin "U9F2.8"
				( objectStatus "@baseboard_fab2_lib.baseboard_fab2(sch_1):page158_i74:vcc" )
			)
			( pin "U9F1.7"
				( objectStatus "@baseboard_fab2_lib.baseboard_fab2(sch_1):page158_i75:a" )
			)
			( pin "U9F1.1"
				( objectStatus "@baseboard_fab2_lib.baseboard_fab2(sch_1):page158_i75:b0" )
			)
			( pin "U9F1.2"
				( objectStatus "@baseboard_fab2_lib.baseboard_fab2(sch_1):page158_i75:b1" )
			)
			( pin "U9F1.3"
				( objectStatus "@baseboard_fab2_lib.baseboard_fab2(sch_1):page158_i75:b2" )
			)
			( pin "U9F1.4"
				( objectStatus "@baseboard_fab2_lib.baseboard_fab2(sch_1):page158_i75:gnd" )
			)
			( pin "U9F1.6"
				( objectStatus "@baseboard_fab2_lib.baseboard_fab2(sch_1):page158_i75:s1" )
			)
			( pin "U9F1.5"
				( objectStatus "@baseboard_fab2_lib.baseboard_fab2(sch_1):page158_i75:s2" )
			)
			( pin "U9F1.8"
				( objectStatus "@baseboard_fab2_lib.baseboard_fab2(sch_1):page158_i75:vcc" )
			)
			( pin "R9F25.1"
				( objectStatus "@baseboard_fab2_lib.baseboard_fab2(sch_1):page158_i86:a" )
			)
			( pin "R9F25.2"
				( objectStatus "@baseboard_fab2_lib.baseboard_fab2(sch_1):page158_i86:b" )
			)
			( pin "R9F27.1"
				( objectStatus "@baseboard_fab2_lib.baseboard_fab2(sch_1):page158_i91:a" )
			)
			( pin "R9F27.2"
				( objectStatus "@baseboard_fab2_lib.baseboard_fab2(sch_1):page158_i91:b" )
			)
			( pin "C1T11.1"
				( objectStatus "@baseboard_fab2_lib.baseboard_fab2(sch_1):page158_i97:a" )
			)
			( pin "C1T11.2"
				( objectStatus "@baseboard_fab2_lib.baseboard_fab2(sch_1):page158_i97:b" )
			)
			( pin "R9F26.1"
				( objectStatus "@baseboard_fab2_lib.baseboard_fab2(sch_1):page158_i99:a" )
			)
			( pin "R9F26.2"
				( objectStatus "@baseboard_fab2_lib.baseboard_fab2(sch_1):page158_i99:b" )
			)
			( pin "R9F24.1"
				( objectStatus "@baseboard_fab2_lib.baseboard_fab2(sch_1):page158_i100:a" )
			)
			( pin "R9F24.2"
				( objectStatus "@baseboard_fab2_lib.baseboard_fab2(sch_1):page158_i100:b" )
			)
			( pin "DS9A4.1"
				( objectStatus "@baseboard_fab2_lib.baseboard_fab2(sch_1):page158_i130:a" )
			)
			( pin "DS9A4.2"
				( objectStatus "@baseboard_fab2_lib.baseboard_fab2(sch_1):page158_i130:c" )
			)
			( pin "R1L43.1"
				( objectStatus "@baseboard_fab2_lib.baseboard_fab2(sch_1):page158_i131:a" )
			)
			( pin "R1L43.2"
				( objectStatus "@baseboard_fab2_lib.baseboard_fab2(sch_1):page158_i131:b" )
			)
			( pin "DS9A7.1"
				( objectStatus "@baseboard_fab2_lib.baseboard_fab2(sch_1):page158_i134:a" )
			)
			( pin "DS9A7.2"
				( objectStatus "@baseboard_fab2_lib.baseboard_fab2(sch_1):page158_i134:c" )
			)
			( pin "R1L44.1"
				( objectStatus "@baseboard_fab2_lib.baseboard_fab2(sch_1):page158_i136:a" )
			)
			( pin "R1L44.2"
				( objectStatus "@baseboard_fab2_lib.baseboard_fab2(sch_1):page158_i136:b" )
			)
			( pin "R9F31.1"
				( objectStatus "@baseboard_fab2_lib.baseboard_fab2(sch_1):page239_i98:\1\" )
			)
			( pin "R9F31.2"
				( objectStatus "@baseboard_fab2_lib.baseboard_fab2(sch_1):page239_i98:\2\" )
			)
			( pin "R8G3.1"
				( objectStatus "@baseboard_fab2_lib.baseboard_fab2(sch_1):page159_i210:a" )
			)
			( pin "R8G3.2"
				( objectStatus "@baseboard_fab2_lib.baseboard_fab2(sch_1):page159_i210:b" )
			)
			( pin "R8G6.1"
				( objectStatus "@baseboard_fab2_lib.baseboard_fab2(sch_1):page159_i212:a" )
			)
			( pin "R8G6.2"
				( objectStatus "@baseboard_fab2_lib.baseboard_fab2(sch_1):page159_i212:b" )
			)
			( pin "R2U5.1"
				( objectStatus "@baseboard_fab2_lib.baseboard_fab2(sch_1):page159_i214:a" )
			)
			( pin "R2U5.2"
				( objectStatus "@baseboard_fab2_lib.baseboard_fab2(sch_1):page159_i214:b" )
			)
			( pin "R2U13.1"
				( objectStatus "@baseboard_fab2_lib.baseboard_fab2(sch_1):page159_i216:a" )
			)
			( pin "R2U13.2"
				( objectStatus "@baseboard_fab2_lib.baseboard_fab2(sch_1):page159_i216:b" )
			)
			( pin "R2U1.1"
				( objectStatus "@baseboard_fab2_lib.baseboard_fab2(sch_1):page159_i218:a" )
			)
			( pin "R2U1.2"
				( objectStatus "@baseboard_fab2_lib.baseboard_fab2(sch_1):page159_i218:b" )
			)
			( pin "R2T49.1"
				( objectStatus "@baseboard_fab2_lib.baseboard_fab2(sch_1):page159_i219:a" )
			)
			( pin "R2T49.2"
				( objectStatus "@baseboard_fab2_lib.baseboard_fab2(sch_1):page159_i219:b" )
			)
			( pin "R2U7.1"
				( objectStatus "@baseboard_fab2_lib.baseboard_fab2(sch_1):page159_i220:a" )
			)
			( pin "R2U7.2"
				( objectStatus "@baseboard_fab2_lib.baseboard_fab2(sch_1):page159_i220:b" )
			)
			( pin "R2U10.1"
				( objectStatus "@baseboard_fab2_lib.baseboard_fab2(sch_1):page159_i221:a" )
			)
			( pin "R2U10.2"
				( objectStatus "@baseboard_fab2_lib.baseboard_fab2(sch_1):page159_i221:b" )
			)
			( pin "R1U11.1"
				( objectStatus "@baseboard_fab2_lib.baseboard_fab2(sch_1):page159_i222:a" )
			)
			( pin "R1U11.2"
				( objectStatus "@baseboard_fab2_lib.baseboard_fab2(sch_1):page159_i222:b" )
			)
			( pin "R1U8.1"
				( objectStatus "@baseboard_fab2_lib.baseboard_fab2(sch_1):page159_i223:a" )
			)
			( pin "R1U8.2"
				( objectStatus "@baseboard_fab2_lib.baseboard_fab2(sch_1):page159_i223:b" )
			)
			( pin "R9G12.1"
				( objectStatus "@baseboard_fab2_lib.baseboard_fab2(sch_1):page159_i224:a" )
			)
			( pin "R9G12.2"
				( objectStatus "@baseboard_fab2_lib.baseboard_fab2(sch_1):page159_i224:b" )
			)
			( pin "R1U20.1"
				( objectStatus "@baseboard_fab2_lib.baseboard_fab2(sch_1):page159_i225:a" )
			)
			( pin "R1U20.2"
				( objectStatus "@baseboard_fab2_lib.baseboard_fab2(sch_1):page159_i225:b" )
			)
			( pin "R1U19.1"
				( objectStatus "@baseboard_fab2_lib.baseboard_fab2(sch_1):page159_i226:a" )
			)
			( pin "R1U19.2"
				( objectStatus "@baseboard_fab2_lib.baseboard_fab2(sch_1):page159_i226:b" )
			)
			( pin "R9G13.1"
				( objectStatus "@baseboard_fab2_lib.baseboard_fab2(sch_1):page159_i227:a" )
			)
			( pin "R9G13.2"
				( objectStatus "@baseboard_fab2_lib.baseboard_fab2(sch_1):page159_i227:b" )
			)
			( pin "R8G5.1"
				( objectStatus "@baseboard_fab2_lib.baseboard_fab2(sch_1):page159_i228:a" )
			)
			( pin "R8G5.2"
				( objectStatus "@baseboard_fab2_lib.baseboard_fab2(sch_1):page159_i228:b" )
			)
			( pin "R8G4.1"
				( objectStatus "@baseboard_fab2_lib.baseboard_fab2(sch_1):page159_i229:a" )
			)
			( pin "R8G4.2"
				( objectStatus "@baseboard_fab2_lib.baseboard_fab2(sch_1):page159_i229:b" )
			)
			( pin "R2U34.1"
				( objectStatus "@baseboard_fab2_lib.baseboard_fab2(sch_1):page159_i230:a" )
			)
			( pin "R2U34.2"
				( objectStatus "@baseboard_fab2_lib.baseboard_fab2(sch_1):page159_i230:b" )
			)
			( pin "R2U33.1"
				( objectStatus "@baseboard_fab2_lib.baseboard_fab2(sch_1):page159_i231:a" )
			)
			( pin "R2U33.2"
				( objectStatus "@baseboard_fab2_lib.baseboard_fab2(sch_1):page159_i231:b" )
			)
			( pin "R1U9.1"
				( objectStatus "@baseboard_fab2_lib.baseboard_fab2(sch_1):page159_i232:a" )
			)
			( pin "R1U9.2"
				( objectStatus "@baseboard_fab2_lib.baseboard_fab2(sch_1):page159_i232:b" )
			)
			( pin "R1U10.1"
				( objectStatus "@baseboard_fab2_lib.baseboard_fab2(sch_1):page159_i233:a" )
			)
			( pin "R1U10.2"
				( objectStatus "@baseboard_fab2_lib.baseboard_fab2(sch_1):page159_i233:b" )
			)
			( pin "R1T8.1"
				( objectStatus "@baseboard_fab2_lib.baseboard_fab2(sch_1):page160_i4:a" )
			)
			( pin "R1T8.2"
				( objectStatus "@baseboard_fab2_lib.baseboard_fab2(sch_1):page160_i4:b" )
			)
			( pin "R1T3.1"
				( objectStatus "@baseboard_fab2_lib.baseboard_fab2(sch_1):page160_i46:a" )
			)
			( pin "R1T3.2"
				( objectStatus "@baseboard_fab2_lib.baseboard_fab2(sch_1):page160_i46:b" )
			)
			( pin "R1T2.1"
				( objectStatus "@baseboard_fab2_lib.baseboard_fab2(sch_1):page160_i49:a" )
			)
			( pin "R1T2.2"
				( objectStatus "@baseboard_fab2_lib.baseboard_fab2(sch_1):page160_i49:b" )
			)
			( pin "R1T7.1"
				( objectStatus "@baseboard_fab2_lib.baseboard_fab2(sch_1):page160_i50:a" )
			)
			( pin "R1T7.2"
				( objectStatus "@baseboard_fab2_lib.baseboard_fab2(sch_1):page160_i50:b" )
			)
			( pin "R9F23.1"
				( objectStatus "@baseboard_fab2_lib.baseboard_fab2(sch_1):page160_i51:a" )
			)
			( pin "R9F23.2"
				( objectStatus "@baseboard_fab2_lib.baseboard_fab2(sch_1):page160_i51:b" )
			)
			( pin "R9F22.1"
				( objectStatus "@baseboard_fab2_lib.baseboard_fab2(sch_1):page160_i52:a" )
			)
			( pin "R9F22.2"
				( objectStatus "@baseboard_fab2_lib.baseboard_fab2(sch_1):page160_i52:b" )
			)
			( pin "J10W1.1"
				( objectStatus "@baseboard_fab2_lib.baseboard_fab2(sch_1):page161_i140:\1\" )
			)
			( pin "J10W1.2"
				( objectStatus "@baseboard_fab2_lib.baseboard_fab2(sch_1):page161_i140:\2\" )
			)
			( pin "J10W1.3"
				( objectStatus "@baseboard_fab2_lib.baseboard_fab2(sch_1):page161_i140:\3\" )
			)
			( pin "J10W1.4"
				( objectStatus "@baseboard_fab2_lib.baseboard_fab2(sch_1):page161_i140:\4\" )
			)
			( pin "J10W1.NP1"
				( objectStatus "@baseboard_fab2_lib.baseboard_fab2(sch_1):page161_i140:np1" )
			)
			( pin "C1E21.1"
				( objectStatus "@baseboard_fab2_lib.baseboard_fab2(sch_1):page161_i3:a" )
			)
			( pin "C1E21.2"
				( objectStatus "@baseboard_fab2_lib.baseboard_fab2(sch_1):page161_i3:b" )
			)
			( pin "C1E20.1"
				( objectStatus "@baseboard_fab2_lib.baseboard_fab2(sch_1):page161_i4:a" )
			)
			( pin "C1E20.2"
				( objectStatus "@baseboard_fab2_lib.baseboard_fab2(sch_1):page161_i4:b" )
			)
			( pin "C9M5.1"
				( objectStatus "@baseboard_fab2_lib.baseboard_fab2(sch_1):page161_i26:a" )
			)
			( pin "C9M5.2"
				( objectStatus "@baseboard_fab2_lib.baseboard_fab2(sch_1):page161_i26:b" )
			)
			( pin "C9M4.1"
				( objectStatus "@baseboard_fab2_lib.baseboard_fab2(sch_1):page161_i27:a" )
			)
			( pin "C9M4.2"
				( objectStatus "@baseboard_fab2_lib.baseboard_fab2(sch_1):page161_i27:b" )
			)
			( pin "CR1F1.2"
				( objectStatus "@baseboard_fab2_lib.baseboard_fab2(sch_1):page161_i42:a" )
			)
			( pin "CR1F1.1"
				( objectStatus "@baseboard_fab2_lib.baseboard_fab2(sch_1):page161_i42:c" )
			)
			( pin "R1F2.1"
				( objectStatus "@baseboard_fab2_lib.baseboard_fab2(sch_1):page161_i43:a" )
			)
			( pin "R1F2.2"
				( objectStatus "@baseboard_fab2_lib.baseboard_fab2(sch_1):page161_i43:b" )
			)
			( pin "R1F1.1"
				( objectStatus "@baseboard_fab2_lib.baseboard_fab2(sch_1):page161_i45:a" )
			)
			( pin "R1F1.2"
				( objectStatus "@baseboard_fab2_lib.baseboard_fab2(sch_1):page161_i45:b" )
			)
			( pin "C1F9.1"
				( objectStatus "@baseboard_fab2_lib.baseboard_fab2(sch_1):page161_i46:a" )
			)
			( pin "C1F9.2"
				( objectStatus "@baseboard_fab2_lib.baseboard_fab2(sch_1):page161_i46:b" )
			)
			( pin "CR1E1.2"
				( objectStatus "@baseboard_fab2_lib.baseboard_fab2(sch_1):page161_i50:a" )
			)
			( pin "CR1E1.1"
				( objectStatus "@baseboard_fab2_lib.baseboard_fab2(sch_1):page161_i50:c" )
			)
			( pin "R1E12.1"
				( objectStatus "@baseboard_fab2_lib.baseboard_fab2(sch_1):page161_i51:a" )
			)
			( pin "R1E12.2"
				( objectStatus "@baseboard_fab2_lib.baseboard_fab2(sch_1):page161_i51:b" )
			)
			( pin "CR1B2.2"
				( objectStatus "@baseboard_fab2_lib.baseboard_fab2(sch_1):page161_i62:a" )
			)
			( pin "CR1B2.1"
				( objectStatus "@baseboard_fab2_lib.baseboard_fab2(sch_1):page161_i62:c" )
			)
			( pin "CR1B1.2"
				( objectStatus "@baseboard_fab2_lib.baseboard_fab2(sch_1):page161_i64:a" )
			)
			( pin "CR1B1.1"
				( objectStatus "@baseboard_fab2_lib.baseboard_fab2(sch_1):page161_i64:c" )
			)
			( pin "R7F33.1"
				( objectStatus "@baseboard_fab2_lib.baseboard_fab2(sch_1):page161_i65:a" )
			)
			( pin "R7F33.2"
				( objectStatus "@baseboard_fab2_lib.baseboard_fab2(sch_1):page161_i65:b" )
			)
			( pin "R1B22.1"
				( objectStatus "@baseboard_fab2_lib.baseboard_fab2(sch_1):page161_i67:a" )
			)
			( pin "R1B22.2"
				( objectStatus "@baseboard_fab2_lib.baseboard_fab2(sch_1):page161_i67:b" )
			)
			( pin "C1B15.1"
				( objectStatus "@baseboard_fab2_lib.baseboard_fab2(sch_1):page161_i68:a" )
			)
			( pin "C1B15.2"
				( objectStatus "@baseboard_fab2_lib.baseboard_fab2(sch_1):page161_i68:b" )
			)
			( pin "R1B21.1"
				( objectStatus "@baseboard_fab2_lib.baseboard_fab2(sch_1):page161_i70:a" )
			)
			( pin "R1B21.2"
				( objectStatus "@baseboard_fab2_lib.baseboard_fab2(sch_1):page161_i70:b" )
			)
			( pin "U8G2.2"
				( objectStatus "@baseboard_fab2_lib.baseboard_fab2(sch_1):page161_i88:a" )
			)
			( pin "U8G2.4"
				( objectStatus "@baseboard_fab2_lib.baseboard_fab2(sch_1):page161_i88:y" )
			)
			( pin "C2U27.1"
				( objectStatus "@baseboard_fab2_lib.baseboard_fab2(sch_1):page161_i90:a" )
			)
			( pin "C2U27.2"
				( objectStatus "@baseboard_fab2_lib.baseboard_fab2(sch_1):page161_i90:b" )
			)
			( pin "U8G3.2"
				( objectStatus "@baseboard_fab2_lib.baseboard_fab2(sch_1):page161_i92:a" )
			)
			( pin "U8G3.4"
				( objectStatus "@baseboard_fab2_lib.baseboard_fab2(sch_1):page161_i92:y" )
			)
			( pin "C2U28.1"
				( objectStatus "@baseboard_fab2_lib.baseboard_fab2(sch_1):page161_i93:a" )
			)
			( pin "C2U28.2"
				( objectStatus "@baseboard_fab2_lib.baseboard_fab2(sch_1):page161_i93:b" )
			)
			( pin "R2U42.1"
				( objectStatus "@baseboard_fab2_lib.baseboard_fab2(sch_1):page161_i99:a" )
			)
			( pin "R2U42.2"
				( objectStatus "@baseboard_fab2_lib.baseboard_fab2(sch_1):page161_i99:b" )
			)
			( pin "R2U44.1"
				( objectStatus "@baseboard_fab2_lib.baseboard_fab2(sch_1):page161_i102:a" )
			)
			( pin "R2U44.2"
				( objectStatus "@baseboard_fab2_lib.baseboard_fab2(sch_1):page161_i102:b" )
			)
			( pin "C1E22.1"
				( objectStatus "@baseboard_fab2_lib.baseboard_fab2(sch_1):page161_i113:a" )
			)
			( pin "C1E22.2"
				( objectStatus "@baseboard_fab2_lib.baseboard_fab2(sch_1):page161_i113:b" )
			)
			( pin "R1E11.1"
				( objectStatus "@baseboard_fab2_lib.baseboard_fab2(sch_1):page161_i120:a" )
			)
			( pin "R1E11.2"
				( objectStatus "@baseboard_fab2_lib.baseboard_fab2(sch_1):page161_i120:b" )
			)
			( pin "U1E2.1"
				( objectStatus "@baseboard_fab2_lib.baseboard_fab2(sch_1):page161_i121:a(0)" )
			)
			( pin "U1E2.2"
				( objectStatus "@baseboard_fab2_lib.baseboard_fab2(sch_1):page161_i121:b(0)" )
			)
			( pin "U1E2.4"
				( objectStatus "@baseboard_fab2_lib.baseboard_fab2(sch_1):page161_i121:y(0)" )
			)
			( pin "R8F16.1"
				( objectStatus "@baseboard_fab2_lib.baseboard_fab2(sch_1):page162_i8:a" )
			)
			( pin "R8F16.2"
				( objectStatus "@baseboard_fab2_lib.baseboard_fab2(sch_1):page162_i8:b" )
			)
			( pin "R8F14.1"
				( objectStatus "@baseboard_fab2_lib.baseboard_fab2(sch_1):page162_i9:a" )
			)
			( pin "R8F14.2"
				( objectStatus "@baseboard_fab2_lib.baseboard_fab2(sch_1):page162_i9:b" )
			)
			( pin "R8F12.1"
				( objectStatus "@baseboard_fab2_lib.baseboard_fab2(sch_1):page162_i13:a" )
			)
			( pin "R8F12.2"
				( objectStatus "@baseboard_fab2_lib.baseboard_fab2(sch_1):page162_i13:b" )
			)
			( pin "R8F34.1"
				( objectStatus "@baseboard_fab2_lib.baseboard_fab2(sch_1):page162_i22:a" )
			)
			( pin "R8F34.2"
				( objectStatus "@baseboard_fab2_lib.baseboard_fab2(sch_1):page162_i22:b" )
			)
			( pin "RN8F2.1"
				( objectStatus "@baseboard_fab2_lib.baseboard_fab2(sch_1):page246_i20:a" )
			)
			( pin "RN8F2.2"
				( objectStatus "@baseboard_fab2_lib.baseboard_fab2(sch_1):page246_i20:b" )
			)
			( pin "R8F35.1"
				( objectStatus "@baseboard_fab2_lib.baseboard_fab2(sch_1):page162_i24:a" )
			)
			( pin "R8F35.2"
				( objectStatus "@baseboard_fab2_lib.baseboard_fab2(sch_1):page162_i24:b" )
			)
			( pin "C8F5.1"
				( objectStatus "@baseboard_fab2_lib.baseboard_fab2(sch_1):page162_i28:a" )
			)
			( pin "C8F5.2"
				( objectStatus "@baseboard_fab2_lib.baseboard_fab2(sch_1):page162_i28:b" )
			)
			( pin "C8F4.1"
				( objectStatus "@baseboard_fab2_lib.baseboard_fab2(sch_1):page162_i30:a" )
			)
			( pin "C8F4.2"
				( objectStatus "@baseboard_fab2_lib.baseboard_fab2(sch_1):page162_i30:b" )
			)
			( pin "U8F2.16"
				( objectStatus "@baseboard_fab2_lib.baseboard_fab2(sch_1):page162_i32:clk" )
			)
			( pin "U8F2.7"
				( objectStatus "@baseboard_fab2_lib.baseboard_fab2(sch_1):page162_i32:cs_n" )
			)
			( pin "U8F2.15"
				( objectStatus "@baseboard_fab2_lib.baseboard_fab2(sch_1):page162_i32:di_io(0)" )
			)
			( pin "U8F2.8"
				( objectStatus "@baseboard_fab2_lib.baseboard_fab2(sch_1):page162_i32:do_io(1)" )
			)
			( pin "U8F2.10"
				( objectStatus "@baseboard_fab2_lib.baseboard_fab2(sch_1):page162_i32:gnd" )
			)
			( pin "U8F2.1"
				( objectStatus "@baseboard_fab2_lib.baseboard_fab2(sch_1):page162_i32:hold_n_io(3)" )
			)
			( pin "U8F2.4"
				( objectStatus "@baseboard_fab2_lib.baseboard_fab2(sch_1):page162_i32:nc(0)" )
			)
			( pin "U8F2.5"
				( objectStatus "@baseboard_fab2_lib.baseboard_fab2(sch_1):page162_i32:nc(1)" )
			)
			( pin "U8F2.6"
				( objectStatus "@baseboard_fab2_lib.baseboard_fab2(sch_1):page162_i32:nc(2)" )
			)
			( pin "U8F2.11"
				( objectStatus "@baseboard_fab2_lib.baseboard_fab2(sch_1):page162_i32:nc(3)" )
			)
			( pin "U8F2.12"
				( objectStatus "@baseboard_fab2_lib.baseboard_fab2(sch_1):page162_i32:nc(4)" )
			)
			( pin "U8F2.13"
				( objectStatus "@baseboard_fab2_lib.baseboard_fab2(sch_1):page162_i32:nc(5)" )
			)
			( pin "U8F2.14"
				( objectStatus "@baseboard_fab2_lib.baseboard_fab2(sch_1):page162_i32:nc(6)" )
			)
			( pin "U8F2.3"
				( objectStatus "@baseboard_fab2_lib.baseboard_fab2(sch_1):page162_i32:reset_n" )
			)
			( pin "U8F2.2"
				( objectStatus "@baseboard_fab2_lib.baseboard_fab2(sch_1):page162_i32:vcc" )
			)
			( pin "U8F2.9"
				( objectStatus "@baseboard_fab2_lib.baseboard_fab2(sch_1):page162_i32:wp_n_io(2)" )
			)
			( pin "R6N8.1"
				( objectStatus "@baseboard_fab2_lib.baseboard_fab2(sch_1):page163_i2:a" )
			)
			( pin "R6N8.2"
				( objectStatus "@baseboard_fab2_lib.baseboard_fab2(sch_1):page163_i2:b" )
			)
			( pin "R6N9.1"
				( objectStatus "@baseboard_fab2_lib.baseboard_fab2(sch_1):page163_i3:a" )
			)
			( pin "R6N9.2"
				( objectStatus "@baseboard_fab2_lib.baseboard_fab2(sch_1):page163_i3:b" )
			)
			( pin "R9M18.1"
				( objectStatus "@baseboard_fab2_lib.baseboard_fab2(sch_1):page163_i6:a" )
			)
			( pin "R9M18.2"
				( objectStatus "@baseboard_fab2_lib.baseboard_fab2(sch_1):page163_i6:b" )
			)
			( pin "R9M19.1"
				( objectStatus "@baseboard_fab2_lib.baseboard_fab2(sch_1):page163_i7:a" )
			)
			( pin "R9M19.2"
				( objectStatus "@baseboard_fab2_lib.baseboard_fab2(sch_1):page163_i7:b" )
			)
			( pin "C9M8.1"
				( objectStatus "@baseboard_fab2_lib.baseboard_fab2(sch_1):page163_i10:a" )
			)
			( pin "C9M8.2"
				( objectStatus "@baseboard_fab2_lib.baseboard_fab2(sch_1):page163_i10:b" )
			)
			( pin "C9M7.1"
				( objectStatus "@baseboard_fab2_lib.baseboard_fab2(sch_1):page163_i12:a" )
			)
			( pin "C9M7.2"
				( objectStatus "@baseboard_fab2_lib.baseboard_fab2(sch_1):page163_i12:b" )
			)
			( pin "R9M17.1"
				( objectStatus "@baseboard_fab2_lib.baseboard_fab2(sch_1):page163_i15:a" )
			)
			( pin "R9M17.2"
				( objectStatus "@baseboard_fab2_lib.baseboard_fab2(sch_1):page163_i15:b" )
			)
			( pin "R9M16.1"
				( objectStatus "@baseboard_fab2_lib.baseboard_fab2(sch_1):page163_i16:a" )
			)
			( pin "R9M16.2"
				( objectStatus "@baseboard_fab2_lib.baseboard_fab2(sch_1):page163_i16:b" )
			)
			( pin "R9M14.1"
				( objectStatus "@baseboard_fab2_lib.baseboard_fab2(sch_1):page163_i20:a" )
			)
			( pin "R9M14.2"
				( objectStatus "@baseboard_fab2_lib.baseboard_fab2(sch_1):page163_i20:b" )
			)
			( pin "R9M13.1"
				( objectStatus "@baseboard_fab2_lib.baseboard_fab2(sch_1):page163_i21:a" )
			)
			( pin "R9M13.2"
				( objectStatus "@baseboard_fab2_lib.baseboard_fab2(sch_1):page163_i21:b" )
			)
			( pin "RN8F6.1"
				( objectStatus "@baseboard_fab2_lib.baseboard_fab2(sch_1):page246_i19:\1\" )
			)
			( pin "RN8F6.2"
				( objectStatus "@baseboard_fab2_lib.baseboard_fab2(sch_1):page246_i19:\2\" )
			)
			( pin "R1U24.1"
				( objectStatus "@baseboard_fab2_lib.baseboard_fab2(sch_1):page164_i47:a" )
			)
			( pin "R1U24.2"
				( objectStatus "@baseboard_fab2_lib.baseboard_fab2(sch_1):page164_i47:b" )
			)
			( pin "R1T11.1"
				( objectStatus "@baseboard_fab2_lib.baseboard_fab2(sch_1):page164_i7:a" )
			)
			( pin "R1T11.2"
				( objectStatus "@baseboard_fab2_lib.baseboard_fab2(sch_1):page164_i7:b" )
			)
			( pin "R1T5.1"
				( objectStatus "@baseboard_fab2_lib.baseboard_fab2(sch_1):page164_i11:a" )
			)
			( pin "R1T5.2"
				( objectStatus "@baseboard_fab2_lib.baseboard_fab2(sch_1):page164_i11:b" )
			)
			( pin "R2N17.1"
				( objectStatus "@baseboard_fab2_lib.baseboard_fab2(sch_1):page164_i46:a" )
			)
			( pin "R2N17.2"
				( objectStatus "@baseboard_fab2_lib.baseboard_fab2(sch_1):page164_i46:b" )
			)
			( pin "R1U17.1"
				( objectStatus "@baseboard_fab2_lib.baseboard_fab2(sch_1):page164_i21:a" )
			)
			( pin "R1U17.2"
				( objectStatus "@baseboard_fab2_lib.baseboard_fab2(sch_1):page164_i21:b" )
			)
			( pin "R2N18.1"
				( objectStatus "@baseboard_fab2_lib.baseboard_fab2(sch_1):page164_i32:a" )
			)
			( pin "R2N18.2"
				( objectStatus "@baseboard_fab2_lib.baseboard_fab2(sch_1):page164_i32:b" )
			)
			( pin "R7W3.1"
				( objectStatus "@baseboard_fab2_lib.baseboard_fab2(sch_1):page166_i46:a" )
			)
			( pin "R7W3.2"
				( objectStatus "@baseboard_fab2_lib.baseboard_fab2(sch_1):page166_i46:b" )
			)
			( pin "R7W2.1"
				( objectStatus "@baseboard_fab2_lib.baseboard_fab2(sch_1):page166_i42:a" )
			)
			( pin "R7W2.2"
				( objectStatus "@baseboard_fab2_lib.baseboard_fab2(sch_1):page166_i42:b" )
			)
			( pin "R7C17.1"
				( objectStatus "@baseboard_fab2_lib.baseboard_fab2(sch_1):page166_i28:a" )
			)
			( pin "R7C17.2"
				( objectStatus "@baseboard_fab2_lib.baseboard_fab2(sch_1):page166_i28:b" )
			)
			( pin "R7D15.1"
				( objectStatus "@baseboard_fab2_lib.baseboard_fab2(sch_1):page166_i32:a" )
			)
			( pin "R7D15.2"
				( objectStatus "@baseboard_fab2_lib.baseboard_fab2(sch_1):page166_i32:b" )
			)
			( pin "U9B4.4"
				( objectStatus "@baseboard_fab2_lib.baseboard_fab2(sch_1):page167_i1:a(0)" )
			)
			( pin "U9B4.3"
				( objectStatus "@baseboard_fab2_lib.baseboard_fab2(sch_1):page167_i1:a(1)" )
			)
			( pin "U9B4.2"
				( objectStatus "@baseboard_fab2_lib.baseboard_fab2(sch_1):page167_i1:dxn" )
			)
			( pin "U9B4.1"
				( objectStatus "@baseboard_fab2_lib.baseboard_fab2(sch_1):page167_i1:dxp" )
			)
			( pin "U9B4.5"
				( objectStatus "@baseboard_fab2_lib.baseboard_fab2(sch_1):page167_i1:gnd" )
			)
			( pin "U9B4.7"
				( objectStatus "@baseboard_fab2_lib.baseboard_fab2(sch_1):page167_i1:scl" )
			)
			( pin "U9B4.6"
				( objectStatus "@baseboard_fab2_lib.baseboard_fab2(sch_1):page167_i1:sda" )
			)
			( pin "U9B4.8"
				( objectStatus "@baseboard_fab2_lib.baseboard_fab2(sch_1):page167_i1:vp" )
			)
			( pin "R9B5.1"
				( objectStatus "@baseboard_fab2_lib.baseboard_fab2(sch_1):page167_i5:a" )
			)
			( pin "R9B5.2"
				( objectStatus "@baseboard_fab2_lib.baseboard_fab2(sch_1):page167_i5:b" )
			)
			( pin "R9B4.1"
				( objectStatus "@baseboard_fab2_lib.baseboard_fab2(sch_1):page167_i6:a" )
			)
			( pin "R9B4.2"
				( objectStatus "@baseboard_fab2_lib.baseboard_fab2(sch_1):page167_i6:b" )
			)
			( pin "C1M4.1"
				( objectStatus "@baseboard_fab2_lib.baseboard_fab2(sch_1):page167_i7:a" )
			)
			( pin "C1M4.2"
				( objectStatus "@baseboard_fab2_lib.baseboard_fab2(sch_1):page167_i7:b" )
			)
			( pin "R1M9.1"
				( objectStatus "@baseboard_fab2_lib.baseboard_fab2(sch_1):page167_i8:a" )
			)
			( pin "R1M9.2"
				( objectStatus "@baseboard_fab2_lib.baseboard_fab2(sch_1):page167_i8:b" )
			)
			( pin "R9B8.1"
				( objectStatus "@baseboard_fab2_lib.baseboard_fab2(sch_1):page167_i10:a" )
			)
			( pin "R9B8.2"
				( objectStatus "@baseboard_fab2_lib.baseboard_fab2(sch_1):page167_i10:b" )
			)
			( pin "C1E19.1"
				( objectStatus "@baseboard_fab2_lib.baseboard_fab2(sch_1):page167_i24:a" )
			)
			( pin "C1E19.2"
				( objectStatus "@baseboard_fab2_lib.baseboard_fab2(sch_1):page167_i24:b" )
			)
			( pin "R9R5.1"
				( objectStatus "@baseboard_fab2_lib.baseboard_fab2(sch_1):page167_i25:a" )
			)
			( pin "R9R5.2"
				( objectStatus "@baseboard_fab2_lib.baseboard_fab2(sch_1):page167_i25:b" )
			)
			( pin "R9R6.1"
				( objectStatus "@baseboard_fab2_lib.baseboard_fab2(sch_1):page167_i26:a" )
			)
			( pin "R9R6.2"
				( objectStatus "@baseboard_fab2_lib.baseboard_fab2(sch_1):page167_i26:b" )
			)
			( pin "U1E1.4"
				( objectStatus "@baseboard_fab2_lib.baseboard_fab2(sch_1):page167_i30:a(0)" )
			)
			( pin "U1E1.3"
				( objectStatus "@baseboard_fab2_lib.baseboard_fab2(sch_1):page167_i30:a(1)" )
			)
			( pin "U1E1.2"
				( objectStatus "@baseboard_fab2_lib.baseboard_fab2(sch_1):page167_i30:dxn" )
			)
			( pin "U1E1.1"
				( objectStatus "@baseboard_fab2_lib.baseboard_fab2(sch_1):page167_i30:dxp" )
			)
			( pin "U1E1.5"
				( objectStatus "@baseboard_fab2_lib.baseboard_fab2(sch_1):page167_i30:gnd" )
			)
			( pin "U1E1.7"
				( objectStatus "@baseboard_fab2_lib.baseboard_fab2(sch_1):page167_i30:scl" )
			)
			( pin "U1E1.6"
				( objectStatus "@baseboard_fab2_lib.baseboard_fab2(sch_1):page167_i30:sda" )
			)
			( pin "U1E1.8"
				( objectStatus "@baseboard_fab2_lib.baseboard_fab2(sch_1):page167_i30:vp" )
			)
			( pin "R1E9.1"
				( objectStatus "@baseboard_fab2_lib.baseboard_fab2(sch_1):page167_i34:a" )
			)
			( pin "R1E9.2"
				( objectStatus "@baseboard_fab2_lib.baseboard_fab2(sch_1):page167_i34:b" )
			)
			( pin "R9B6.1"
				( objectStatus "@baseboard_fab2_lib.baseboard_fab2(sch_1):page167_i35:a" )
			)
			( pin "R9B6.2"
				( objectStatus "@baseboard_fab2_lib.baseboard_fab2(sch_1):page167_i35:b" )
			)
			( pin "R1E10.1"
				( objectStatus "@baseboard_fab2_lib.baseboard_fab2(sch_1):page167_i38:a" )
			)
			( pin "R1E10.2"
				( objectStatus "@baseboard_fab2_lib.baseboard_fab2(sch_1):page167_i38:b" )
			)
			( pin "C9B7.1"
				( objectStatus "@baseboard_fab2_lib.baseboard_fab2(sch_1):page167_i39:a" )
			)
			( pin "C9B7.2"
				( objectStatus "@baseboard_fab2_lib.baseboard_fab2(sch_1):page167_i39:b" )
			)
			( pin "C9R14.1"
				( objectStatus "@baseboard_fab2_lib.baseboard_fab2(sch_1):page167_i41:a" )
			)
			( pin "C9R14.2"
				( objectStatus "@baseboard_fab2_lib.baseboard_fab2(sch_1):page167_i41:b" )
			)
			( pin "C9R13.1"
				( objectStatus "@baseboard_fab2_lib.baseboard_fab2(sch_1):page167_i42:a" )
			)
			( pin "C9R13.2"
				( objectStatus "@baseboard_fab2_lib.baseboard_fab2(sch_1):page167_i42:b" )
			)
			( pin "U8D4.1"
				( objectStatus "@baseboard_fab2_lib.baseboard_fab2(sch_1):page167_i49:a0" )
			)
			( pin "U8D4.2"
				( objectStatus "@baseboard_fab2_lib.baseboard_fab2(sch_1):page167_i49:a1" )
			)
			( pin "U8D4.3"
				( objectStatus "@baseboard_fab2_lib.baseboard_fab2(sch_1):page167_i49:a2" )
			)
			( pin "U8D4.6"
				( objectStatus "@baseboard_fab2_lib.baseboard_fab2(sch_1):page167_i49:scl" )
			)
			( pin "U8D4.5"
				( objectStatus "@baseboard_fab2_lib.baseboard_fab2(sch_1):page167_i49:sda" )
			)
			( pin "U8D4.7"
				( objectStatus "@baseboard_fab2_lib.baseboard_fab2(sch_1):page167_i49:wp" )
			)
			( pin "R8D27.1"
				( objectStatus "@baseboard_fab2_lib.baseboard_fab2(sch_1):page167_i50:a" )
			)
			( pin "R8D27.2"
				( objectStatus "@baseboard_fab2_lib.baseboard_fab2(sch_1):page167_i50:b" )
			)
			( pin "R9G15.1"
				( objectStatus "@baseboard_fab2_lib.baseboard_fab2(sch_1):page167_i58:a" )
			)
			( pin "R9G15.2"
				( objectStatus "@baseboard_fab2_lib.baseboard_fab2(sch_1):page167_i58:b" )
			)
			( pin "R8D28.1"
				( objectStatus "@baseboard_fab2_lib.baseboard_fab2(sch_1):page167_i70:a" )
			)
			( pin "R8D28.2"
				( objectStatus "@baseboard_fab2_lib.baseboard_fab2(sch_1):page167_i70:b" )
			)
			( pin "R1M8.1"
				( objectStatus "@baseboard_fab2_lib.baseboard_fab2(sch_1):page167_i74:a" )
			)
			( pin "R1M8.2"
				( objectStatus "@baseboard_fab2_lib.baseboard_fab2(sch_1):page167_i74:b" )
			)
			( pin "R9R7.1"
				( objectStatus "@baseboard_fab2_lib.baseboard_fab2(sch_1):page167_i75:a" )
			)
			( pin "R9R7.2"
				( objectStatus "@baseboard_fab2_lib.baseboard_fab2(sch_1):page167_i75:b" )
			)
			( pin "R9R8.1"
				( objectStatus "@baseboard_fab2_lib.baseboard_fab2(sch_1):page167_i76:a" )
			)
			( pin "R9R8.2"
				( objectStatus "@baseboard_fab2_lib.baseboard_fab2(sch_1):page167_i76:b" )
			)
			( pin "R9G14.1"
				( objectStatus "@baseboard_fab2_lib.baseboard_fab2(sch_1):page167_i77:a" )
			)
			( pin "R9G14.2"
				( objectStatus "@baseboard_fab2_lib.baseboard_fab2(sch_1):page167_i77:b" )
			)
			( pin "R2U38.1"
				( objectStatus "@baseboard_fab2_lib.baseboard_fab2(sch_1):page167_i80:a" )
			)
			( pin "R2U38.2"
				( objectStatus "@baseboard_fab2_lib.baseboard_fab2(sch_1):page167_i80:b" )
			)
			( pin "R2U39.1"
				( objectStatus "@baseboard_fab2_lib.baseboard_fab2(sch_1):page167_i83:a" )
			)
			( pin "R2U39.2"
				( objectStatus "@baseboard_fab2_lib.baseboard_fab2(sch_1):page167_i83:b" )
			)
			( pin "R8D24.1"
				( objectStatus "@baseboard_fab2_lib.baseboard_fab2(sch_1):page167_i84:a" )
			)
			( pin "R8D24.2"
				( objectStatus "@baseboard_fab2_lib.baseboard_fab2(sch_1):page167_i84:b" )
			)
			( pin "R8D23.1"
				( objectStatus "@baseboard_fab2_lib.baseboard_fab2(sch_1):page167_i85:a" )
			)
			( pin "R8D23.2"
				( objectStatus "@baseboard_fab2_lib.baseboard_fab2(sch_1):page167_i85:b" )
			)
			( pin "CR1L1.2"
				( objectStatus "@baseboard_fab2_lib.baseboard_fab2(sch_1):page168_i2:a" )
			)
			( pin "CR1L1.1"
				( objectStatus "@baseboard_fab2_lib.baseboard_fab2(sch_1):page168_i2:c" )
			)
			( pin "CR1L2.2"
				( objectStatus "@baseboard_fab2_lib.baseboard_fab2(sch_1):page168_i3:a" )
			)
			( pin "CR1L2.1"
				( objectStatus "@baseboard_fab2_lib.baseboard_fab2(sch_1):page168_i3:c" )
			)
			( pin "CR1L3.2"
				( objectStatus "@baseboard_fab2_lib.baseboard_fab2(sch_1):page168_i4:a" )
			)
			( pin "CR1L3.1"
				( objectStatus "@baseboard_fab2_lib.baseboard_fab2(sch_1):page168_i4:c" )
			)
			( pin "CR1L4.2"
				( objectStatus "@baseboard_fab2_lib.baseboard_fab2(sch_1):page168_i5:a" )
			)
			( pin "CR1L4.1"
				( objectStatus "@baseboard_fab2_lib.baseboard_fab2(sch_1):page168_i5:c" )
			)
			( pin "R1L6.1"
				( objectStatus "@baseboard_fab2_lib.baseboard_fab2(sch_1):page168_i6:a" )
			)
			( pin "R1L6.2"
				( objectStatus "@baseboard_fab2_lib.baseboard_fab2(sch_1):page168_i6:b" )
			)
			( pin "Q1L3.1"
				( objectStatus "@baseboard_fab2_lib.baseboard_fab2(sch_1):page168_i8:b" )
			)
			( pin "Q1L3.3"
				( objectStatus "@baseboard_fab2_lib.baseboard_fab2(sch_1):page168_i8:c" )
			)
			( pin "Q1L3.2"
				( objectStatus "@baseboard_fab2_lib.baseboard_fab2(sch_1):page168_i8:e" )
			)
			( pin "R1L36.1"
				( objectStatus "@baseboard_fab2_lib.baseboard_fab2(sch_1):page168_i11:a" )
			)
			( pin "R1L36.2"
				( objectStatus "@baseboard_fab2_lib.baseboard_fab2(sch_1):page168_i11:b" )
			)
			( pin "Q1L4.3"
				( objectStatus "@baseboard_fab2_lib.baseboard_fab2(sch_1):page168_i18:drain(0)" )
			)
			( pin "Q1L4.5"
				( objectStatus "@baseboard_fab2_lib.baseboard_fab2(sch_1):page168_i18:gate(0)" )
			)
			( pin "Q1L4.4"
				( objectStatus "@baseboard_fab2_lib.baseboard_fab2(sch_1):page168_i18:source(0)" )
			)
			( pin "Q1L4.6"
				( objectStatus "@baseboard_fab2_lib.baseboard_fab2(sch_1):page168_i19:drain(0)" )
			)
			( pin "Q1L4.2"
				( objectStatus "@baseboard_fab2_lib.baseboard_fab2(sch_1):page168_i19:gate(0)" )
			)
			( pin "Q1L4.1"
				( objectStatus "@baseboard_fab2_lib.baseboard_fab2(sch_1):page168_i19:source(0)" )
			)
			( pin "R1L38.1"
				( objectStatus "@baseboard_fab2_lib.baseboard_fab2(sch_1):page168_i22:a" )
			)
			( pin "R1L38.2"
				( objectStatus "@baseboard_fab2_lib.baseboard_fab2(sch_1):page168_i22:b" )
			)
			( pin "C1U21.1"
				( objectStatus "@baseboard_fab2_lib.baseboard_fab2(sch_1):page169_i56:a" )
			)
			( pin "C1U21.2"
				( objectStatus "@baseboard_fab2_lib.baseboard_fab2(sch_1):page169_i56:b" )
			)
			( pin "FB1U3.1"
				( objectStatus "@baseboard_fab2_lib.baseboard_fab2(sch_1):page169_i57:a" )
			)
			( pin "FB1U3.2"
				( objectStatus "@baseboard_fab2_lib.baseboard_fab2(sch_1):page169_i57:b" )
			)
			( pin "C9G21.1"
				( objectStatus "@baseboard_fab2_lib.baseboard_fab2(sch_1):page169_i68:a" )
			)
			( pin "C9G21.2"
				( objectStatus "@baseboard_fab2_lib.baseboard_fab2(sch_1):page169_i68:b" )
			)
			( pin "C9G17.1"
				( objectStatus "@baseboard_fab2_lib.baseboard_fab2(sch_1):page169_i80:a" )
			)
			( pin "C9G17.2"
				( objectStatus "@baseboard_fab2_lib.baseboard_fab2(sch_1):page169_i80:b" )
			)
			( pin "R1U32.1"
				( objectStatus "@baseboard_fab2_lib.baseboard_fab2(sch_1):page169_i82:a" )
			)
			( pin "R1U32.2"
				( objectStatus "@baseboard_fab2_lib.baseboard_fab2(sch_1):page169_i82:b" )
			)
			( pin "C9G20.1"
				( objectStatus "@baseboard_fab2_lib.baseboard_fab2(sch_1):page169_i86:a" )
			)
			( pin "C9G20.2"
				( objectStatus "@baseboard_fab2_lib.baseboard_fab2(sch_1):page169_i86:b" )
			)
			( pin "R1U39.1"
				( objectStatus "@baseboard_fab2_lib.baseboard_fab2(sch_1):page169_i88:a" )
			)
			( pin "R1U39.2"
				( objectStatus "@baseboard_fab2_lib.baseboard_fab2(sch_1):page169_i88:b" )
			)
			( pin "R9G26.1"
				( objectStatus "@baseboard_fab2_lib.baseboard_fab2(sch_1):page169_i106:a" )
			)
			( pin "R9G26.2"
				( objectStatus "@baseboard_fab2_lib.baseboard_fab2(sch_1):page169_i106:b" )
			)
			( pin "C9G22.1"
				( objectStatus "@baseboard_fab2_lib.baseboard_fab2(sch_1):page169_i108:a" )
			)
			( pin "C9G22.2"
				( objectStatus "@baseboard_fab2_lib.baseboard_fab2(sch_1):page169_i108:b" )
			)
			( pin "R1U44.1"
				( objectStatus "@baseboard_fab2_lib.baseboard_fab2(sch_1):page169_i170:\1\" )
			)
			( pin "R1U44.2"
				( objectStatus "@baseboard_fab2_lib.baseboard_fab2(sch_1):page169_i170:\2\" )
			)
			( pin "R1U47.1"
				( objectStatus "@baseboard_fab2_lib.baseboard_fab2(sch_1):page169_i115:a" )
			)
			( pin "R1U47.2"
				( objectStatus "@baseboard_fab2_lib.baseboard_fab2(sch_1):page169_i115:b" )
			)
			( pin "R1U50.1"
				( objectStatus "@baseboard_fab2_lib.baseboard_fab2(sch_1):page169_i126:a" )
			)
			( pin "R1U50.2"
				( objectStatus "@baseboard_fab2_lib.baseboard_fab2(sch_1):page169_i126:b" )
			)
			( pin "C9G15.1"
				( objectStatus "@baseboard_fab2_lib.baseboard_fab2(sch_1):page169_i139:a" )
			)
			( pin "C9G15.2"
				( objectStatus "@baseboard_fab2_lib.baseboard_fab2(sch_1):page169_i139:b" )
			)
			( pin "R1U29.1"
				( objectStatus "@baseboard_fab2_lib.baseboard_fab2(sch_1):page169_i141:a" )
			)
			( pin "R1U29.2"
				( objectStatus "@baseboard_fab2_lib.baseboard_fab2(sch_1):page169_i141:b" )
			)
			( pin "C9G14.1"
				( objectStatus "@baseboard_fab2_lib.baseboard_fab2(sch_1):page169_i146:a" )
			)
			( pin "C9G14.2"
				( objectStatus "@baseboard_fab2_lib.baseboard_fab2(sch_1):page169_i146:b" )
			)
			( pin "R1U26.1"
				( objectStatus "@baseboard_fab2_lib.baseboard_fab2(sch_1):page169_i148:a" )
			)
			( pin "R1U26.2"
				( objectStatus "@baseboard_fab2_lib.baseboard_fab2(sch_1):page169_i148:b" )
			)
			( pin "R1U28.1"
				( objectStatus "@baseboard_fab2_lib.baseboard_fab2(sch_1):page169_i169:\1\" )
			)
			( pin "R1U28.2"
				( objectStatus "@baseboard_fab2_lib.baseboard_fab2(sch_1):page169_i169:\2\" )
			)
			( pin "C9G18.1"
				( objectStatus "@baseboard_fab2_lib.baseboard_fab2(sch_1):page169_i153:a" )
			)
			( pin "C9G18.2"
				( objectStatus "@baseboard_fab2_lib.baseboard_fab2(sch_1):page169_i153:b" )
			)
			( pin "FB1U4.1"
				( objectStatus "@baseboard_fab2_lib.baseboard_fab2(sch_1):page169_i155:a" )
			)
			( pin "FB1U4.2"
				( objectStatus "@baseboard_fab2_lib.baseboard_fab2(sch_1):page169_i155:b" )
			)
			( pin "Q9G1.3"
				( objectStatus "@baseboard_fab2_lib.baseboard_fab2(sch_1):page169_i157:drain(0)" )
			)
			( pin "Q9G1.5"
				( objectStatus "@baseboard_fab2_lib.baseboard_fab2(sch_1):page169_i157:gate(0)" )
			)
			( pin "Q9G1.4"
				( objectStatus "@baseboard_fab2_lib.baseboard_fab2(sch_1):page169_i157:source(0)" )
			)
			( pin "Q9G1.6"
				( objectStatus "@baseboard_fab2_lib.baseboard_fab2(sch_1):page169_i162:drain(0)" )
			)
			( pin "Q9G1.2"
				( objectStatus "@baseboard_fab2_lib.baseboard_fab2(sch_1):page169_i162:gate(0)" )
			)
			( pin "Q9G1.1"
				( objectStatus "@baseboard_fab2_lib.baseboard_fab2(sch_1):page169_i162:source(0)" )
			)
			( pin "R1U49.1"
				( objectStatus "@baseboard_fab2_lib.baseboard_fab2(sch_1):page169_i163:a" )
			)
			( pin "R1U49.2"
				( objectStatus "@baseboard_fab2_lib.baseboard_fab2(sch_1):page169_i163:b" )
			)
			( pin "R9G35.1"
				( objectStatus "@baseboard_fab2_lib.baseboard_fab2(sch_1):page169_i164:a" )
			)
			( pin "R9G35.2"
				( objectStatus "@baseboard_fab2_lib.baseboard_fab2(sch_1):page169_i164:b" )
			)
			( pin "R2P3.1"
				( objectStatus "@baseboard_fab2_lib.baseboard_fab2(sch_1):page170_i2:a" )
			)
			( pin "R2P3.2"
				( objectStatus "@baseboard_fab2_lib.baseboard_fab2(sch_1):page170_i2:b" )
			)
			( pin "U8D3.2"
				( objectStatus "@baseboard_fab2_lib.baseboard_fab2(sch_1):page170_i4:a" )
			)
			( pin "U8D3.4"
				( objectStatus "@baseboard_fab2_lib.baseboard_fab2(sch_1):page170_i4:y" )
			)
			( pin "C2P1.1"
				( objectStatus "@baseboard_fab2_lib.baseboard_fab2(sch_1):page170_i8:a" )
			)
			( pin "C2P1.2"
				( objectStatus "@baseboard_fab2_lib.baseboard_fab2(sch_1):page170_i8:b" )
			)
			( pin "U8E1.1"
				( objectStatus "@baseboard_fab2_lib.baseboard_fab2(sch_1):page170_i10:a(0)" )
			)
			( pin "U8E1.2"
				( objectStatus "@baseboard_fab2_lib.baseboard_fab2(sch_1):page170_i10:b(0)" )
			)
			( pin "U8E1.3"
				( objectStatus "@baseboard_fab2_lib.baseboard_fab2(sch_1):page170_i10:y(0)" )
			)
			( pin "U8E1.4"
				( objectStatus "@baseboard_fab2_lib.baseboard_fab2(sch_1):page170_i11:a(0)" )
			)
			( pin "U8E1.5"
				( objectStatus "@baseboard_fab2_lib.baseboard_fab2(sch_1):page170_i11:b(0)" )
			)
			( pin "U8E1.6"
				( objectStatus "@baseboard_fab2_lib.baseboard_fab2(sch_1):page170_i11:y(0)" )
			)
			( pin "U8E1.12"
				( objectStatus "@baseboard_fab2_lib.baseboard_fab2(sch_1):page170_i12:a(0)" )
			)
			( pin "U8E1.13"
				( objectStatus "@baseboard_fab2_lib.baseboard_fab2(sch_1):page170_i12:b(0)" )
			)
			( pin "U8E1.11"
				( objectStatus "@baseboard_fab2_lib.baseboard_fab2(sch_1):page170_i12:y(0)" )
			)
			( pin "U1R2.2"
				( objectStatus "@baseboard_fab2_lib.baseboard_fab2(sch_1):page170_i20:a" )
			)
			( pin "U1R2.1"
				( objectStatus "@baseboard_fab2_lib.baseboard_fab2(sch_1):page170_i20:oe" )
			)
			( pin "U1R2.4"
				( objectStatus "@baseboard_fab2_lib.baseboard_fab2(sch_1):page170_i20:y" )
			)
			( pin "C1R27.1"
				( objectStatus "@baseboard_fab2_lib.baseboard_fab2(sch_1):page170_i30:a" )
			)
			( pin "C1R27.2"
				( objectStatus "@baseboard_fab2_lib.baseboard_fab2(sch_1):page170_i30:b" )
			)
			( pin "C8D2.1"
				( objectStatus "@baseboard_fab2_lib.baseboard_fab2(sch_1):page170_i33:a" )
			)
			( pin "C8D2.2"
				( objectStatus "@baseboard_fab2_lib.baseboard_fab2(sch_1):page170_i33:b" )
			)
			( pin "U8D5.2"
				( objectStatus "@baseboard_fab2_lib.baseboard_fab2(sch_1):page170_i38:a" )
			)
			( pin "U8D5.1"
				( objectStatus "@baseboard_fab2_lib.baseboard_fab2(sch_1):page170_i38:oe" )
			)
			( pin "U8D5.4"
				( objectStatus "@baseboard_fab2_lib.baseboard_fab2(sch_1):page170_i38:y" )
			)
			( pin "C8E2.1"
				( objectStatus "@baseboard_fab2_lib.baseboard_fab2(sch_1):page170_i40:a" )
			)
			( pin "C8E2.2"
				( objectStatus "@baseboard_fab2_lib.baseboard_fab2(sch_1):page170_i40:b" )
			)
			( pin "C8D3.1"
				( objectStatus "@baseboard_fab2_lib.baseboard_fab2(sch_1):page170_i42:a" )
			)
			( pin "C8D3.2"
				( objectStatus "@baseboard_fab2_lib.baseboard_fab2(sch_1):page170_i42:b" )
			)
			( pin "U1R1.2"
				( objectStatus "@baseboard_fab2_lib.baseboard_fab2(sch_1):page170_i46:a" )
			)
			( pin "U1R1.4"
				( objectStatus "@baseboard_fab2_lib.baseboard_fab2(sch_1):page170_i46:y" )
			)
			( pin "C1R28.1"
				( objectStatus "@baseboard_fab2_lib.baseboard_fab2(sch_1):page170_i49:a" )
			)
			( pin "C1R28.2"
				( objectStatus "@baseboard_fab2_lib.baseboard_fab2(sch_1):page170_i49:b" )
			)
			( pin "R1R8.1"
				( objectStatus "@baseboard_fab2_lib.baseboard_fab2(sch_1):page170_i51:a" )
			)
			( pin "R1R8.2"
				( objectStatus "@baseboard_fab2_lib.baseboard_fab2(sch_1):page170_i51:b" )
			)
			( pin "R2T3.1"
				( objectStatus "@baseboard_fab2_lib.baseboard_fab2(sch_1):page170_i54:a" )
			)
			( pin "R2T3.2"
				( objectStatus "@baseboard_fab2_lib.baseboard_fab2(sch_1):page170_i54:b" )
			)
			( pin "R2P5.1"
				( objectStatus "@baseboard_fab2_lib.baseboard_fab2(sch_1):page170_i56:a" )
			)
			( pin "R2P5.2"
				( objectStatus "@baseboard_fab2_lib.baseboard_fab2(sch_1):page170_i56:b" )
			)
			( pin "Q2P1.3"
				( objectStatus "@baseboard_fab2_lib.baseboard_fab2(sch_1):page170_i58:drn" )
			)
			( pin "Q2P1.1"
				( objectStatus "@baseboard_fab2_lib.baseboard_fab2(sch_1):page170_i58:gate" )
			)
			( pin "Q2P1.2"
				( objectStatus "@baseboard_fab2_lib.baseboard_fab2(sch_1):page170_i58:src" )
			)
			( pin "R2P13.1"
				( objectStatus "@baseboard_fab2_lib.baseboard_fab2(sch_1):page170_i61:a" )
			)
			( pin "R2P13.2"
				( objectStatus "@baseboard_fab2_lib.baseboard_fab2(sch_1):page170_i61:b" )
			)
			( pin "R2P11.1"
				( objectStatus "@baseboard_fab2_lib.baseboard_fab2(sch_1):page170_i63:a" )
			)
			( pin "R2P11.2"
				( objectStatus "@baseboard_fab2_lib.baseboard_fab2(sch_1):page170_i63:b" )
			)
			( pin "R9F3.1"
				( objectStatus "@baseboard_fab2_lib.baseboard_fab2(sch_1):page170_i65:a" )
			)
			( pin "R9F3.2"
				( objectStatus "@baseboard_fab2_lib.baseboard_fab2(sch_1):page170_i65:b" )
			)
			( pin "Q8F2.3"
				( objectStatus "@baseboard_fab2_lib.baseboard_fab2(sch_1):page170_i67:drn" )
			)
			( pin "Q8F2.1"
				( objectStatus "@baseboard_fab2_lib.baseboard_fab2(sch_1):page170_i67:gate" )
			)
			( pin "Q8F2.2"
				( objectStatus "@baseboard_fab2_lib.baseboard_fab2(sch_1):page170_i67:src" )
			)
			( pin "R8D26.1"
				( objectStatus "@baseboard_fab2_lib.baseboard_fab2(sch_1):page170_i71:a" )
			)
			( pin "R8D26.2"
				( objectStatus "@baseboard_fab2_lib.baseboard_fab2(sch_1):page170_i71:b" )
			)
			( pin "R1R5.1"
				( objectStatus "@baseboard_fab2_lib.baseboard_fab2(sch_1):page170_i73:a" )
			)
			( pin "R1R5.2"
				( objectStatus "@baseboard_fab2_lib.baseboard_fab2(sch_1):page170_i73:b" )
			)
			( pin "R2P4.1"
				( objectStatus "@baseboard_fab2_lib.baseboard_fab2(sch_1):page170_i74:a" )
			)
			( pin "R2P4.2"
				( objectStatus "@baseboard_fab2_lib.baseboard_fab2(sch_1):page170_i74:b" )
			)
			( pin "C2L49.1"
				( objectStatus "@baseboard_fab2_lib.baseboard_fab2(sch_1):page172_i5:a" )
			)
			( pin "C2L49.2"
				( objectStatus "@baseboard_fab2_lib.baseboard_fab2(sch_1):page172_i5:b" )
			)
			( pin "C2L52.1"
				( objectStatus "@baseboard_fab2_lib.baseboard_fab2(sch_1):page172_i6:a" )
			)
			( pin "C2L52.2"
				( objectStatus "@baseboard_fab2_lib.baseboard_fab2(sch_1):page172_i6:b" )
			)
			( pin "C2L50.1"
				( objectStatus "@baseboard_fab2_lib.baseboard_fab2(sch_1):page172_i7:a" )
			)
			( pin "C2L50.2"
				( objectStatus "@baseboard_fab2_lib.baseboard_fab2(sch_1):page172_i7:b" )
			)
			( pin "C2L51.1"
				( objectStatus "@baseboard_fab2_lib.baseboard_fab2(sch_1):page172_i8:a" )
			)
			( pin "C2L51.2"
				( objectStatus "@baseboard_fab2_lib.baseboard_fab2(sch_1):page172_i8:b" )
			)
			( pin "C9B2.1"
				( objectStatus "@baseboard_fab2_lib.baseboard_fab2(sch_1):page172_i36:a" )
			)
			( pin "C9B2.2"
				( objectStatus "@baseboard_fab2_lib.baseboard_fab2(sch_1):page172_i36:b" )
			)
			( pin "C9B1.1"
				( objectStatus "@baseboard_fab2_lib.baseboard_fab2(sch_1):page172_i39:a" )
			)
			( pin "C9B1.2"
				( objectStatus "@baseboard_fab2_lib.baseboard_fab2(sch_1):page172_i39:b" )
			)
			( pin "R25W108.1"
				( objectStatus "@baseboard_fab2_lib.baseboard_fab2(sch_1):page150_i191:a" )
			)
			( pin "R25W108.2"
				( objectStatus "@baseboard_fab2_lib.baseboard_fab2(sch_1):page150_i191:b" )
			)
			( pin "R25W116.1"
				( objectStatus "@baseboard_fab2_lib.baseboard_fab2(sch_1):page150_i189:a" )
			)
			( pin "R25W116.2"
				( objectStatus "@baseboard_fab2_lib.baseboard_fab2(sch_1):page150_i189:b" )
			)
			( pin "J8A1.2D9"
				( objectStatus "@baseboard_fab2_lib.baseboard_fab2(sch_1):page173_i163:gnd(0)" )
			)
			( pin "J8A1.2D6"
				( objectStatus "@baseboard_fab2_lib.baseboard_fab2(sch_1):page173_i163:gnd(1)" )
			)
			( pin "J8A1.2D3"
				( objectStatus "@baseboard_fab2_lib.baseboard_fab2(sch_1):page173_i163:gnd(2)" )
			)
			( pin "J8A1.2C9"
				( objectStatus "@baseboard_fab2_lib.baseboard_fab2(sch_1):page173_i163:gnd(3)" )
			)
			( pin "J8A1.2C6"
				( objectStatus "@baseboard_fab2_lib.baseboard_fab2(sch_1):page173_i163:gnd(4)" )
			)
			( pin "J8A1.2C3"
				( objectStatus "@baseboard_fab2_lib.baseboard_fab2(sch_1):page173_i163:gnd(5)" )
			)
			( pin "J8A1.2B9"
				( objectStatus "@baseboard_fab2_lib.baseboard_fab2(sch_1):page173_i163:gnd(6)" )
			)
			( pin "J8A1.2B6"
				( objectStatus "@baseboard_fab2_lib.baseboard_fab2(sch_1):page173_i163:gnd(7)" )
			)
			( pin "J8A1.2B3"
				( objectStatus "@baseboard_fab2_lib.baseboard_fab2(sch_1):page173_i163:gnd(8)" )
			)
			( pin "J8A1.2A9"
				( objectStatus "@baseboard_fab2_lib.baseboard_fab2(sch_1):page173_i163:gnd(9)" )
			)
			( pin "J8A1.2A6"
				( objectStatus "@baseboard_fab2_lib.baseboard_fab2(sch_1):page173_i163:gnd(10)" )
			)
			( pin "J8A1.2A3"
				( objectStatus "@baseboard_fab2_lib.baseboard_fab2(sch_1):page173_i163:gnd(11)" )
			)
			( pin "J8A1.1D9"
				( objectStatus "@baseboard_fab2_lib.baseboard_fab2(sch_1):page173_i163:gnd(12)" )
			)
			( pin "J8A1.1D6"
				( objectStatus "@baseboard_fab2_lib.baseboard_fab2(sch_1):page173_i163:gnd(13)" )
			)
			( pin "J8A1.1D3"
				( objectStatus "@baseboard_fab2_lib.baseboard_fab2(sch_1):page173_i163:gnd(14)" )
			)
			( pin "J8A1.1C9"
				( objectStatus "@baseboard_fab2_lib.baseboard_fab2(sch_1):page173_i163:gnd(15)" )
			)
			( pin "J8A1.1C6"
				( objectStatus "@baseboard_fab2_lib.baseboard_fab2(sch_1):page173_i163:gnd(16)" )
			)
			( pin "J8A1.1C3"
				( objectStatus "@baseboard_fab2_lib.baseboard_fab2(sch_1):page173_i163:gnd(17)" )
			)
			( pin "J8A1.1B9"
				( objectStatus "@baseboard_fab2_lib.baseboard_fab2(sch_1):page173_i163:gnd(18)" )
			)
			( pin "J8A1.1B6"
				( objectStatus "@baseboard_fab2_lib.baseboard_fab2(sch_1):page173_i163:gnd(19)" )
			)
			( pin "J8A1.1B3"
				( objectStatus "@baseboard_fab2_lib.baseboard_fab2(sch_1):page173_i163:gnd(20)" )
			)
			( pin "J8A1.1A9"
				( objectStatus "@baseboard_fab2_lib.baseboard_fab2(sch_1):page173_i163:gnd(21)" )
			)
			( pin "J8A1.1A6"
				( objectStatus "@baseboard_fab2_lib.baseboard_fab2(sch_1):page173_i163:gnd(22)" )
			)
			( pin "J8A1.1A3"
				( objectStatus "@baseboard_fab2_lib.baseboard_fab2(sch_1):page173_i163:gnd(23)" )
			)
			( pin "J8A1.1B5"
				( objectStatus "@baseboard_fab2_lib.baseboard_fab2(sch_1):page173_i163:rxa0_dn" )
			)
			( pin "J8A1.1B4"
				( objectStatus "@baseboard_fab2_lib.baseboard_fab2(sch_1):page173_i163:rxa0_dp" )
			)
			( pin "J8A1.1A5"
				( objectStatus "@baseboard_fab2_lib.baseboard_fab2(sch_1):page173_i163:rxa1_dn" )
			)
			( pin "J8A1.1A4"
				( objectStatus "@baseboard_fab2_lib.baseboard_fab2(sch_1):page173_i163:rxa1_dp" )
			)
			( pin "J8A1.1B8"
				( objectStatus "@baseboard_fab2_lib.baseboard_fab2(sch_1):page173_i163:rxa2_dn" )
			)
			( pin "J8A1.1B7"
				( objectStatus "@baseboard_fab2_lib.baseboard_fab2(sch_1):page173_i163:rxa2_dp" )
			)
			( pin "J8A1.1A8"
				( objectStatus "@baseboard_fab2_lib.baseboard_fab2(sch_1):page173_i163:rxa3_dn" )
			)
			( pin "J8A1.1A7"
				( objectStatus "@baseboard_fab2_lib.baseboard_fab2(sch_1):page173_i163:rxa3_dp" )
			)
			( pin "J8A1.2B5"
				( objectStatus "@baseboard_fab2_lib.baseboard_fab2(sch_1):page173_i163:rxb0_dn" )
			)
			( pin "J8A1.2B4"
				( objectStatus "@baseboard_fab2_lib.baseboard_fab2(sch_1):page173_i163:rxb0_dp" )
			)
			( pin "J8A1.2A5"
				( objectStatus "@baseboard_fab2_lib.baseboard_fab2(sch_1):page173_i163:rxb1_dn" )
			)
			( pin "J8A1.2A4"
				( objectStatus "@baseboard_fab2_lib.baseboard_fab2(sch_1):page173_i163:rxb1_dp" )
			)
			( pin "J8A1.2B8"
				( objectStatus "@baseboard_fab2_lib.baseboard_fab2(sch_1):page173_i163:rxb2_dn" )
			)
			( pin "J8A1.2B7"
				( objectStatus "@baseboard_fab2_lib.baseboard_fab2(sch_1):page173_i163:rxb2_dp" )
			)
			( pin "J8A1.2A8"
				( objectStatus "@baseboard_fab2_lib.baseboard_fab2(sch_1):page173_i163:rxb3_dn" )
			)
			( pin "J8A1.2A7"
				( objectStatus "@baseboard_fab2_lib.baseboard_fab2(sch_1):page173_i163:rxb3_dp" )
			)
			( pin "J8A1.1A2"
				( objectStatus "@baseboard_fab2_lib.baseboard_fab2(sch_1):page173_i163:sidebanda_0" )
			)
			( pin "J8A1.1B2"
				( objectStatus "@baseboard_fab2_lib.baseboard_fab2(sch_1):page173_i163:sidebanda_1" )
			)
			( pin "J8A1.1C2"
				( objectStatus "@baseboard_fab2_lib.baseboard_fab2(sch_1):page173_i163:sidebanda_2" )
			)
			( pin "J8A1.1B1"
				( objectStatus "@baseboard_fab2_lib.baseboard_fab2(sch_1):page173_i163:sidebanda_3" )
			)
			( pin "J8A1.1C1"
				( objectStatus "@baseboard_fab2_lib.baseboard_fab2(sch_1):page173_i163:sidebanda_4" )
			)
			( pin "J8A1.1D1"
				( objectStatus "@baseboard_fab2_lib.baseboard_fab2(sch_1):page173_i163:sidebanda_5" )
			)
			( pin "J8A1.1D2"
				( objectStatus "@baseboard_fab2_lib.baseboard_fab2(sch_1):page173_i163:sidebanda_6" )
			)
			( pin "J8A1.1A1"
				( objectStatus "@baseboard_fab2_lib.baseboard_fab2(sch_1):page173_i163:sidebanda_7" )
			)
			( pin "J8A1.2A2"
				( objectStatus "@baseboard_fab2_lib.baseboard_fab2(sch_1):page173_i163:sidebandb_0" )
			)
			( pin "J8A1.2B2"
				( objectStatus "@baseboard_fab2_lib.baseboard_fab2(sch_1):page173_i163:sidebandb_1" )
			)
			( pin "J8A1.2C2"
				( objectStatus "@baseboard_fab2_lib.baseboard_fab2(sch_1):page173_i163:sidebandb_2" )
			)
			( pin "J8A1.2B1"
				( objectStatus "@baseboard_fab2_lib.baseboard_fab2(sch_1):page173_i163:sidebandb_3" )
			)
			( pin "J8A1.2C1"
				( objectStatus "@baseboard_fab2_lib.baseboard_fab2(sch_1):page173_i163:sidebandb_4" )
			)
			( pin "J8A1.2D1"
				( objectStatus "@baseboard_fab2_lib.baseboard_fab2(sch_1):page173_i163:sidebandb_5" )
			)
			( pin "J8A1.2D2"
				( objectStatus "@baseboard_fab2_lib.baseboard_fab2(sch_1):page173_i163:sidebandb_6" )
			)
			( pin "J8A1.2A1"
				( objectStatus "@baseboard_fab2_lib.baseboard_fab2(sch_1):page173_i163:sidebandb_7" )
			)
			( pin "J8A1.1D5"
				( objectStatus "@baseboard_fab2_lib.baseboard_fab2(sch_1):page173_i163:txa0_dn" )
			)
			( pin "J8A1.1D4"
				( objectStatus "@baseboard_fab2_lib.baseboard_fab2(sch_1):page173_i163:txa0_dp" )
			)
			( pin "J8A1.1C5"
				( objectStatus "@baseboard_fab2_lib.baseboard_fab2(sch_1):page173_i163:txa1_dn" )
			)
			( pin "J8A1.1C4"
				( objectStatus "@baseboard_fab2_lib.baseboard_fab2(sch_1):page173_i163:txa1_dp" )
			)
			( pin "J8A1.1D8"
				( objectStatus "@baseboard_fab2_lib.baseboard_fab2(sch_1):page173_i163:txa2_dn" )
			)
			( pin "J8A1.1D7"
				( objectStatus "@baseboard_fab2_lib.baseboard_fab2(sch_1):page173_i163:txa2_dp" )
			)
			( pin "J8A1.1C8"
				( objectStatus "@baseboard_fab2_lib.baseboard_fab2(sch_1):page173_i163:txa3_dn" )
			)
			( pin "J8A1.1C7"
				( objectStatus "@baseboard_fab2_lib.baseboard_fab2(sch_1):page173_i163:txa3_dp" )
			)
			( pin "J8A1.2D5"
				( objectStatus "@baseboard_fab2_lib.baseboard_fab2(sch_1):page173_i163:txb0_dn" )
			)
			( pin "J8A1.2D4"
				( objectStatus "@baseboard_fab2_lib.baseboard_fab2(sch_1):page173_i163:txb0_dp" )
			)
			( pin "J8A1.2C5"
				( objectStatus "@baseboard_fab2_lib.baseboard_fab2(sch_1):page173_i163:txb1_dn" )
			)
			( pin "J8A1.2C4"
				( objectStatus "@baseboard_fab2_lib.baseboard_fab2(sch_1):page173_i163:txb1_dp" )
			)
			( pin "J8A1.2D8"
				( objectStatus "@baseboard_fab2_lib.baseboard_fab2(sch_1):page173_i163:txb2_dn" )
			)
			( pin "J8A1.2D7"
				( objectStatus "@baseboard_fab2_lib.baseboard_fab2(sch_1):page173_i163:txb2_dp" )
			)
			( pin "J8A1.2C8"
				( objectStatus "@baseboard_fab2_lib.baseboard_fab2(sch_1):page173_i163:txb3_dn" )
			)
			( pin "J8A1.2C7"
				( objectStatus "@baseboard_fab2_lib.baseboard_fab2(sch_1):page173_i163:txb3_dp" )
			)
			( pin "C2L13.1"
				( objectStatus "@baseboard_fab2_lib.baseboard_fab2(sch_1):page173_i165:a" )
			)
			( pin "C2L13.2"
				( objectStatus "@baseboard_fab2_lib.baseboard_fab2(sch_1):page173_i165:b" )
			)
			( pin "C2L6.1"
				( objectStatus "@baseboard_fab2_lib.baseboard_fab2(sch_1):page173_i166:a" )
			)
			( pin "C2L6.2"
				( objectStatus "@baseboard_fab2_lib.baseboard_fab2(sch_1):page173_i166:b" )
			)
			( pin "C2L19.1"
				( objectStatus "@baseboard_fab2_lib.baseboard_fab2(sch_1):page173_i172:a" )
			)
			( pin "C2L19.2"
				( objectStatus "@baseboard_fab2_lib.baseboard_fab2(sch_1):page173_i172:b" )
			)
			( pin "C2L10.1"
				( objectStatus "@baseboard_fab2_lib.baseboard_fab2(sch_1):page173_i173:a" )
			)
			( pin "C2L10.2"
				( objectStatus "@baseboard_fab2_lib.baseboard_fab2(sch_1):page173_i173:b" )
			)
			( pin "C2L17.1"
				( objectStatus "@baseboard_fab2_lib.baseboard_fab2(sch_1):page173_i174:a" )
			)
			( pin "C2L17.2"
				( objectStatus "@baseboard_fab2_lib.baseboard_fab2(sch_1):page173_i174:b" )
			)
			( pin "C2L15.1"
				( objectStatus "@baseboard_fab2_lib.baseboard_fab2(sch_1):page173_i191:a" )
			)
			( pin "C2L15.2"
				( objectStatus "@baseboard_fab2_lib.baseboard_fab2(sch_1):page173_i191:b" )
			)
			( pin "C2L4.1"
				( objectStatus "@baseboard_fab2_lib.baseboard_fab2(sch_1):page173_i192:a" )
			)
			( pin "C2L4.2"
				( objectStatus "@baseboard_fab2_lib.baseboard_fab2(sch_1):page173_i192:b" )
			)
			( pin "C2L3.1"
				( objectStatus "@baseboard_fab2_lib.baseboard_fab2(sch_1):page173_i194:a" )
			)
			( pin "C2L3.2"
				( objectStatus "@baseboard_fab2_lib.baseboard_fab2(sch_1):page173_i194:b" )
			)
			( pin "C2L20.1"
				( objectStatus "@baseboard_fab2_lib.baseboard_fab2(sch_1):page173_i195:a" )
			)
			( pin "C2L20.2"
				( objectStatus "@baseboard_fab2_lib.baseboard_fab2(sch_1):page173_i195:b" )
			)
			( pin "C2L12.1"
				( objectStatus "@baseboard_fab2_lib.baseboard_fab2(sch_1):page173_i196:a" )
			)
			( pin "C2L12.2"
				( objectStatus "@baseboard_fab2_lib.baseboard_fab2(sch_1):page173_i196:b" )
			)
			( pin "C2L18.1"
				( objectStatus "@baseboard_fab2_lib.baseboard_fab2(sch_1):page173_i197:a" )
			)
			( pin "C2L18.2"
				( objectStatus "@baseboard_fab2_lib.baseboard_fab2(sch_1):page173_i197:b" )
			)
			( pin "C2L16.1"
				( objectStatus "@baseboard_fab2_lib.baseboard_fab2(sch_1):page173_i205:a" )
			)
			( pin "C2L16.2"
				( objectStatus "@baseboard_fab2_lib.baseboard_fab2(sch_1):page173_i205:b" )
			)
			( pin "C2L7.1"
				( objectStatus "@baseboard_fab2_lib.baseboard_fab2(sch_1):page173_i206:a" )
			)
			( pin "C2L7.2"
				( objectStatus "@baseboard_fab2_lib.baseboard_fab2(sch_1):page173_i206:b" )
			)
			( pin "C2L9.1"
				( objectStatus "@baseboard_fab2_lib.baseboard_fab2(sch_1):page173_i207:a" )
			)
			( pin "C2L9.2"
				( objectStatus "@baseboard_fab2_lib.baseboard_fab2(sch_1):page173_i207:b" )
			)
			( pin "C2L14.1"
				( objectStatus "@baseboard_fab2_lib.baseboard_fab2(sch_1):page173_i208:a" )
			)
			( pin "C2L14.2"
				( objectStatus "@baseboard_fab2_lib.baseboard_fab2(sch_1):page173_i208:b" )
			)
			( pin "C2L5.1"
				( objectStatus "@baseboard_fab2_lib.baseboard_fab2(sch_1):page173_i209:a" )
			)
			( pin "C2L5.2"
				( objectStatus "@baseboard_fab2_lib.baseboard_fab2(sch_1):page173_i209:b" )
			)
			( pin "C2L40.1"
				( objectStatus "@baseboard_fab2_lib.baseboard_fab2(sch_1):page173_i220:a" )
			)
			( pin "C2L40.2"
				( objectStatus "@baseboard_fab2_lib.baseboard_fab2(sch_1):page173_i220:b" )
			)
			( pin "C2L39.1"
				( objectStatus "@baseboard_fab2_lib.baseboard_fab2(sch_1):page173_i221:a" )
			)
			( pin "C2L39.2"
				( objectStatus "@baseboard_fab2_lib.baseboard_fab2(sch_1):page173_i221:b" )
			)
			( pin "C2L43.1"
				( objectStatus "@baseboard_fab2_lib.baseboard_fab2(sch_1):page173_i222:a" )
			)
			( pin "C2L43.2"
				( objectStatus "@baseboard_fab2_lib.baseboard_fab2(sch_1):page173_i222:b" )
			)
			( pin "C2L44.1"
				( objectStatus "@baseboard_fab2_lib.baseboard_fab2(sch_1):page173_i228:a" )
			)
			( pin "C2L44.2"
				( objectStatus "@baseboard_fab2_lib.baseboard_fab2(sch_1):page173_i228:b" )
			)
			( pin "C2L42.1"
				( objectStatus "@baseboard_fab2_lib.baseboard_fab2(sch_1):page173_i233:a" )
			)
			( pin "C2L42.2"
				( objectStatus "@baseboard_fab2_lib.baseboard_fab2(sch_1):page173_i233:b" )
			)
			( pin "C2L22.1"
				( objectStatus "@baseboard_fab2_lib.baseboard_fab2(sch_1):page173_i234:a" )
			)
			( pin "C2L22.2"
				( objectStatus "@baseboard_fab2_lib.baseboard_fab2(sch_1):page173_i234:b" )
			)
			( pin "C2L37.1"
				( objectStatus "@baseboard_fab2_lib.baseboard_fab2(sch_1):page173_i238:a" )
			)
			( pin "C2L37.2"
				( objectStatus "@baseboard_fab2_lib.baseboard_fab2(sch_1):page173_i238:b" )
			)
			( pin "C2L47.1"
				( objectStatus "@baseboard_fab2_lib.baseboard_fab2(sch_1):page173_i239:a" )
			)
			( pin "C2L47.2"
				( objectStatus "@baseboard_fab2_lib.baseboard_fab2(sch_1):page173_i239:b" )
			)
			( pin "C2L27.1"
				( objectStatus "@baseboard_fab2_lib.baseboard_fab2(sch_1):page173_i240:a" )
			)
			( pin "C2L27.2"
				( objectStatus "@baseboard_fab2_lib.baseboard_fab2(sch_1):page173_i240:b" )
			)
			( pin "C2L23.1"
				( objectStatus "@baseboard_fab2_lib.baseboard_fab2(sch_1):page173_i241:a" )
			)
			( pin "C2L23.2"
				( objectStatus "@baseboard_fab2_lib.baseboard_fab2(sch_1):page173_i241:b" )
			)
			( pin "C2L41.1"
				( objectStatus "@baseboard_fab2_lib.baseboard_fab2(sch_1):page173_i242:a" )
			)
			( pin "C2L41.2"
				( objectStatus "@baseboard_fab2_lib.baseboard_fab2(sch_1):page173_i242:b" )
			)
			( pin "C2L26.1"
				( objectStatus "@baseboard_fab2_lib.baseboard_fab2(sch_1):page173_i255:a" )
			)
			( pin "C2L26.2"
				( objectStatus "@baseboard_fab2_lib.baseboard_fab2(sch_1):page173_i255:b" )
			)
			( pin "C2L38.1"
				( objectStatus "@baseboard_fab2_lib.baseboard_fab2(sch_1):page173_i256:a" )
			)
			( pin "C2L38.2"
				( objectStatus "@baseboard_fab2_lib.baseboard_fab2(sch_1):page173_i256:b" )
			)
			( pin "C2L48.1"
				( objectStatus "@baseboard_fab2_lib.baseboard_fab2(sch_1):page173_i257:a" )
			)
			( pin "C2L48.2"
				( objectStatus "@baseboard_fab2_lib.baseboard_fab2(sch_1):page173_i257:b" )
			)
			( pin "C2L24.1"
				( objectStatus "@baseboard_fab2_lib.baseboard_fab2(sch_1):page173_i258:a" )
			)
			( pin "C2L24.2"
				( objectStatus "@baseboard_fab2_lib.baseboard_fab2(sch_1):page173_i258:b" )
			)
			( pin "C2L21.1"
				( objectStatus "@baseboard_fab2_lib.baseboard_fab2(sch_1):page173_i259:a" )
			)
			( pin "C2L21.2"
				( objectStatus "@baseboard_fab2_lib.baseboard_fab2(sch_1):page173_i259:b" )
			)
			( pin "R2L23.1"
				( objectStatus "@baseboard_fab2_lib.baseboard_fab2(sch_1):page173_i261:a" )
			)
			( pin "R2L23.2"
				( objectStatus "@baseboard_fab2_lib.baseboard_fab2(sch_1):page173_i261:b" )
			)
			( pin "R2L21.1"
				( objectStatus "@baseboard_fab2_lib.baseboard_fab2(sch_1):page173_i263:a" )
			)
			( pin "R2L21.2"
				( objectStatus "@baseboard_fab2_lib.baseboard_fab2(sch_1):page173_i263:b" )
			)
			( pin "R2L22.1"
				( objectStatus "@baseboard_fab2_lib.baseboard_fab2(sch_1):page173_i264:a" )
			)
			( pin "R2L22.2"
				( objectStatus "@baseboard_fab2_lib.baseboard_fab2(sch_1):page173_i264:b" )
			)
			( pin "R2L18.1"
				( objectStatus "@baseboard_fab2_lib.baseboard_fab2(sch_1):page173_i266:a" )
			)
			( pin "R2L18.2"
				( objectStatus "@baseboard_fab2_lib.baseboard_fab2(sch_1):page173_i266:b" )
			)
			( pin "R6W41.1"
				( objectStatus "@baseboard_fab2_lib.baseboard_fab2(sch_1):page164_i87:a" )
			)
			( pin "R6W41.2"
				( objectStatus "@baseboard_fab2_lib.baseboard_fab2(sch_1):page164_i87:b" )
			)
			( pin "C25W29.1"
				( objectStatus "@baseboard_fab2_lib.baseboard_fab2(sch_1):page149_i129:a" )
			)
			( pin "C25W29.2"
				( objectStatus "@baseboard_fab2_lib.baseboard_fab2(sch_1):page149_i129:b" )
			)
			( pin "R6W44.1"
				( objectStatus "@baseboard_fab2_lib.baseboard_fab2(sch_1):page164_i78:a" )
			)
			( pin "R6W44.2"
				( objectStatus "@baseboard_fab2_lib.baseboard_fab2(sch_1):page164_i78:b" )
			)
			( pin "R6W47.1"
				( objectStatus "@baseboard_fab2_lib.baseboard_fab2(sch_1):page164_i76:a" )
			)
			( pin "R6W47.2"
				( objectStatus "@baseboard_fab2_lib.baseboard_fab2(sch_1):page164_i76:b" )
			)
			( pin "C6W14.1"
				( objectStatus "@baseboard_fab2_lib.baseboard_fab2(sch_1):page164_i66:a" )
			)
			( pin "C6W14.2"
				( objectStatus "@baseboard_fab2_lib.baseboard_fab2(sch_1):page164_i66:b" )
			)
			( pin "R1L31.1"
				( objectStatus "@baseboard_fab2_lib.baseboard_fab2(sch_1):page175_i4:a" )
			)
			( pin "R1L31.2"
				( objectStatus "@baseboard_fab2_lib.baseboard_fab2(sch_1):page175_i4:b" )
			)
			( pin "R1L27.1"
				( objectStatus "@baseboard_fab2_lib.baseboard_fab2(sch_1):page175_i5:a" )
			)
			( pin "R1L27.2"
				( objectStatus "@baseboard_fab2_lib.baseboard_fab2(sch_1):page175_i5:b" )
			)
			( pin "C1L18.1"
				( objectStatus "@baseboard_fab2_lib.baseboard_fab2(sch_1):page175_i11:a" )
			)
			( pin "C1L18.2"
				( objectStatus "@baseboard_fab2_lib.baseboard_fab2(sch_1):page175_i11:b" )
			)
			( pin "R1L26.1"
				( objectStatus "@baseboard_fab2_lib.baseboard_fab2(sch_1):page175_i13:a" )
			)
			( pin "R1L26.2"
				( objectStatus "@baseboard_fab2_lib.baseboard_fab2(sch_1):page175_i13:b" )
			)
			( pin "C1L10.1"
				( objectStatus "@baseboard_fab2_lib.baseboard_fab2(sch_1):page175_i19:a" )
			)
			( pin "C1L10.2"
				( objectStatus "@baseboard_fab2_lib.baseboard_fab2(sch_1):page175_i19:b" )
			)
			( pin "R1L22.1"
				( objectStatus "@baseboard_fab2_lib.baseboard_fab2(sch_1):page175_i22:a" )
			)
			( pin "R1L22.2"
				( objectStatus "@baseboard_fab2_lib.baseboard_fab2(sch_1):page175_i22:b" )
			)
			( pin "R1L28.1"
				( objectStatus "@baseboard_fab2_lib.baseboard_fab2(sch_1):page111_i97:a" )
			)
			( pin "R1L28.2"
				( objectStatus "@baseboard_fab2_lib.baseboard_fab2(sch_1):page111_i97:b" )
			)
			( pin "C1L17.1"
				( objectStatus "@baseboard_fab2_lib.baseboard_fab2(sch_1):page175_i37:a" )
			)
			( pin "C1L17.2"
				( objectStatus "@baseboard_fab2_lib.baseboard_fab2(sch_1):page175_i37:b" )
			)
			( pin "C1L9.1"
				( objectStatus "@baseboard_fab2_lib.baseboard_fab2(sch_1):page175_i38:a" )
			)
			( pin "C1L9.2"
				( objectStatus "@baseboard_fab2_lib.baseboard_fab2(sch_1):page175_i38:b" )
			)
			( pin "C9A3.1"
				( objectStatus "@baseboard_fab2_lib.baseboard_fab2(sch_1):page175_i40:a" )
			)
			( pin "C9A3.2"
				( objectStatus "@baseboard_fab2_lib.baseboard_fab2(sch_1):page175_i40:b" )
			)
			( pin "R1L33.1"
				( objectStatus "@baseboard_fab2_lib.baseboard_fab2(sch_1):page175_i45:a" )
			)
			( pin "R1L33.2"
				( objectStatus "@baseboard_fab2_lib.baseboard_fab2(sch_1):page175_i45:b" )
			)
			( pin "Q9A3.3"
				( objectStatus "@baseboard_fab2_lib.baseboard_fab2(sch_1):page175_i49:drn" )
			)
			( pin "Q9A3.1"
				( objectStatus "@baseboard_fab2_lib.baseboard_fab2(sch_1):page175_i49:gate" )
			)
			( pin "Q9A3.2"
				( objectStatus "@baseboard_fab2_lib.baseboard_fab2(sch_1):page175_i49:src" )
			)
			( pin "DS9A1.2"
				( objectStatus "@baseboard_fab2_lib.baseboard_fab2(sch_1):page175_i50:a" )
			)
			( pin "DS9A1.1"
				( objectStatus "@baseboard_fab2_lib.baseboard_fab2(sch_1):page175_i50:c" )
			)
			( pin "U1L2.1"
				( objectStatus "@baseboard_fab2_lib.baseboard_fab2(sch_1):page175_i57:a" )
			)
			( pin "U1L2.2"
				( objectStatus "@baseboard_fab2_lib.baseboard_fab2(sch_1):page175_i57:b" )
			)
			( pin "U1L2.4"
				( objectStatus "@baseboard_fab2_lib.baseboard_fab2(sch_1):page175_i57:y" )
			)
			( pin "R1L8.1"
				( objectStatus "@baseboard_fab2_lib.baseboard_fab2(sch_1):page175_i58:a" )
			)
			( pin "R1L8.2"
				( objectStatus "@baseboard_fab2_lib.baseboard_fab2(sch_1):page175_i58:b" )
			)
			( pin "R1L12.1"
				( objectStatus "@baseboard_fab2_lib.baseboard_fab2(sch_1):page175_i63:a" )
			)
			( pin "R1L12.2"
				( objectStatus "@baseboard_fab2_lib.baseboard_fab2(sch_1):page175_i63:b" )
			)
			( pin "C1L4.1"
				( objectStatus "@baseboard_fab2_lib.baseboard_fab2(sch_1):page175_i64:a" )
			)
			( pin "C1L4.2"
				( objectStatus "@baseboard_fab2_lib.baseboard_fab2(sch_1):page175_i64:b" )
			)
			( pin "DS9A3.2"
				( objectStatus "@baseboard_fab2_lib.baseboard_fab2(sch_1):page175_i67:a" )
			)
			( pin "DS9A3.1"
				( objectStatus "@baseboard_fab2_lib.baseboard_fab2(sch_1):page175_i67:c" )
			)
			( pin "S9A1.1"
				( objectStatus "@baseboard_fab2_lib.baseboard_fab2(sch_1):page175_i78:pin1" )
			)
			( pin "S9A1.2"
				( objectStatus "@baseboard_fab2_lib.baseboard_fab2(sch_1):page175_i78:pin2" )
			)
			( pin "S9A1.3"
				( objectStatus "@baseboard_fab2_lib.baseboard_fab2(sch_1):page175_i78:pin3" )
			)
			( pin "S9A1.4"
				( objectStatus "@baseboard_fab2_lib.baseboard_fab2(sch_1):page175_i78:pin4" )
			)
			( pin "U3T1.16"
				( objectStatus "@baseboard_fab2_lib.baseboard_fab2(sch_1):page153_i185:clk" )
			)
			( pin "U3T1.7"
				( objectStatus "@baseboard_fab2_lib.baseboard_fab2(sch_1):page153_i185:\cs#\" )
			)
			( pin "U3T1.15"
				( objectStatus "@baseboard_fab2_lib.baseboard_fab2(sch_1):page153_i185:\di/io0\" )
			)
			( pin "U3T1.8"
				( objectStatus "@baseboard_fab2_lib.baseboard_fab2(sch_1):page153_i185:\do/io1\" )
			)
			( pin "U3T1.10"
				( objectStatus "@baseboard_fab2_lib.baseboard_fab2(sch_1):page153_i185:gnd" )
			)
			( pin "U3T1.1"
				( objectStatus "@baseboard_fab2_lib.baseboard_fab2(sch_1):page153_i185:\hold#/io3\" )
			)
			( pin "U3T1.4"
				( objectStatus "@baseboard_fab2_lib.baseboard_fab2(sch_1):page153_i185:\nc#4\" )
			)
			( pin "U3T1.5"
				( objectStatus "@baseboard_fab2_lib.baseboard_fab2(sch_1):page153_i185:\nc#5\" )
			)
			( pin "U3T1.6"
				( objectStatus "@baseboard_fab2_lib.baseboard_fab2(sch_1):page153_i185:\nc#6\" )
			)
			( pin "U3T1.11"
				( objectStatus "@baseboard_fab2_lib.baseboard_fab2(sch_1):page153_i185:\nc#11\" )
			)
			( pin "U3T1.12"
				( objectStatus "@baseboard_fab2_lib.baseboard_fab2(sch_1):page153_i185:\nc#12\" )
			)
			( pin "U3T1.13"
				( objectStatus "@baseboard_fab2_lib.baseboard_fab2(sch_1):page153_i185:\nc#13\" )
			)
			( pin "U3T1.14"
				( objectStatus "@baseboard_fab2_lib.baseboard_fab2(sch_1):page153_i185:\nc#14\" )
			)
			( pin "U3T1.3"
				( objectStatus "@baseboard_fab2_lib.baseboard_fab2(sch_1):page153_i185:\reset#\" )
			)
			( pin "U3T1.2"
				( objectStatus "@baseboard_fab2_lib.baseboard_fab2(sch_1):page153_i185:vcc" )
			)
			( pin "U3T1.9"
				( objectStatus "@baseboard_fab2_lib.baseboard_fab2(sch_1):page153_i185:\wp#/io2\" )
			)
			( pin "R1M5.1"
				( objectStatus "@baseboard_fab2_lib.baseboard_fab2(sch_1):page176_i16:a" )
			)
			( pin "R1M5.2"
				( objectStatus "@baseboard_fab2_lib.baseboard_fab2(sch_1):page176_i16:b" )
			)
			( pin "R1M6.1"
				( objectStatus "@baseboard_fab2_lib.baseboard_fab2(sch_1):page176_i31:a" )
			)
			( pin "R1M6.2"
				( objectStatus "@baseboard_fab2_lib.baseboard_fab2(sch_1):page176_i31:b" )
			)
			( pin "J9B1.2"
				( objectStatus "@baseboard_fab2_lib.baseboard_fab2(sch_1):page176_i69:dn" )
			)
			( pin "J9B1.3"
				( objectStatus "@baseboard_fab2_lib.baseboard_fab2(sch_1):page176_i69:dp" )
			)
			( pin "J9B1.4"
				( objectStatus "@baseboard_fab2_lib.baseboard_fab2(sch_1):page176_i69:gnd" )
			)
			( pin "J9B1.7"
				( objectStatus "@baseboard_fab2_lib.baseboard_fab2(sch_1):page176_i69:gnd_drain" )
			)
			( pin "J9B1.MH1"
				( objectStatus "@baseboard_fab2_lib.baseboard_fab2(sch_1):page176_i69:mh1" )
			)
			( pin "J9B1.MH2"
				( objectStatus "@baseboard_fab2_lib.baseboard_fab2(sch_1):page176_i69:mh2" )
			)
			( pin "J9B1.MH3"
				( objectStatus "@baseboard_fab2_lib.baseboard_fab2(sch_1):page176_i69:mh3" )
			)
			( pin "J9B1.MH4"
				( objectStatus "@baseboard_fab2_lib.baseboard_fab2(sch_1):page176_i69:mh4" )
			)
			( pin "J9B1.5"
				( objectStatus "@baseboard_fab2_lib.baseboard_fab2(sch_1):page176_i69:stda_ssrxn" )
			)
			( pin "J9B1.6"
				( objectStatus "@baseboard_fab2_lib.baseboard_fab2(sch_1):page176_i69:stda_ssrxp" )
			)
			( pin "J9B1.8"
				( objectStatus "@baseboard_fab2_lib.baseboard_fab2(sch_1):page176_i69:stda_sstxn" )
			)
			( pin "J9B1.9"
				( objectStatus "@baseboard_fab2_lib.baseboard_fab2(sch_1):page176_i69:stda_sstxp" )
			)
			( pin "J9B1.1"
				( objectStatus "@baseboard_fab2_lib.baseboard_fab2(sch_1):page176_i69:vbus" )
			)
			( pin "CR1M2.1"
				( objectStatus "@baseboard_fab2_lib.baseboard_fab2(sch_1):page176_i98:ac0" )
			)
			( pin "CR1M2.2"
				( objectStatus "@baseboard_fab2_lib.baseboard_fab2(sch_1):page176_i98:ac1" )
			)
			( pin "CR1M2.4"
				( objectStatus "@baseboard_fab2_lib.baseboard_fab2(sch_1):page176_i98:ac2" )
			)
			( pin "CR1M2.5"
				( objectStatus "@baseboard_fab2_lib.baseboard_fab2(sch_1):page176_i98:ac3" )
			)
			( pin "CR1M2.3"
				( objectStatus "@baseboard_fab2_lib.baseboard_fab2(sch_1):page176_i98:gnd(0)" )
			)
			( pin "CR1M2.9"
				( objectStatus "@baseboard_fab2_lib.baseboard_fab2(sch_1):page176_i98:out0" )
			)
			( pin "CR1M2.8"
				( objectStatus "@baseboard_fab2_lib.baseboard_fab2(sch_1):page176_i98:out1" )
			)
			( pin "CR1M2.7"
				( objectStatus "@baseboard_fab2_lib.baseboard_fab2(sch_1):page176_i98:out2" )
			)
			( pin "CR1M2.6"
				( objectStatus "@baseboard_fab2_lib.baseboard_fab2(sch_1):page176_i98:out3" )
			)
			( pin "U1M3.4"
				( objectStatus "@baseboard_fab2_lib.baseboard_fab2(sch_1):page176_i100:en_n" )
			)
			( pin "U1M3.2"
				( objectStatus "@baseboard_fab2_lib.baseboard_fab2(sch_1):page176_i100:gnd" )
			)
			( pin "U1M3.5"
				( objectStatus "@baseboard_fab2_lib.baseboard_fab2(sch_1):page176_i100:\in\" )
			)
			( pin "U1M3.3"
				( objectStatus "@baseboard_fab2_lib.baseboard_fab2(sch_1):page176_i100:oc_n" )
			)
			( pin "U1M3.1"
				( objectStatus "@baseboard_fab2_lib.baseboard_fab2(sch_1):page176_i100:\out\" )
			)
			( pin "R1M24.1"
				( objectStatus "@baseboard_fab2_lib.baseboard_fab2(sch_1):page176_i105:a" )
			)
			( pin "R1M24.2"
				( objectStatus "@baseboard_fab2_lib.baseboard_fab2(sch_1):page176_i105:b" )
			)
			( pin "C1M38.1"
				( objectStatus "@baseboard_fab2_lib.baseboard_fab2(sch_1):page176_i108:a" )
			)
			( pin "C1M38.2"
				( objectStatus "@baseboard_fab2_lib.baseboard_fab2(sch_1):page176_i108:b" )
			)
			( pin "R1M25.1"
				( objectStatus "@baseboard_fab2_lib.baseboard_fab2(sch_1):page176_i111:a" )
			)
			( pin "R1M25.2"
				( objectStatus "@baseboard_fab2_lib.baseboard_fab2(sch_1):page176_i111:b" )
			)
			( pin "C9B8.1"
				( objectStatus "@baseboard_fab2_lib.baseboard_fab2(sch_1):page176_i113:a" )
			)
			( pin "C9B8.2"
				( objectStatus "@baseboard_fab2_lib.baseboard_fab2(sch_1):page176_i113:b" )
			)
			( pin "R1M13.1"
				( objectStatus "@baseboard_fab2_lib.baseboard_fab2(sch_1):page177_i3:a" )
			)
			( pin "R1M13.2"
				( objectStatus "@baseboard_fab2_lib.baseboard_fab2(sch_1):page177_i3:b" )
			)
			( pin "R1M10.1"
				( objectStatus "@baseboard_fab2_lib.baseboard_fab2(sch_1):page177_i6:a" )
			)
			( pin "R1M10.2"
				( objectStatus "@baseboard_fab2_lib.baseboard_fab2(sch_1):page177_i6:b" )
			)
			( pin "R1M12.1"
				( objectStatus "@baseboard_fab2_lib.baseboard_fab2(sch_1):page177_i8:a" )
			)
			( pin "R1M12.2"
				( objectStatus "@baseboard_fab2_lib.baseboard_fab2(sch_1):page177_i8:b" )
			)
			( pin "R1M11.1"
				( objectStatus "@baseboard_fab2_lib.baseboard_fab2(sch_1):page177_i9:a" )
			)
			( pin "R1M11.2"
				( objectStatus "@baseboard_fab2_lib.baseboard_fab2(sch_1):page177_i9:b" )
			)
			( pin "C1M3.1"
				( objectStatus "@baseboard_fab2_lib.baseboard_fab2(sch_1):page177_i20:a" )
			)
			( pin "C1M3.2"
				( objectStatus "@baseboard_fab2_lib.baseboard_fab2(sch_1):page177_i20:b" )
			)
			( pin "DS9A6.1"
				( objectStatus "@baseboard_fab2_lib.baseboard_fab2(sch_1):page177_i31:a" )
			)
			( pin "DS9A6.2"
				( objectStatus "@baseboard_fab2_lib.baseboard_fab2(sch_1):page177_i31:c" )
			)
			( pin "R1L37.1"
				( objectStatus "@baseboard_fab2_lib.baseboard_fab2(sch_1):page177_i33:a" )
			)
			( pin "R1L37.2"
				( objectStatus "@baseboard_fab2_lib.baseboard_fab2(sch_1):page177_i33:b" )
			)
			( pin "DS9A2.2"
				( objectStatus "@baseboard_fab2_lib.baseboard_fab2(sch_1):page177_i42:a" )
			)
			( pin "DS9A2.1"
				( objectStatus "@baseboard_fab2_lib.baseboard_fab2(sch_1):page177_i42:c" )
			)
			( pin "R1L21.1"
				( objectStatus "@baseboard_fab2_lib.baseboard_fab2(sch_1):page177_i43:a" )
			)
			( pin "R1L21.2"
				( objectStatus "@baseboard_fab2_lib.baseboard_fab2(sch_1):page177_i43:b" )
			)
			( pin "U1M1.1"
				( objectStatus "@baseboard_fab2_lib.baseboard_fab2(sch_1):page177_i70:a(0)" )
			)
			( pin "U1M1.2"
				( objectStatus "@baseboard_fab2_lib.baseboard_fab2(sch_1):page177_i70:b(0)" )
			)
			( pin "U1M1.4"
				( objectStatus "@baseboard_fab2_lib.baseboard_fab2(sch_1):page177_i70:y(0)" )
			)
			( pin "DS9F1.1"
				( objectStatus "@baseboard_fab2_lib.baseboard_fab2(sch_1):page177_i71:a" )
			)
			( pin "DS9F1.2"
				( objectStatus "@baseboard_fab2_lib.baseboard_fab2(sch_1):page177_i71:c" )
			)
			( pin "R9F28.1"
				( objectStatus "@baseboard_fab2_lib.baseboard_fab2(sch_1):page177_i72:a" )
			)
			( pin "R9F28.2"
				( objectStatus "@baseboard_fab2_lib.baseboard_fab2(sch_1):page177_i72:b" )
			)
			( pin "R9F30.1"
				( objectStatus "@baseboard_fab2_lib.baseboard_fab2(sch_1):page177_i76:a" )
			)
			( pin "R9F30.2"
				( objectStatus "@baseboard_fab2_lib.baseboard_fab2(sch_1):page177_i76:b" )
			)
			( pin "Q9F1.3"
				( objectStatus "@baseboard_fab2_lib.baseboard_fab2(sch_1):page177_i79:drain(0)" )
			)
			( pin "Q9F1.5"
				( objectStatus "@baseboard_fab2_lib.baseboard_fab2(sch_1):page177_i79:gate(0)" )
			)
			( pin "Q9F1.4"
				( objectStatus "@baseboard_fab2_lib.baseboard_fab2(sch_1):page177_i79:source(0)" )
			)
			( pin "Q9F1.6"
				( objectStatus "@baseboard_fab2_lib.baseboard_fab2(sch_1):page177_i80:drain(0)" )
			)
			( pin "Q9F1.2"
				( objectStatus "@baseboard_fab2_lib.baseboard_fab2(sch_1):page177_i80:gate(0)" )
			)
			( pin "Q9F1.1"
				( objectStatus "@baseboard_fab2_lib.baseboard_fab2(sch_1):page177_i80:source(0)" )
			)
			( pin "R9F52.1"
				( objectStatus "@baseboard_fab2_lib.baseboard_fab2(sch_1):page177_i82:a" )
			)
			( pin "R9F52.2"
				( objectStatus "@baseboard_fab2_lib.baseboard_fab2(sch_1):page177_i82:b" )
			)
			( pin "R8D20.1"
				( objectStatus "@baseboard_fab2_lib.baseboard_fab2(sch_1):page178_i1:a" )
			)
			( pin "R8D20.2"
				( objectStatus "@baseboard_fab2_lib.baseboard_fab2(sch_1):page178_i1:b" )
			)
			( pin "R2L12.1"
				( objectStatus "@baseboard_fab2_lib.baseboard_fab2(sch_1):page178_i2:a" )
			)
			( pin "R2L12.2"
				( objectStatus "@baseboard_fab2_lib.baseboard_fab2(sch_1):page178_i2:b" )
			)
			( pin "R8D19.1"
				( objectStatus "@baseboard_fab2_lib.baseboard_fab2(sch_1):page178_i8:a" )
			)
			( pin "R8D19.2"
				( objectStatus "@baseboard_fab2_lib.baseboard_fab2(sch_1):page178_i8:b" )
			)
			( pin "R2N31.1"
				( objectStatus "@baseboard_fab2_lib.baseboard_fab2(sch_1):page178_i11:a" )
			)
			( pin "R2N31.2"
				( objectStatus "@baseboard_fab2_lib.baseboard_fab2(sch_1):page178_i11:b" )
			)
			( pin "R2L15.1"
				( objectStatus "@baseboard_fab2_lib.baseboard_fab2(sch_1):page178_i12:a" )
			)
			( pin "R2L15.2"
				( objectStatus "@baseboard_fab2_lib.baseboard_fab2(sch_1):page178_i12:b" )
			)
			( pin "R2L11.1"
				( objectStatus "@baseboard_fab2_lib.baseboard_fab2(sch_1):page178_i13:a" )
			)
			( pin "R2L11.2"
				( objectStatus "@baseboard_fab2_lib.baseboard_fab2(sch_1):page178_i13:b" )
			)
			( pin "R2L6.1"
				( objectStatus "@baseboard_fab2_lib.baseboard_fab2(sch_1):page178_i17:a" )
			)
			( pin "R2L6.2"
				( objectStatus "@baseboard_fab2_lib.baseboard_fab2(sch_1):page178_i17:b" )
			)
			( pin "R2L4.1"
				( objectStatus "@baseboard_fab2_lib.baseboard_fab2(sch_1):page178_i18:a" )
			)
			( pin "R2L4.2"
				( objectStatus "@baseboard_fab2_lib.baseboard_fab2(sch_1):page178_i18:b" )
			)
			( pin "R2L5.1"
				( objectStatus "@baseboard_fab2_lib.baseboard_fab2(sch_1):page178_i20:a" )
			)
			( pin "R2L5.2"
				( objectStatus "@baseboard_fab2_lib.baseboard_fab2(sch_1):page178_i20:b" )
			)
			( pin "R8B29.1"
				( objectStatus "@baseboard_fab2_lib.baseboard_fab2(sch_1):page178_i21:a" )
			)
			( pin "R8B29.2"
				( objectStatus "@baseboard_fab2_lib.baseboard_fab2(sch_1):page178_i21:b" )
			)
			( pin "R2N19.1"
				( objectStatus "@baseboard_fab2_lib.baseboard_fab2(sch_1):page178_i22:a" )
			)
			( pin "R2N19.2"
				( objectStatus "@baseboard_fab2_lib.baseboard_fab2(sch_1):page178_i22:b" )
			)
			( pin "R2N22.1"
				( objectStatus "@baseboard_fab2_lib.baseboard_fab2(sch_1):page178_i23:a" )
			)
			( pin "R2N22.2"
				( objectStatus "@baseboard_fab2_lib.baseboard_fab2(sch_1):page178_i23:b" )
			)
			( pin "C9N17.1"
				( objectStatus "@baseboard_fab2_lib.baseboard_fab2(sch_1):page182_i38:a" )
			)
			( pin "C9N17.2"
				( objectStatus "@baseboard_fab2_lib.baseboard_fab2(sch_1):page182_i38:b" )
			)
			( pin "C9N18.1"
				( objectStatus "@baseboard_fab2_lib.baseboard_fab2(sch_1):page182_i39:a" )
			)
			( pin "C9N18.2"
				( objectStatus "@baseboard_fab2_lib.baseboard_fab2(sch_1):page182_i39:b" )
			)
			( pin "C9N1.1"
				( objectStatus "@baseboard_fab2_lib.baseboard_fab2(sch_1):page182_i40:a" )
			)
			( pin "C9N1.2"
				( objectStatus "@baseboard_fab2_lib.baseboard_fab2(sch_1):page182_i40:b" )
			)
			( pin "R9F69.1"
				( objectStatus "@baseboard_fab2_lib.baseboard_fab2(sch_1):page158_i150:a" )
			)
			( pin "R9F69.2"
				( objectStatus "@baseboard_fab2_lib.baseboard_fab2(sch_1):page158_i150:b" )
			)
			( pin "R9F68.1"
				( objectStatus "@baseboard_fab2_lib.baseboard_fab2(sch_1):page158_i149:a" )
			)
			( pin "R9F68.2"
				( objectStatus "@baseboard_fab2_lib.baseboard_fab2(sch_1):page158_i149:b" )
			)
			( pin "C9N15.1"
				( objectStatus "@baseboard_fab2_lib.baseboard_fab2(sch_1):page182_i41:a" )
			)
			( pin "C9N15.2"
				( objectStatus "@baseboard_fab2_lib.baseboard_fab2(sch_1):page182_i41:b" )
			)
			( pin "C9N6.1"
				( objectStatus "@baseboard_fab2_lib.baseboard_fab2(sch_1):page182_i42:a" )
			)
			( pin "C9N6.2"
				( objectStatus "@baseboard_fab2_lib.baseboard_fab2(sch_1):page182_i42:b" )
			)
			( pin "C9N14.1"
				( objectStatus "@baseboard_fab2_lib.baseboard_fab2(sch_1):page182_i43:a" )
			)
			( pin "C9N14.2"
				( objectStatus "@baseboard_fab2_lib.baseboard_fab2(sch_1):page182_i43:b" )
			)
			( pin "C9N4.1"
				( objectStatus "@baseboard_fab2_lib.baseboard_fab2(sch_1):page182_i44:a" )
			)
			( pin "C9N4.2"
				( objectStatus "@baseboard_fab2_lib.baseboard_fab2(sch_1):page182_i44:b" )
			)
			( pin "C9N5.1"
				( objectStatus "@baseboard_fab2_lib.baseboard_fab2(sch_1):page182_i45:a" )
			)
			( pin "C9N5.2"
				( objectStatus "@baseboard_fab2_lib.baseboard_fab2(sch_1):page182_i45:b" )
			)
			( pin "C9N16.1"
				( objectStatus "@baseboard_fab2_lib.baseboard_fab2(sch_1):page182_i46:a" )
			)
			( pin "C9N16.2"
				( objectStatus "@baseboard_fab2_lib.baseboard_fab2(sch_1):page182_i46:b" )
			)
			( pin "C9N3.1"
				( objectStatus "@baseboard_fab2_lib.baseboard_fab2(sch_1):page182_i47:a" )
			)
			( pin "C9N3.2"
				( objectStatus "@baseboard_fab2_lib.baseboard_fab2(sch_1):page182_i47:b" )
			)
			( pin "C9N7.1"
				( objectStatus "@baseboard_fab2_lib.baseboard_fab2(sch_1):page182_i48:a" )
			)
			( pin "C9N7.2"
				( objectStatus "@baseboard_fab2_lib.baseboard_fab2(sch_1):page182_i48:b" )
			)
			( pin "C9N10.1"
				( objectStatus "@baseboard_fab2_lib.baseboard_fab2(sch_1):page182_i49:a" )
			)
			( pin "C9N10.2"
				( objectStatus "@baseboard_fab2_lib.baseboard_fab2(sch_1):page182_i49:b" )
			)
			( pin "C9N9.1"
				( objectStatus "@baseboard_fab2_lib.baseboard_fab2(sch_1):page182_i52:a" )
			)
			( pin "C9N9.2"
				( objectStatus "@baseboard_fab2_lib.baseboard_fab2(sch_1):page182_i52:b" )
			)
			( pin "C9N8.1"
				( objectStatus "@baseboard_fab2_lib.baseboard_fab2(sch_1):page182_i53:a" )
			)
			( pin "C9N8.2"
				( objectStatus "@baseboard_fab2_lib.baseboard_fab2(sch_1):page182_i53:b" )
			)
			( pin "J8E1.1"
				( objectStatus "@baseboard_fab2_lib.baseboard_fab2(sch_1):page184_i87:io1" )
			)
			( pin "J8E1.2"
				( objectStatus "@baseboard_fab2_lib.baseboard_fab2(sch_1):page184_i87:io2" )
			)
			( pin "J8E1.3"
				( objectStatus "@baseboard_fab2_lib.baseboard_fab2(sch_1):page184_i87:io3" )
			)
			( pin "J8E1.4"
				( objectStatus "@baseboard_fab2_lib.baseboard_fab2(sch_1):page184_i87:io4" )
			)
			( pin "J8E1.5"
				( objectStatus "@baseboard_fab2_lib.baseboard_fab2(sch_1):page184_i87:io5" )
			)
			( pin "J8E1.6"
				( objectStatus "@baseboard_fab2_lib.baseboard_fab2(sch_1):page184_i87:io6" )
			)
			( pin "J8E1.7"
				( objectStatus "@baseboard_fab2_lib.baseboard_fab2(sch_1):page184_i87:io7" )
			)
			( pin "J8E1.8"
				( objectStatus "@baseboard_fab2_lib.baseboard_fab2(sch_1):page184_i87:io8" )
			)
			( pin "J8E1.9"
				( objectStatus "@baseboard_fab2_lib.baseboard_fab2(sch_1):page184_i87:io9" )
			)
			( pin "J8E1.10"
				( objectStatus "@baseboard_fab2_lib.baseboard_fab2(sch_1):page184_i87:io10" )
			)
			( pin "J8E1.11"
				( objectStatus "@baseboard_fab2_lib.baseboard_fab2(sch_1):page184_i87:io11" )
			)
			( pin "J8E1.MP1"
				( objectStatus "@baseboard_fab2_lib.baseboard_fab2(sch_1):page184_i87:mp1" )
			)
			( pin "J8E1.MP2"
				( objectStatus "@baseboard_fab2_lib.baseboard_fab2(sch_1):page184_i87:mp2" )
			)
			( pin "R8E9.1"
				( objectStatus "@baseboard_fab2_lib.baseboard_fab2(sch_1):page184_i88:a" )
			)
			( pin "R8E9.2"
				( objectStatus "@baseboard_fab2_lib.baseboard_fab2(sch_1):page184_i88:b" )
			)
			( pin "R8D35.1"
				( objectStatus "@baseboard_fab2_lib.baseboard_fab2(sch_1):page184_i92:a" )
			)
			( pin "R8D35.2"
				( objectStatus "@baseboard_fab2_lib.baseboard_fab2(sch_1):page184_i92:b" )
			)
			( pin "R8E13.1"
				( objectStatus "@baseboard_fab2_lib.baseboard_fab2(sch_1):page184_i93:a" )
			)
			( pin "R8E13.2"
				( objectStatus "@baseboard_fab2_lib.baseboard_fab2(sch_1):page184_i93:b" )
			)
			( pin "R8E10.1"
				( objectStatus "@baseboard_fab2_lib.baseboard_fab2(sch_1):page184_i95:a" )
			)
			( pin "R8E10.2"
				( objectStatus "@baseboard_fab2_lib.baseboard_fab2(sch_1):page184_i95:b" )
			)
			( pin "R8E1.1"
				( objectStatus "@baseboard_fab2_lib.baseboard_fab2(sch_1):page184_i99:a" )
			)
			( pin "R8E1.2"
				( objectStatus "@baseboard_fab2_lib.baseboard_fab2(sch_1):page184_i99:b" )
			)
			( pin "RM8D1.1"
				( objectStatus "@baseboard_fab2_lib.baseboard_fab2(sch_1):page184_i104:io1" )
			)
			( pin "C2T13.1"
				( objectStatus "@baseboard_fab2_lib.baseboard_fab2(sch_1):page185_i172:a" )
			)
			( pin "C2T13.2"
				( objectStatus "@baseboard_fab2_lib.baseboard_fab2(sch_1):page185_i172:b" )
			)
			( pin "C2T14.1"
				( objectStatus "@baseboard_fab2_lib.baseboard_fab2(sch_1):page185_i171:a" )
			)
			( pin "C2T14.2"
				( objectStatus "@baseboard_fab2_lib.baseboard_fab2(sch_1):page185_i171:b" )
			)
			( pin "C2T23.1"
				( objectStatus "@baseboard_fab2_lib.baseboard_fab2(sch_1):page185_i180:a" )
			)
			( pin "C2T23.2"
				( objectStatus "@baseboard_fab2_lib.baseboard_fab2(sch_1):page185_i180:b" )
			)
			( pin "C2T20.1"
				( objectStatus "@baseboard_fab2_lib.baseboard_fab2(sch_1):page185_i179:a" )
			)
			( pin "C2T20.2"
				( objectStatus "@baseboard_fab2_lib.baseboard_fab2(sch_1):page185_i179:b" )
			)
			( pin "C3P33.1"
				( objectStatus "@baseboard_fab2_lib.baseboard_fab2(sch_1):page107_i477:a" )
			)
			( pin "C3P33.2"
				( objectStatus "@baseboard_fab2_lib.baseboard_fab2(sch_1):page107_i477:b" )
			)
			( pin "C8F11.1"
				( objectStatus "@baseboard_fab2_lib.baseboard_fab2(sch_1):page185_i139:a" )
			)
			( pin "C8F11.2"
				( objectStatus "@baseboard_fab2_lib.baseboard_fab2(sch_1):page185_i139:b" )
			)
			( pin "C8F7.1"
				( objectStatus "@baseboard_fab2_lib.baseboard_fab2(sch_1):page185_i96:a" )
			)
			( pin "C8F7.2"
				( objectStatus "@baseboard_fab2_lib.baseboard_fab2(sch_1):page185_i96:b" )
			)
			( pin "C3P16.1"
				( objectStatus "@baseboard_fab2_lib.baseboard_fab2(sch_1):page107_i476:a" )
			)
			( pin "C3P16.2"
				( objectStatus "@baseboard_fab2_lib.baseboard_fab2(sch_1):page107_i476:b" )
			)
			( pin "C3P36.1"
				( objectStatus "@baseboard_fab2_lib.baseboard_fab2(sch_1):page107_i475:a" )
			)
			( pin "C3P36.2"
				( objectStatus "@baseboard_fab2_lib.baseboard_fab2(sch_1):page107_i475:b" )
			)
			( pin "C3P41.1"
				( objectStatus "@baseboard_fab2_lib.baseboard_fab2(sch_1):page107_i474:a" )
			)
			( pin "C3P41.2"
				( objectStatus "@baseboard_fab2_lib.baseboard_fab2(sch_1):page107_i474:b" )
			)
			( pin "R8F18.1"
				( objectStatus "@baseboard_fab2_lib.baseboard_fab2(sch_1):page185_i105:a" )
			)
			( pin "R8F18.2"
				( objectStatus "@baseboard_fab2_lib.baseboard_fab2(sch_1):page185_i105:b" )
			)
			( pin "R8F21.1"
				( objectStatus "@baseboard_fab2_lib.baseboard_fab2(sch_1):page185_i106:a" )
			)
			( pin "R8F21.2"
				( objectStatus "@baseboard_fab2_lib.baseboard_fab2(sch_1):page185_i106:b" )
			)
			( pin "U2P1.2"
				( objectStatus "@baseboard_fab2_lib.baseboard_fab2(sch_1):page185_i110:a" )
			)
			( pin "U2P1.4"
				( objectStatus "@baseboard_fab2_lib.baseboard_fab2(sch_1):page185_i110:y" )
			)
			( pin "R2P15.1"
				( objectStatus "@baseboard_fab2_lib.baseboard_fab2(sch_1):page185_i111:a" )
			)
			( pin "R2P15.2"
				( objectStatus "@baseboard_fab2_lib.baseboard_fab2(sch_1):page185_i111:b" )
			)
			( pin "R2P16.1"
				( objectStatus "@baseboard_fab2_lib.baseboard_fab2(sch_1):page185_i113:a" )
			)
			( pin "R2P16.2"
				( objectStatus "@baseboard_fab2_lib.baseboard_fab2(sch_1):page185_i113:b" )
			)
			( pin "R2P14.1"
				( objectStatus "@baseboard_fab2_lib.baseboard_fab2(sch_1):page185_i115:a" )
			)
			( pin "R2P14.2"
				( objectStatus "@baseboard_fab2_lib.baseboard_fab2(sch_1):page185_i115:b" )
			)
			( pin "C2P9.1"
				( objectStatus "@baseboard_fab2_lib.baseboard_fab2(sch_1):page185_i117:a" )
			)
			( pin "C2P9.2"
				( objectStatus "@baseboard_fab2_lib.baseboard_fab2(sch_1):page185_i117:b" )
			)
			( pin "C2T29.1"
				( objectStatus "@baseboard_fab2_lib.baseboard_fab2(sch_1):page185_i120:a" )
			)
			( pin "C2T29.2"
				( objectStatus "@baseboard_fab2_lib.baseboard_fab2(sch_1):page185_i120:b" )
			)
			( pin "C2T26.1"
				( objectStatus "@baseboard_fab2_lib.baseboard_fab2(sch_1):page185_i123:a" )
			)
			( pin "C2T26.2"
				( objectStatus "@baseboard_fab2_lib.baseboard_fab2(sch_1):page185_i123:b" )
			)
			( pin "C2T21.1"
				( objectStatus "@baseboard_fab2_lib.baseboard_fab2(sch_1):page185_i124:a" )
			)
			( pin "C2T21.2"
				( objectStatus "@baseboard_fab2_lib.baseboard_fab2(sch_1):page185_i124:b" )
			)
			( pin "C2T16.1"
				( objectStatus "@baseboard_fab2_lib.baseboard_fab2(sch_1):page185_i126:a" )
			)
			( pin "C2T16.2"
				( objectStatus "@baseboard_fab2_lib.baseboard_fab2(sch_1):page185_i126:b" )
			)
			( pin "C2T15.1"
				( objectStatus "@baseboard_fab2_lib.baseboard_fab2(sch_1):page185_i127:a" )
			)
			( pin "C2T15.2"
				( objectStatus "@baseboard_fab2_lib.baseboard_fab2(sch_1):page185_i127:b" )
			)
			( pin "C2T24.1"
				( objectStatus "@baseboard_fab2_lib.baseboard_fab2(sch_1):page185_i129:a" )
			)
			( pin "C2T24.2"
				( objectStatus "@baseboard_fab2_lib.baseboard_fab2(sch_1):page185_i129:b" )
			)
			( pin "C2T2.1"
				( objectStatus "@baseboard_fab2_lib.baseboard_fab2(sch_1):page185_i131:a" )
			)
			( pin "C2T2.2"
				( objectStatus "@baseboard_fab2_lib.baseboard_fab2(sch_1):page185_i131:b" )
			)
			( pin "C2T4.1"
				( objectStatus "@baseboard_fab2_lib.baseboard_fab2(sch_1):page185_i132:a" )
			)
			( pin "C2T4.2"
				( objectStatus "@baseboard_fab2_lib.baseboard_fab2(sch_1):page185_i132:b" )
			)
			( pin "C2T5.1"
				( objectStatus "@baseboard_fab2_lib.baseboard_fab2(sch_1):page185_i135:a" )
			)
			( pin "C2T5.2"
				( objectStatus "@baseboard_fab2_lib.baseboard_fab2(sch_1):page185_i135:b" )
			)
			( pin "R8F36.1"
				( objectStatus "@baseboard_fab2_lib.baseboard_fab2(sch_1):page185_i136:a" )
			)
			( pin "R8F36.2"
				( objectStatus "@baseboard_fab2_lib.baseboard_fab2(sch_1):page185_i136:b" )
			)
			( pin "C1M27.1"
				( objectStatus "@baseboard_fab2_lib.baseboard_fab2(sch_1):page186_i3:a" )
			)
			( pin "C1M27.2"
				( objectStatus "@baseboard_fab2_lib.baseboard_fab2(sch_1):page186_i3:b" )
			)
			( pin "C1M26.1"
				( objectStatus "@baseboard_fab2_lib.baseboard_fab2(sch_1):page186_i6:a" )
			)
			( pin "C1M26.2"
				( objectStatus "@baseboard_fab2_lib.baseboard_fab2(sch_1):page186_i6:b" )
			)
			( pin "C1M23.1"
				( objectStatus "@baseboard_fab2_lib.baseboard_fab2(sch_1):page186_i7:a" )
			)
			( pin "C1M23.2"
				( objectStatus "@baseboard_fab2_lib.baseboard_fab2(sch_1):page186_i7:b" )
			)
			( pin "C1M22.1"
				( objectStatus "@baseboard_fab2_lib.baseboard_fab2(sch_1):page186_i8:a" )
			)
			( pin "C1M22.2"
				( objectStatus "@baseboard_fab2_lib.baseboard_fab2(sch_1):page186_i8:b" )
			)
			( pin "C1M24.1"
				( objectStatus "@baseboard_fab2_lib.baseboard_fab2(sch_1):page186_i10:a" )
			)
			( pin "C1M24.2"
				( objectStatus "@baseboard_fab2_lib.baseboard_fab2(sch_1):page186_i10:b" )
			)
			( pin "R1M14.1"
				( objectStatus "@baseboard_fab2_lib.baseboard_fab2(sch_1):page186_i220:a" )
			)
			( pin "R1M14.2"
				( objectStatus "@baseboard_fab2_lib.baseboard_fab2(sch_1):page186_i220:b" )
			)
			( pin "RT2.1"
				( objectStatus "@baseboard_fab2_lib.baseboard_fab2(sch_1):page202_i114:\1\" )
			)
			( pin "RT2.2"
				( objectStatus "@baseboard_fab2_lib.baseboard_fab2(sch_1):page202_i114:\2\" )
			)
			( pin "C1M20.1"
				( objectStatus "@baseboard_fab2_lib.baseboard_fab2(sch_1):page186_i270:a" )
			)
			( pin "C1M20.2"
				( objectStatus "@baseboard_fab2_lib.baseboard_fab2(sch_1):page186_i270:b" )
			)
			( pin "C1M21.1"
				( objectStatus "@baseboard_fab2_lib.baseboard_fab2(sch_1):page186_i334:a" )
			)
			( pin "C1M21.2"
				( objectStatus "@baseboard_fab2_lib.baseboard_fab2(sch_1):page186_i334:b" )
			)
			( pin "C1M25.1"
				( objectStatus "@baseboard_fab2_lib.baseboard_fab2(sch_1):page186_i335:a" )
			)
			( pin "C1M25.2"
				( objectStatus "@baseboard_fab2_lib.baseboard_fab2(sch_1):page186_i335:b" )
			)
			( pin "J9B3.1"
				( objectStatus "@baseboard_fab2_lib.baseboard_fab2(sch_1):page186_i336:io1" )
			)
			( pin "J9B3.2"
				( objectStatus "@baseboard_fab2_lib.baseboard_fab2(sch_1):page186_i336:io2" )
			)
			( pin "J9B3.3"
				( objectStatus "@baseboard_fab2_lib.baseboard_fab2(sch_1):page186_i336:io3" )
			)
			( pin "J9B3.4"
				( objectStatus "@baseboard_fab2_lib.baseboard_fab2(sch_1):page186_i336:io4" )
			)
			( pin "J9B3.5"
				( objectStatus "@baseboard_fab2_lib.baseboard_fab2(sch_1):page186_i336:io5" )
			)
			( pin "J9B3.6"
				( objectStatus "@baseboard_fab2_lib.baseboard_fab2(sch_1):page186_i336:io6" )
			)
			( pin "J9B3.7"
				( objectStatus "@baseboard_fab2_lib.baseboard_fab2(sch_1):page186_i336:io7" )
			)
			( pin "J9B3.8"
				( objectStatus "@baseboard_fab2_lib.baseboard_fab2(sch_1):page186_i336:io8" )
			)
			( pin "J9B3.9"
				( objectStatus "@baseboard_fab2_lib.baseboard_fab2(sch_1):page186_i336:io9" )
			)
			( pin "J9B3.10"
				( objectStatus "@baseboard_fab2_lib.baseboard_fab2(sch_1):page186_i336:io10" )
			)
			( pin "J9B3.11"
				( objectStatus "@baseboard_fab2_lib.baseboard_fab2(sch_1):page186_i336:io11" )
			)
			( pin "J9B3.12"
				( objectStatus "@baseboard_fab2_lib.baseboard_fab2(sch_1):page186_i336:io12" )
			)
			( pin "J9B3.13"
				( objectStatus "@baseboard_fab2_lib.baseboard_fab2(sch_1):page186_i336:io13" )
			)
			( pin "J9B3.14"
				( objectStatus "@baseboard_fab2_lib.baseboard_fab2(sch_1):page186_i336:io14" )
			)
			( pin "J9B3.15"
				( objectStatus "@baseboard_fab2_lib.baseboard_fab2(sch_1):page186_i336:io15" )
			)
			( pin "J9B3.16"
				( objectStatus "@baseboard_fab2_lib.baseboard_fab2(sch_1):page186_i336:io16" )
			)
			( pin "J9B3.17"
				( objectStatus "@baseboard_fab2_lib.baseboard_fab2(sch_1):page186_i336:io17" )
			)
			( pin "J9B3.18"
				( objectStatus "@baseboard_fab2_lib.baseboard_fab2(sch_1):page186_i336:io18" )
			)
			( pin "J9B3.19"
				( objectStatus "@baseboard_fab2_lib.baseboard_fab2(sch_1):page186_i336:io19" )
			)
			( pin "J9B3.20"
				( objectStatus "@baseboard_fab2_lib.baseboard_fab2(sch_1):page186_i336:io20" )
			)
			( pin "J9B3.21"
				( objectStatus "@baseboard_fab2_lib.baseboard_fab2(sch_1):page186_i336:io21" )
			)
			( pin "J9B3.22"
				( objectStatus "@baseboard_fab2_lib.baseboard_fab2(sch_1):page186_i336:io22" )
			)
			( pin "J9B3.23"
				( objectStatus "@baseboard_fab2_lib.baseboard_fab2(sch_1):page186_i336:io23" )
			)
			( pin "J9B3.24"
				( objectStatus "@baseboard_fab2_lib.baseboard_fab2(sch_1):page186_i336:io24" )
			)
			( pin "J9B3.25"
				( objectStatus "@baseboard_fab2_lib.baseboard_fab2(sch_1):page186_i336:io25" )
			)
			( pin "J9B3.26"
				( objectStatus "@baseboard_fab2_lib.baseboard_fab2(sch_1):page186_i336:io26" )
			)
			( pin "J9B3.27"
				( objectStatus "@baseboard_fab2_lib.baseboard_fab2(sch_1):page186_i336:io27" )
			)
			( pin "J9B3.28"
				( objectStatus "@baseboard_fab2_lib.baseboard_fab2(sch_1):page186_i336:io28" )
			)
			( pin "J9B3.29"
				( objectStatus "@baseboard_fab2_lib.baseboard_fab2(sch_1):page186_i336:io29" )
			)
			( pin "J9B3.30"
				( objectStatus "@baseboard_fab2_lib.baseboard_fab2(sch_1):page186_i336:io30" )
			)
			( pin "J9B3.31"
				( objectStatus "@baseboard_fab2_lib.baseboard_fab2(sch_1):page186_i336:io31" )
			)
			( pin "J9B3.32"
				( objectStatus "@baseboard_fab2_lib.baseboard_fab2(sch_1):page186_i336:io32" )
			)
			( pin "J9B3.33"
				( objectStatus "@baseboard_fab2_lib.baseboard_fab2(sch_1):page186_i336:io33" )
			)
			( pin "J9B3.34"
				( objectStatus "@baseboard_fab2_lib.baseboard_fab2(sch_1):page186_i336:io34" )
			)
			( pin "J9B3.35"
				( objectStatus "@baseboard_fab2_lib.baseboard_fab2(sch_1):page186_i336:io35" )
			)
			( pin "J9B3.36"
				( objectStatus "@baseboard_fab2_lib.baseboard_fab2(sch_1):page186_i336:io36" )
			)
			( pin "J9B3.37"
				( objectStatus "@baseboard_fab2_lib.baseboard_fab2(sch_1):page186_i336:io37" )
			)
			( pin "J9B3.38"
				( objectStatus "@baseboard_fab2_lib.baseboard_fab2(sch_1):page186_i336:io38" )
			)
			( pin "J9B3.39"
				( objectStatus "@baseboard_fab2_lib.baseboard_fab2(sch_1):page186_i336:io39" )
			)
			( pin "J9B3.40"
				( objectStatus "@baseboard_fab2_lib.baseboard_fab2(sch_1):page186_i336:io40" )
			)
			( pin "J9B3.41"
				( objectStatus "@baseboard_fab2_lib.baseboard_fab2(sch_1):page186_i336:io41" )
			)
			( pin "J9B3.42"
				( objectStatus "@baseboard_fab2_lib.baseboard_fab2(sch_1):page186_i336:io42" )
			)
			( pin "J9B3.43"
				( objectStatus "@baseboard_fab2_lib.baseboard_fab2(sch_1):page186_i336:io43" )
			)
			( pin "J9B3.44"
				( objectStatus "@baseboard_fab2_lib.baseboard_fab2(sch_1):page186_i336:io44" )
			)
			( pin "J9B3.45"
				( objectStatus "@baseboard_fab2_lib.baseboard_fab2(sch_1):page186_i336:io45" )
			)
			( pin "J9B3.46"
				( objectStatus "@baseboard_fab2_lib.baseboard_fab2(sch_1):page186_i336:io46" )
			)
			( pin "J9B3.47"
				( objectStatus "@baseboard_fab2_lib.baseboard_fab2(sch_1):page186_i336:io47" )
			)
			( pin "J9B3.48"
				( objectStatus "@baseboard_fab2_lib.baseboard_fab2(sch_1):page186_i336:io48" )
			)
			( pin "J9B3.49"
				( objectStatus "@baseboard_fab2_lib.baseboard_fab2(sch_1):page186_i336:io49" )
			)
			( pin "J9B3.50"
				( objectStatus "@baseboard_fab2_lib.baseboard_fab2(sch_1):page186_i336:io50" )
			)
			( pin "J9B3.51"
				( objectStatus "@baseboard_fab2_lib.baseboard_fab2(sch_1):page186_i336:io51" )
			)
			( pin "J9B3.52"
				( objectStatus "@baseboard_fab2_lib.baseboard_fab2(sch_1):page186_i336:io52" )
			)
			( pin "J9B3.53"
				( objectStatus "@baseboard_fab2_lib.baseboard_fab2(sch_1):page186_i336:io53" )
			)
			( pin "J9B3.54"
				( objectStatus "@baseboard_fab2_lib.baseboard_fab2(sch_1):page186_i336:io54" )
			)
			( pin "J9B3.55"
				( objectStatus "@baseboard_fab2_lib.baseboard_fab2(sch_1):page186_i336:io55" )
			)
			( pin "J9B3.56"
				( objectStatus "@baseboard_fab2_lib.baseboard_fab2(sch_1):page186_i336:io56" )
			)
			( pin "J9B3.57"
				( objectStatus "@baseboard_fab2_lib.baseboard_fab2(sch_1):page186_i336:io57" )
			)
			( pin "J9B3.58"
				( objectStatus "@baseboard_fab2_lib.baseboard_fab2(sch_1):page186_i336:io58" )
			)
			( pin "J9B3.59"
				( objectStatus "@baseboard_fab2_lib.baseboard_fab2(sch_1):page186_i336:io59" )
			)
			( pin "J9B3.60"
				( objectStatus "@baseboard_fab2_lib.baseboard_fab2(sch_1):page186_i336:io60" )
			)
			( pin "J9B3.61"
				( objectStatus "@baseboard_fab2_lib.baseboard_fab2(sch_1):page186_i336:io61" )
			)
			( pin "J9B3.62"
				( objectStatus "@baseboard_fab2_lib.baseboard_fab2(sch_1):page186_i336:io62" )
			)
			( pin "J9B3.63"
				( objectStatus "@baseboard_fab2_lib.baseboard_fab2(sch_1):page186_i336:io63" )
			)
			( pin "J9B3.64"
				( objectStatus "@baseboard_fab2_lib.baseboard_fab2(sch_1):page186_i336:io64" )
			)
			( pin "J9B3.65"
				( objectStatus "@baseboard_fab2_lib.baseboard_fab2(sch_1):page186_i336:io65" )
			)
			( pin "J9B3.66"
				( objectStatus "@baseboard_fab2_lib.baseboard_fab2(sch_1):page186_i336:io66" )
			)
			( pin "J9B3.67"
				( objectStatus "@baseboard_fab2_lib.baseboard_fab2(sch_1):page186_i336:io67" )
			)
			( pin "J9B3.68"
				( objectStatus "@baseboard_fab2_lib.baseboard_fab2(sch_1):page186_i336:io68" )
			)
			( pin "J9B3.69"
				( objectStatus "@baseboard_fab2_lib.baseboard_fab2(sch_1):page186_i336:io69" )
			)
			( pin "J9B3.70"
				( objectStatus "@baseboard_fab2_lib.baseboard_fab2(sch_1):page186_i336:io70" )
			)
			( pin "J9B3.71"
				( objectStatus "@baseboard_fab2_lib.baseboard_fab2(sch_1):page186_i336:io71" )
			)
			( pin "J9B3.72"
				( objectStatus "@baseboard_fab2_lib.baseboard_fab2(sch_1):page186_i336:io72" )
			)
			( pin "J9B3.73"
				( objectStatus "@baseboard_fab2_lib.baseboard_fab2(sch_1):page186_i336:io73" )
			)
			( pin "J9B3.74"
				( objectStatus "@baseboard_fab2_lib.baseboard_fab2(sch_1):page186_i336:io74" )
			)
			( pin "J9B3.75"
				( objectStatus "@baseboard_fab2_lib.baseboard_fab2(sch_1):page186_i336:io75" )
			)
			( pin "J9B3.76"
				( objectStatus "@baseboard_fab2_lib.baseboard_fab2(sch_1):page186_i336:io76" )
			)
			( pin "J9B3.77"
				( objectStatus "@baseboard_fab2_lib.baseboard_fab2(sch_1):page186_i336:io77" )
			)
			( pin "J9B3.78"
				( objectStatus "@baseboard_fab2_lib.baseboard_fab2(sch_1):page186_i336:io78" )
			)
			( pin "J9B3.79"
				( objectStatus "@baseboard_fab2_lib.baseboard_fab2(sch_1):page186_i336:io79" )
			)
			( pin "J9B3.80"
				( objectStatus "@baseboard_fab2_lib.baseboard_fab2(sch_1):page186_i336:io80" )
			)
			( pin "J9B3.81"
				( objectStatus "@baseboard_fab2_lib.baseboard_fab2(sch_1):page186_i336:io81" )
			)
			( pin "J9B3.82"
				( objectStatus "@baseboard_fab2_lib.baseboard_fab2(sch_1):page186_i336:io82" )
			)
			( pin "J9B3.83"
				( objectStatus "@baseboard_fab2_lib.baseboard_fab2(sch_1):page186_i336:io83" )
			)
			( pin "J9B3.84"
				( objectStatus "@baseboard_fab2_lib.baseboard_fab2(sch_1):page186_i336:io84" )
			)
			( pin "J9B3.85"
				( objectStatus "@baseboard_fab2_lib.baseboard_fab2(sch_1):page186_i336:io85" )
			)
			( pin "J9B3.86"
				( objectStatus "@baseboard_fab2_lib.baseboard_fab2(sch_1):page186_i336:io86" )
			)
			( pin "J9B3.87"
				( objectStatus "@baseboard_fab2_lib.baseboard_fab2(sch_1):page186_i336:io87" )
			)
			( pin "J9B3.88"
				( objectStatus "@baseboard_fab2_lib.baseboard_fab2(sch_1):page186_i336:io88" )
			)
			( pin "J9B3.89"
				( objectStatus "@baseboard_fab2_lib.baseboard_fab2(sch_1):page186_i336:io89" )
			)
			( pin "J9B3.90"
				( objectStatus "@baseboard_fab2_lib.baseboard_fab2(sch_1):page186_i336:io90" )
			)
			( pin "J9B3.91"
				( objectStatus "@baseboard_fab2_lib.baseboard_fab2(sch_1):page186_i336:io91" )
			)
			( pin "J9B3.92"
				( objectStatus "@baseboard_fab2_lib.baseboard_fab2(sch_1):page186_i336:io92" )
			)
			( pin "J9B3.93"
				( objectStatus "@baseboard_fab2_lib.baseboard_fab2(sch_1):page186_i336:io93" )
			)
			( pin "J9B3.94"
				( objectStatus "@baseboard_fab2_lib.baseboard_fab2(sch_1):page186_i336:io94" )
			)
			( pin "J9B3.95"
				( objectStatus "@baseboard_fab2_lib.baseboard_fab2(sch_1):page186_i336:io95" )
			)
			( pin "J9B3.96"
				( objectStatus "@baseboard_fab2_lib.baseboard_fab2(sch_1):page186_i336:io96" )
			)
			( pin "J9B3.97"
				( objectStatus "@baseboard_fab2_lib.baseboard_fab2(sch_1):page186_i336:io97" )
			)
			( pin "J9B3.98"
				( objectStatus "@baseboard_fab2_lib.baseboard_fab2(sch_1):page186_i336:io98" )
			)
			( pin "J9B3.99"
				( objectStatus "@baseboard_fab2_lib.baseboard_fab2(sch_1):page186_i336:io99" )
			)
			( pin "J9B3.100"
				( objectStatus "@baseboard_fab2_lib.baseboard_fab2(sch_1):page186_i336:io100" )
			)
			( pin "J9B3.101"
				( objectStatus "@baseboard_fab2_lib.baseboard_fab2(sch_1):page186_i336:io101" )
			)
			( pin "J9B3.102"
				( objectStatus "@baseboard_fab2_lib.baseboard_fab2(sch_1):page186_i336:io102" )
			)
			( pin "J9B3.103"
				( objectStatus "@baseboard_fab2_lib.baseboard_fab2(sch_1):page186_i336:io103" )
			)
			( pin "J9B3.104"
				( objectStatus "@baseboard_fab2_lib.baseboard_fab2(sch_1):page186_i336:io104" )
			)
			( pin "J9B3.105"
				( objectStatus "@baseboard_fab2_lib.baseboard_fab2(sch_1):page186_i336:io105" )
			)
			( pin "J9B3.106"
				( objectStatus "@baseboard_fab2_lib.baseboard_fab2(sch_1):page186_i336:io106" )
			)
			( pin "J9B3.107"
				( objectStatus "@baseboard_fab2_lib.baseboard_fab2(sch_1):page186_i336:io107" )
			)
			( pin "J9B3.108"
				( objectStatus "@baseboard_fab2_lib.baseboard_fab2(sch_1):page186_i336:io108" )
			)
			( pin "J9B3.109"
				( objectStatus "@baseboard_fab2_lib.baseboard_fab2(sch_1):page186_i336:io109" )
			)
			( pin "J9B3.110"
				( objectStatus "@baseboard_fab2_lib.baseboard_fab2(sch_1):page186_i336:io110" )
			)
			( pin "J9B3.111"
				( objectStatus "@baseboard_fab2_lib.baseboard_fab2(sch_1):page186_i336:io111" )
			)
			( pin "J9B3.112"
				( objectStatus "@baseboard_fab2_lib.baseboard_fab2(sch_1):page186_i336:io112" )
			)
			( pin "J9B3.113"
				( objectStatus "@baseboard_fab2_lib.baseboard_fab2(sch_1):page186_i336:io113" )
			)
			( pin "J9B3.114"
				( objectStatus "@baseboard_fab2_lib.baseboard_fab2(sch_1):page186_i336:io114" )
			)
			( pin "J9B3.115"
				( objectStatus "@baseboard_fab2_lib.baseboard_fab2(sch_1):page186_i336:io115" )
			)
			( pin "J9B3.116"
				( objectStatus "@baseboard_fab2_lib.baseboard_fab2(sch_1):page186_i336:io116" )
			)
			( pin "J9B3.117"
				( objectStatus "@baseboard_fab2_lib.baseboard_fab2(sch_1):page186_i336:io117" )
			)
			( pin "J9B3.118"
				( objectStatus "@baseboard_fab2_lib.baseboard_fab2(sch_1):page186_i336:io118" )
			)
			( pin "J9B3.119"
				( objectStatus "@baseboard_fab2_lib.baseboard_fab2(sch_1):page186_i336:io119" )
			)
			( pin "J9B3.120"
				( objectStatus "@baseboard_fab2_lib.baseboard_fab2(sch_1):page186_i336:io120" )
			)
			( pin "R1M16.1"
				( objectStatus "@baseboard_fab2_lib.baseboard_fab2(sch_1):page186_i337:a" )
			)
			( pin "R1M16.2"
				( objectStatus "@baseboard_fab2_lib.baseboard_fab2(sch_1):page186_i337:b" )
			)
			( pin "R1M17.1"
				( objectStatus "@baseboard_fab2_lib.baseboard_fab2(sch_1):page186_i338:a" )
			)
			( pin "R1M17.2"
				( objectStatus "@baseboard_fab2_lib.baseboard_fab2(sch_1):page186_i338:b" )
			)
			( pin "R1M15.1"
				( objectStatus "@baseboard_fab2_lib.baseboard_fab2(sch_1):page186_i339:a" )
			)
			( pin "R1M15.2"
				( objectStatus "@baseboard_fab2_lib.baseboard_fab2(sch_1):page186_i339:b" )
			)
			( pin "R1M18.1"
				( objectStatus "@baseboard_fab2_lib.baseboard_fab2(sch_1):page186_i340:a" )
			)
			( pin "R1M18.2"
				( objectStatus "@baseboard_fab2_lib.baseboard_fab2(sch_1):page186_i340:b" )
			)
			( pin "C9B10.1"
				( objectStatus "@baseboard_fab2_lib.baseboard_fab2(sch_1):page186_i345:a" )
			)
			( pin "C9B10.2"
				( objectStatus "@baseboard_fab2_lib.baseboard_fab2(sch_1):page186_i345:b" )
			)
			( pin "C1C18.1"
				( objectStatus "@baseboard_fab2_lib.baseboard_fab2(sch_1):page209_i89:\1\" )
			)
			( pin "C1C18.2"
				( objectStatus "@baseboard_fab2_lib.baseboard_fab2(sch_1):page209_i89:\2\" )
			)
			( pin "J8E3.1"
				( objectStatus "@baseboard_fab2_lib.baseboard_fab2(sch_1):page187_i119:io1" )
			)
			( pin "J8E3.2"
				( objectStatus "@baseboard_fab2_lib.baseboard_fab2(sch_1):page187_i119:io2" )
			)
			( pin "J8E3.3"
				( objectStatus "@baseboard_fab2_lib.baseboard_fab2(sch_1):page187_i119:io3" )
			)
			( pin "J8E3.4"
				( objectStatus "@baseboard_fab2_lib.baseboard_fab2(sch_1):page187_i119:io4" )
			)
			( pin "J8E3.5"
				( objectStatus "@baseboard_fab2_lib.baseboard_fab2(sch_1):page187_i119:io5" )
			)
			( pin "J8E3.6"
				( objectStatus "@baseboard_fab2_lib.baseboard_fab2(sch_1):page187_i119:io6" )
			)
			( pin "J8E3.7"
				( objectStatus "@baseboard_fab2_lib.baseboard_fab2(sch_1):page187_i119:io7" )
			)
			( pin "J8E3.8"
				( objectStatus "@baseboard_fab2_lib.baseboard_fab2(sch_1):page187_i119:io8" )
			)
			( pin "J8E3.9"
				( objectStatus "@baseboard_fab2_lib.baseboard_fab2(sch_1):page187_i119:io9" )
			)
			( pin "J8E3.10"
				( objectStatus "@baseboard_fab2_lib.baseboard_fab2(sch_1):page187_i119:io10" )
			)
			( pin "J8E3.11"
				( objectStatus "@baseboard_fab2_lib.baseboard_fab2(sch_1):page187_i119:io11" )
			)
			( pin "J8E3.12"
				( objectStatus "@baseboard_fab2_lib.baseboard_fab2(sch_1):page187_i119:io12" )
			)
			( pin "J8E3.13"
				( objectStatus "@baseboard_fab2_lib.baseboard_fab2(sch_1):page187_i119:io13" )
			)
			( pin "J8E3.14"
				( objectStatus "@baseboard_fab2_lib.baseboard_fab2(sch_1):page187_i119:io14" )
			)
			( pin "J8E3.15"
				( objectStatus "@baseboard_fab2_lib.baseboard_fab2(sch_1):page187_i119:io15" )
			)
			( pin "J8E3.16"
				( objectStatus "@baseboard_fab2_lib.baseboard_fab2(sch_1):page187_i119:io16" )
			)
			( pin "J8E3.17"
				( objectStatus "@baseboard_fab2_lib.baseboard_fab2(sch_1):page187_i119:io17" )
			)
			( pin "J8E3.18"
				( objectStatus "@baseboard_fab2_lib.baseboard_fab2(sch_1):page187_i119:io18" )
			)
			( pin "J8E3.19"
				( objectStatus "@baseboard_fab2_lib.baseboard_fab2(sch_1):page187_i119:io19" )
			)
			( pin "J8E3.20"
				( objectStatus "@baseboard_fab2_lib.baseboard_fab2(sch_1):page187_i119:io20" )
			)
			( pin "J8E3.21"
				( objectStatus "@baseboard_fab2_lib.baseboard_fab2(sch_1):page187_i119:io21" )
			)
			( pin "J8E3.22"
				( objectStatus "@baseboard_fab2_lib.baseboard_fab2(sch_1):page187_i119:io22" )
			)
			( pin "J8E3.23"
				( objectStatus "@baseboard_fab2_lib.baseboard_fab2(sch_1):page187_i119:io23" )
			)
			( pin "J8E3.24"
				( objectStatus "@baseboard_fab2_lib.baseboard_fab2(sch_1):page187_i119:io24" )
			)
			( pin "J8E3.25"
				( objectStatus "@baseboard_fab2_lib.baseboard_fab2(sch_1):page187_i119:io25" )
			)
			( pin "J8E3.26"
				( objectStatus "@baseboard_fab2_lib.baseboard_fab2(sch_1):page187_i119:io26" )
			)
			( pin "J8E3.27"
				( objectStatus "@baseboard_fab2_lib.baseboard_fab2(sch_1):page187_i119:io27" )
			)
			( pin "J8E3.28"
				( objectStatus "@baseboard_fab2_lib.baseboard_fab2(sch_1):page187_i119:io28" )
			)
			( pin "J8E3.29"
				( objectStatus "@baseboard_fab2_lib.baseboard_fab2(sch_1):page187_i119:io29" )
			)
			( pin "J8E3.30"
				( objectStatus "@baseboard_fab2_lib.baseboard_fab2(sch_1):page187_i119:io30" )
			)
			( pin "J8E3.31"
				( objectStatus "@baseboard_fab2_lib.baseboard_fab2(sch_1):page187_i119:io31" )
			)
			( pin "J8E3.32"
				( objectStatus "@baseboard_fab2_lib.baseboard_fab2(sch_1):page187_i119:io32" )
			)
			( pin "J8E3.33"
				( objectStatus "@baseboard_fab2_lib.baseboard_fab2(sch_1):page187_i119:io33" )
			)
			( pin "J8E3.34"
				( objectStatus "@baseboard_fab2_lib.baseboard_fab2(sch_1):page187_i119:io34" )
			)
			( pin "J8E3.35"
				( objectStatus "@baseboard_fab2_lib.baseboard_fab2(sch_1):page187_i119:io35" )
			)
			( pin "J8E3.36"
				( objectStatus "@baseboard_fab2_lib.baseboard_fab2(sch_1):page187_i119:io36" )
			)
			( pin "J8E3.37"
				( objectStatus "@baseboard_fab2_lib.baseboard_fab2(sch_1):page187_i119:io37" )
			)
			( pin "J8E3.38"
				( objectStatus "@baseboard_fab2_lib.baseboard_fab2(sch_1):page187_i119:io38" )
			)
			( pin "J8E3.39"
				( objectStatus "@baseboard_fab2_lib.baseboard_fab2(sch_1):page187_i119:io39" )
			)
			( pin "J8E3.40"
				( objectStatus "@baseboard_fab2_lib.baseboard_fab2(sch_1):page187_i119:io40" )
			)
			( pin "J8E3.41"
				( objectStatus "@baseboard_fab2_lib.baseboard_fab2(sch_1):page187_i119:io41" )
			)
			( pin "J8E3.42"
				( objectStatus "@baseboard_fab2_lib.baseboard_fab2(sch_1):page187_i119:io42" )
			)
			( pin "J8E3.43"
				( objectStatus "@baseboard_fab2_lib.baseboard_fab2(sch_1):page187_i119:io43" )
			)
			( pin "J8E3.44"
				( objectStatus "@baseboard_fab2_lib.baseboard_fab2(sch_1):page187_i119:io44" )
			)
			( pin "J8E3.45"
				( objectStatus "@baseboard_fab2_lib.baseboard_fab2(sch_1):page187_i119:io45" )
			)
			( pin "J8E3.46"
				( objectStatus "@baseboard_fab2_lib.baseboard_fab2(sch_1):page187_i119:io46" )
			)
			( pin "J8E3.47"
				( objectStatus "@baseboard_fab2_lib.baseboard_fab2(sch_1):page187_i119:io47" )
			)
			( pin "J8E3.48"
				( objectStatus "@baseboard_fab2_lib.baseboard_fab2(sch_1):page187_i119:io48" )
			)
			( pin "J8E3.49"
				( objectStatus "@baseboard_fab2_lib.baseboard_fab2(sch_1):page187_i119:io49" )
			)
			( pin "J8E3.50"
				( objectStatus "@baseboard_fab2_lib.baseboard_fab2(sch_1):page187_i119:io50" )
			)
			( pin "J8E3.51"
				( objectStatus "@baseboard_fab2_lib.baseboard_fab2(sch_1):page187_i119:io51" )
			)
			( pin "J8E3.52"
				( objectStatus "@baseboard_fab2_lib.baseboard_fab2(sch_1):page187_i119:io52" )
			)
			( pin "J8E3.53"
				( objectStatus "@baseboard_fab2_lib.baseboard_fab2(sch_1):page187_i119:io53" )
			)
			( pin "J8E3.54"
				( objectStatus "@baseboard_fab2_lib.baseboard_fab2(sch_1):page187_i119:io54" )
			)
			( pin "J8E3.55"
				( objectStatus "@baseboard_fab2_lib.baseboard_fab2(sch_1):page187_i119:io55" )
			)
			( pin "J8E3.56"
				( objectStatus "@baseboard_fab2_lib.baseboard_fab2(sch_1):page187_i119:io56" )
			)
			( pin "J8E3.57"
				( objectStatus "@baseboard_fab2_lib.baseboard_fab2(sch_1):page187_i119:io57" )
			)
			( pin "J8E3.58"
				( objectStatus "@baseboard_fab2_lib.baseboard_fab2(sch_1):page187_i119:io58" )
			)
			( pin "J8E3.59"
				( objectStatus "@baseboard_fab2_lib.baseboard_fab2(sch_1):page187_i119:io59" )
			)
			( pin "J8E3.60"
				( objectStatus "@baseboard_fab2_lib.baseboard_fab2(sch_1):page187_i119:io60" )
			)
			( pin "J8E3.61"
				( objectStatus "@baseboard_fab2_lib.baseboard_fab2(sch_1):page187_i119:io61" )
			)
			( pin "J8E3.62"
				( objectStatus "@baseboard_fab2_lib.baseboard_fab2(sch_1):page187_i119:io62" )
			)
			( pin "J8E3.63"
				( objectStatus "@baseboard_fab2_lib.baseboard_fab2(sch_1):page187_i119:io63" )
			)
			( pin "J8E3.64"
				( objectStatus "@baseboard_fab2_lib.baseboard_fab2(sch_1):page187_i119:io64" )
			)
			( pin "J8E3.65"
				( objectStatus "@baseboard_fab2_lib.baseboard_fab2(sch_1):page187_i119:io65" )
			)
			( pin "J8E3.66"
				( objectStatus "@baseboard_fab2_lib.baseboard_fab2(sch_1):page187_i119:io66" )
			)
			( pin "J8E3.67"
				( objectStatus "@baseboard_fab2_lib.baseboard_fab2(sch_1):page187_i119:io67" )
			)
			( pin "J8E3.68"
				( objectStatus "@baseboard_fab2_lib.baseboard_fab2(sch_1):page187_i119:io68" )
			)
			( pin "J8E3.69"
				( objectStatus "@baseboard_fab2_lib.baseboard_fab2(sch_1):page187_i119:io69" )
			)
			( pin "J8E3.70"
				( objectStatus "@baseboard_fab2_lib.baseboard_fab2(sch_1):page187_i119:io70" )
			)
			( pin "J8E3.71"
				( objectStatus "@baseboard_fab2_lib.baseboard_fab2(sch_1):page187_i119:io71" )
			)
			( pin "J8E3.72"
				( objectStatus "@baseboard_fab2_lib.baseboard_fab2(sch_1):page187_i119:io72" )
			)
			( pin "J8E3.73"
				( objectStatus "@baseboard_fab2_lib.baseboard_fab2(sch_1):page187_i119:io73" )
			)
			( pin "J8E3.74"
				( objectStatus "@baseboard_fab2_lib.baseboard_fab2(sch_1):page187_i119:io74" )
			)
			( pin "J8E3.75"
				( objectStatus "@baseboard_fab2_lib.baseboard_fab2(sch_1):page187_i119:io75" )
			)
			( pin "J8E3.76"
				( objectStatus "@baseboard_fab2_lib.baseboard_fab2(sch_1):page187_i119:io76" )
			)
			( pin "J8E3.77"
				( objectStatus "@baseboard_fab2_lib.baseboard_fab2(sch_1):page187_i119:io77" )
			)
			( pin "J8E3.78"
				( objectStatus "@baseboard_fab2_lib.baseboard_fab2(sch_1):page187_i119:io78" )
			)
			( pin "J8E3.79"
				( objectStatus "@baseboard_fab2_lib.baseboard_fab2(sch_1):page187_i119:io79" )
			)
			( pin "J8E3.80"
				( objectStatus "@baseboard_fab2_lib.baseboard_fab2(sch_1):page187_i119:io80" )
			)
			( pin "R9E10.1"
				( objectStatus "@baseboard_fab2_lib.baseboard_fab2(sch_1):page187_i145:a" )
			)
			( pin "R9E10.2"
				( objectStatus "@baseboard_fab2_lib.baseboard_fab2(sch_1):page187_i145:b" )
			)
			( pin "R9E11.1"
				( objectStatus "@baseboard_fab2_lib.baseboard_fab2(sch_1):page187_i150:a" )
			)
			( pin "R9E11.2"
				( objectStatus "@baseboard_fab2_lib.baseboard_fab2(sch_1):page187_i150:b" )
			)
			( pin "R9E12.1"
				( objectStatus "@baseboard_fab2_lib.baseboard_fab2(sch_1):page187_i153:a" )
			)
			( pin "R9E12.2"
				( objectStatus "@baseboard_fab2_lib.baseboard_fab2(sch_1):page187_i153:b" )
			)
			( pin "C2R15.1"
				( objectStatus "@baseboard_fab2_lib.baseboard_fab2(sch_1):page188_i2:a" )
			)
			( pin "C2R15.2"
				( objectStatus "@baseboard_fab2_lib.baseboard_fab2(sch_1):page188_i2:b" )
			)
			( pin "C2R18.1"
				( objectStatus "@baseboard_fab2_lib.baseboard_fab2(sch_1):page188_i3:a" )
			)
			( pin "C2R18.2"
				( objectStatus "@baseboard_fab2_lib.baseboard_fab2(sch_1):page188_i3:b" )
			)
			( pin "C2P11.1"
				( objectStatus "@baseboard_fab2_lib.baseboard_fab2(sch_1):page188_i21:a" )
			)
			( pin "C2P11.2"
				( objectStatus "@baseboard_fab2_lib.baseboard_fab2(sch_1):page188_i21:b" )
			)
			( pin "C2P12.1"
				( objectStatus "@baseboard_fab2_lib.baseboard_fab2(sch_1):page188_i23:a" )
			)
			( pin "C2P12.2"
				( objectStatus "@baseboard_fab2_lib.baseboard_fab2(sch_1):page188_i23:b" )
			)
			( pin "C2R17.1"
				( objectStatus "@baseboard_fab2_lib.baseboard_fab2(sch_1):page188_i25:a" )
			)
			( pin "C2R17.2"
				( objectStatus "@baseboard_fab2_lib.baseboard_fab2(sch_1):page188_i25:b" )
			)
			( pin "J8E4.1"
				( objectStatus "@baseboard_fab2_lib.baseboard_fab2(sch_1):page188_i27:io1" )
			)
			( pin "J8E4.2"
				( objectStatus "@baseboard_fab2_lib.baseboard_fab2(sch_1):page188_i27:io2" )
			)
			( pin "J8E4.3"
				( objectStatus "@baseboard_fab2_lib.baseboard_fab2(sch_1):page188_i27:io3" )
			)
			( pin "J8E4.4"
				( objectStatus "@baseboard_fab2_lib.baseboard_fab2(sch_1):page188_i27:io4" )
			)
			( pin "J8E4.5"
				( objectStatus "@baseboard_fab2_lib.baseboard_fab2(sch_1):page188_i27:io5" )
			)
			( pin "J8E4.6"
				( objectStatus "@baseboard_fab2_lib.baseboard_fab2(sch_1):page188_i27:io6" )
			)
			( pin "J8E4.7"
				( objectStatus "@baseboard_fab2_lib.baseboard_fab2(sch_1):page188_i27:io7" )
			)
			( pin "J8E4.8"
				( objectStatus "@baseboard_fab2_lib.baseboard_fab2(sch_1):page188_i27:io8" )
			)
			( pin "J8E4.9"
				( objectStatus "@baseboard_fab2_lib.baseboard_fab2(sch_1):page188_i27:io9" )
			)
			( pin "J8E4.10"
				( objectStatus "@baseboard_fab2_lib.baseboard_fab2(sch_1):page188_i27:io10" )
			)
			( pin "J8E4.11"
				( objectStatus "@baseboard_fab2_lib.baseboard_fab2(sch_1):page188_i27:io11" )
			)
			( pin "J8E4.12"
				( objectStatus "@baseboard_fab2_lib.baseboard_fab2(sch_1):page188_i27:io12" )
			)
			( pin "J8E4.13"
				( objectStatus "@baseboard_fab2_lib.baseboard_fab2(sch_1):page188_i27:io13" )
			)
			( pin "J8E4.14"
				( objectStatus "@baseboard_fab2_lib.baseboard_fab2(sch_1):page188_i27:io14" )
			)
			( pin "J8E4.15"
				( objectStatus "@baseboard_fab2_lib.baseboard_fab2(sch_1):page188_i27:io15" )
			)
			( pin "J8E4.16"
				( objectStatus "@baseboard_fab2_lib.baseboard_fab2(sch_1):page188_i27:io16" )
			)
			( pin "J8E4.17"
				( objectStatus "@baseboard_fab2_lib.baseboard_fab2(sch_1):page188_i27:io17" )
			)
			( pin "J8E4.18"
				( objectStatus "@baseboard_fab2_lib.baseboard_fab2(sch_1):page188_i27:io18" )
			)
			( pin "J8E4.19"
				( objectStatus "@baseboard_fab2_lib.baseboard_fab2(sch_1):page188_i27:io19" )
			)
			( pin "J8E4.20"
				( objectStatus "@baseboard_fab2_lib.baseboard_fab2(sch_1):page188_i27:io20" )
			)
			( pin "J8E4.21"
				( objectStatus "@baseboard_fab2_lib.baseboard_fab2(sch_1):page188_i27:io21" )
			)
			( pin "J8E4.22"
				( objectStatus "@baseboard_fab2_lib.baseboard_fab2(sch_1):page188_i27:io22" )
			)
			( pin "J8E4.23"
				( objectStatus "@baseboard_fab2_lib.baseboard_fab2(sch_1):page188_i27:io23" )
			)
			( pin "J8E4.24"
				( objectStatus "@baseboard_fab2_lib.baseboard_fab2(sch_1):page188_i27:io24" )
			)
			( pin "J8E4.25"
				( objectStatus "@baseboard_fab2_lib.baseboard_fab2(sch_1):page188_i27:io25" )
			)
			( pin "J8E4.26"
				( objectStatus "@baseboard_fab2_lib.baseboard_fab2(sch_1):page188_i27:io26" )
			)
			( pin "J8E4.27"
				( objectStatus "@baseboard_fab2_lib.baseboard_fab2(sch_1):page188_i27:io27" )
			)
			( pin "J8E4.28"
				( objectStatus "@baseboard_fab2_lib.baseboard_fab2(sch_1):page188_i27:io28" )
			)
			( pin "J8E4.29"
				( objectStatus "@baseboard_fab2_lib.baseboard_fab2(sch_1):page188_i27:io29" )
			)
			( pin "J8E4.30"
				( objectStatus "@baseboard_fab2_lib.baseboard_fab2(sch_1):page188_i27:io30" )
			)
			( pin "J8E4.31"
				( objectStatus "@baseboard_fab2_lib.baseboard_fab2(sch_1):page188_i27:io31" )
			)
			( pin "J8E4.32"
				( objectStatus "@baseboard_fab2_lib.baseboard_fab2(sch_1):page188_i27:io32" )
			)
			( pin "J8E4.33"
				( objectStatus "@baseboard_fab2_lib.baseboard_fab2(sch_1):page188_i27:io33" )
			)
			( pin "J8E4.34"
				( objectStatus "@baseboard_fab2_lib.baseboard_fab2(sch_1):page188_i27:io34" )
			)
			( pin "J8E4.35"
				( objectStatus "@baseboard_fab2_lib.baseboard_fab2(sch_1):page188_i27:io35" )
			)
			( pin "J8E4.36"
				( objectStatus "@baseboard_fab2_lib.baseboard_fab2(sch_1):page188_i27:io36" )
			)
			( pin "J8E4.37"
				( objectStatus "@baseboard_fab2_lib.baseboard_fab2(sch_1):page188_i27:io37" )
			)
			( pin "J8E4.38"
				( objectStatus "@baseboard_fab2_lib.baseboard_fab2(sch_1):page188_i27:io38" )
			)
			( pin "J8E4.39"
				( objectStatus "@baseboard_fab2_lib.baseboard_fab2(sch_1):page188_i27:io39" )
			)
			( pin "J8E4.40"
				( objectStatus "@baseboard_fab2_lib.baseboard_fab2(sch_1):page188_i27:io40" )
			)
			( pin "J8E4.41"
				( objectStatus "@baseboard_fab2_lib.baseboard_fab2(sch_1):page188_i27:io41" )
			)
			( pin "J8E4.42"
				( objectStatus "@baseboard_fab2_lib.baseboard_fab2(sch_1):page188_i27:io42" )
			)
			( pin "J8E4.43"
				( objectStatus "@baseboard_fab2_lib.baseboard_fab2(sch_1):page188_i27:io43" )
			)
			( pin "J8E4.44"
				( objectStatus "@baseboard_fab2_lib.baseboard_fab2(sch_1):page188_i27:io44" )
			)
			( pin "J8E4.45"
				( objectStatus "@baseboard_fab2_lib.baseboard_fab2(sch_1):page188_i27:io45" )
			)
			( pin "J8E4.46"
				( objectStatus "@baseboard_fab2_lib.baseboard_fab2(sch_1):page188_i27:io46" )
			)
			( pin "J8E4.47"
				( objectStatus "@baseboard_fab2_lib.baseboard_fab2(sch_1):page188_i27:io47" )
			)
			( pin "J8E4.48"
				( objectStatus "@baseboard_fab2_lib.baseboard_fab2(sch_1):page188_i27:io48" )
			)
			( pin "J8E4.49"
				( objectStatus "@baseboard_fab2_lib.baseboard_fab2(sch_1):page188_i27:io49" )
			)
			( pin "J8E4.50"
				( objectStatus "@baseboard_fab2_lib.baseboard_fab2(sch_1):page188_i27:io50" )
			)
			( pin "J8E4.51"
				( objectStatus "@baseboard_fab2_lib.baseboard_fab2(sch_1):page188_i27:io51" )
			)
			( pin "J8E4.52"
				( objectStatus "@baseboard_fab2_lib.baseboard_fab2(sch_1):page188_i27:io52" )
			)
			( pin "J8E4.53"
				( objectStatus "@baseboard_fab2_lib.baseboard_fab2(sch_1):page188_i27:io53" )
			)
			( pin "J8E4.54"
				( objectStatus "@baseboard_fab2_lib.baseboard_fab2(sch_1):page188_i27:io54" )
			)
			( pin "J8E4.55"
				( objectStatus "@baseboard_fab2_lib.baseboard_fab2(sch_1):page188_i27:io55" )
			)
			( pin "J8E4.56"
				( objectStatus "@baseboard_fab2_lib.baseboard_fab2(sch_1):page188_i27:io56" )
			)
			( pin "J8E4.57"
				( objectStatus "@baseboard_fab2_lib.baseboard_fab2(sch_1):page188_i27:io57" )
			)
			( pin "J8E4.58"
				( objectStatus "@baseboard_fab2_lib.baseboard_fab2(sch_1):page188_i27:io58" )
			)
			( pin "J8E4.59"
				( objectStatus "@baseboard_fab2_lib.baseboard_fab2(sch_1):page188_i27:io59" )
			)
			( pin "J8E4.60"
				( objectStatus "@baseboard_fab2_lib.baseboard_fab2(sch_1):page188_i27:io60" )
			)
			( pin "J8E4.61"
				( objectStatus "@baseboard_fab2_lib.baseboard_fab2(sch_1):page188_i27:io61" )
			)
			( pin "J8E4.62"
				( objectStatus "@baseboard_fab2_lib.baseboard_fab2(sch_1):page188_i27:io62" )
			)
			( pin "J8E4.63"
				( objectStatus "@baseboard_fab2_lib.baseboard_fab2(sch_1):page188_i27:io63" )
			)
			( pin "J8E4.64"
				( objectStatus "@baseboard_fab2_lib.baseboard_fab2(sch_1):page188_i27:io64" )
			)
			( pin "C2R16.1"
				( objectStatus "@baseboard_fab2_lib.baseboard_fab2(sch_1):page188_i40:a" )
			)
			( pin "C2R16.2"
				( objectStatus "@baseboard_fab2_lib.baseboard_fab2(sch_1):page188_i40:b" )
			)
			( pin "C2P10.1"
				( objectStatus "@baseboard_fab2_lib.baseboard_fab2(sch_1):page188_i41:a" )
			)
			( pin "C2P10.2"
				( objectStatus "@baseboard_fab2_lib.baseboard_fab2(sch_1):page188_i41:b" )
			)
			( pin "C2P16.1"
				( objectStatus "@baseboard_fab2_lib.baseboard_fab2(sch_1):page188_i53:a" )
			)
			( pin "C2P16.2"
				( objectStatus "@baseboard_fab2_lib.baseboard_fab2(sch_1):page188_i53:b" )
			)
			( pin "C2P15.1"
				( objectStatus "@baseboard_fab2_lib.baseboard_fab2(sch_1):page188_i55:a" )
			)
			( pin "C2P15.2"
				( objectStatus "@baseboard_fab2_lib.baseboard_fab2(sch_1):page188_i55:b" )
			)
			( pin "C2P14.1"
				( objectStatus "@baseboard_fab2_lib.baseboard_fab2(sch_1):page188_i56:a" )
			)
			( pin "C2P14.2"
				( objectStatus "@baseboard_fab2_lib.baseboard_fab2(sch_1):page188_i56:b" )
			)
			( pin "C2P13.1"
				( objectStatus "@baseboard_fab2_lib.baseboard_fab2(sch_1):page188_i57:a" )
			)
			( pin "C2P13.2"
				( objectStatus "@baseboard_fab2_lib.baseboard_fab2(sch_1):page188_i57:b" )
			)
			( pin "C8C15.1"
				( objectStatus "@baseboard_fab2_lib.baseboard_fab2(sch_1):page188_i82:a" )
			)
			( pin "C8C15.2"
				( objectStatus "@baseboard_fab2_lib.baseboard_fab2(sch_1):page188_i82:b" )
			)
			( pin "C8C14.1"
				( objectStatus "@baseboard_fab2_lib.baseboard_fab2(sch_1):page188_i86:a" )
			)
			( pin "C8C14.2"
				( objectStatus "@baseboard_fab2_lib.baseboard_fab2(sch_1):page188_i86:b" )
			)
			( pin "R1R18.1"
				( objectStatus "@baseboard_fab2_lib.baseboard_fab2(sch_1):page188_i88:a" )
			)
			( pin "R1R18.2"
				( objectStatus "@baseboard_fab2_lib.baseboard_fab2(sch_1):page188_i88:b" )
			)
			( pin "R1R19.1"
				( objectStatus "@baseboard_fab2_lib.baseboard_fab2(sch_1):page188_i89:a" )
			)
			( pin "R1R19.2"
				( objectStatus "@baseboard_fab2_lib.baseboard_fab2(sch_1):page188_i89:b" )
			)
			( pin "R1R21.1"
				( objectStatus "@baseboard_fab2_lib.baseboard_fab2(sch_1):page188_i90:a" )
			)
			( pin "R1R21.2"
				( objectStatus "@baseboard_fab2_lib.baseboard_fab2(sch_1):page188_i90:b" )
			)
			( pin "R1R20.1"
				( objectStatus "@baseboard_fab2_lib.baseboard_fab2(sch_1):page188_i91:a" )
			)
			( pin "R1R20.2"
				( objectStatus "@baseboard_fab2_lib.baseboard_fab2(sch_1):page188_i91:b" )
			)
			( pin "R1R22.1"
				( objectStatus "@baseboard_fab2_lib.baseboard_fab2(sch_1):page188_i92:a" )
			)
			( pin "R1R22.2"
				( objectStatus "@baseboard_fab2_lib.baseboard_fab2(sch_1):page188_i92:b" )
			)
			( pin "R1R16.1"
				( objectStatus "@baseboard_fab2_lib.baseboard_fab2(sch_1):page188_i93:a" )
			)
			( pin "R1R16.2"
				( objectStatus "@baseboard_fab2_lib.baseboard_fab2(sch_1):page188_i93:b" )
			)
			( pin "R1R17.1"
				( objectStatus "@baseboard_fab2_lib.baseboard_fab2(sch_1):page188_i94:a" )
			)
			( pin "R1R17.2"
				( objectStatus "@baseboard_fab2_lib.baseboard_fab2(sch_1):page188_i94:b" )
			)
			( pin "R1R23.1"
				( objectStatus "@baseboard_fab2_lib.baseboard_fab2(sch_1):page188_i95:a" )
			)
			( pin "R1R23.2"
				( objectStatus "@baseboard_fab2_lib.baseboard_fab2(sch_1):page188_i95:b" )
			)
			( pin "R8G10.1"
				( objectStatus "@baseboard_fab2_lib.baseboard_fab2(sch_1):page189_i7:a" )
			)
			( pin "R8G10.2"
				( objectStatus "@baseboard_fab2_lib.baseboard_fab2(sch_1):page189_i7:b" )
			)
			( pin "R7G19.1"
				( objectStatus "@baseboard_fab2_lib.baseboard_fab2(sch_1):page189_i8:a" )
			)
			( pin "R7G19.2"
				( objectStatus "@baseboard_fab2_lib.baseboard_fab2(sch_1):page189_i8:b" )
			)
			( pin "R8G9.1"
				( objectStatus "@baseboard_fab2_lib.baseboard_fab2(sch_1):page189_i9:a" )
			)
			( pin "R8G9.2"
				( objectStatus "@baseboard_fab2_lib.baseboard_fab2(sch_1):page189_i9:b" )
			)
			( pin "R7G18.1"
				( objectStatus "@baseboard_fab2_lib.baseboard_fab2(sch_1):page189_i13:a" )
			)
			( pin "R7G18.2"
				( objectStatus "@baseboard_fab2_lib.baseboard_fab2(sch_1):page189_i13:b" )
			)
			( pin "R8G8.1"
				( objectStatus "@baseboard_fab2_lib.baseboard_fab2(sch_1):page189_i17:a" )
			)
			( pin "R8G8.2"
				( objectStatus "@baseboard_fab2_lib.baseboard_fab2(sch_1):page189_i17:b" )
			)
			( pin "R8G7.1"
				( objectStatus "@baseboard_fab2_lib.baseboard_fab2(sch_1):page189_i18:a" )
			)
			( pin "R8G7.2"
				( objectStatus "@baseboard_fab2_lib.baseboard_fab2(sch_1):page189_i18:b" )
			)
			( pin "R8G11.1"
				( objectStatus "@baseboard_fab2_lib.baseboard_fab2(sch_1):page189_i19:a" )
			)
			( pin "R8G11.2"
				( objectStatus "@baseboard_fab2_lib.baseboard_fab2(sch_1):page189_i19:b" )
			)
			( pin "R8G14.1"
				( objectStatus "@baseboard_fab2_lib.baseboard_fab2(sch_1):page189_i20:a" )
			)
			( pin "R8G14.2"
				( objectStatus "@baseboard_fab2_lib.baseboard_fab2(sch_1):page189_i20:b" )
			)
			( pin "R8G12.1"
				( objectStatus "@baseboard_fab2_lib.baseboard_fab2(sch_1):page189_i21:a" )
			)
			( pin "R8G12.2"
				( objectStatus "@baseboard_fab2_lib.baseboard_fab2(sch_1):page189_i21:b" )
			)
			( pin "R8G16.1"
				( objectStatus "@baseboard_fab2_lib.baseboard_fab2(sch_1):page189_i22:a" )
			)
			( pin "R8G16.2"
				( objectStatus "@baseboard_fab2_lib.baseboard_fab2(sch_1):page189_i22:b" )
			)
			( pin "R8G13.1"
				( objectStatus "@baseboard_fab2_lib.baseboard_fab2(sch_1):page189_i23:a" )
			)
			( pin "R8G13.2"
				( objectStatus "@baseboard_fab2_lib.baseboard_fab2(sch_1):page189_i23:b" )
			)
			( pin "R8G15.1"
				( objectStatus "@baseboard_fab2_lib.baseboard_fab2(sch_1):page189_i24:a" )
			)
			( pin "R8G15.2"
				( objectStatus "@baseboard_fab2_lib.baseboard_fab2(sch_1):page189_i24:b" )
			)
			( pin "R8G17.1"
				( objectStatus "@baseboard_fab2_lib.baseboard_fab2(sch_1):page189_i25:a" )
			)
			( pin "R8G17.2"
				( objectStatus "@baseboard_fab2_lib.baseboard_fab2(sch_1):page189_i25:b" )
			)
			( pin "R8G18.1"
				( objectStatus "@baseboard_fab2_lib.baseboard_fab2(sch_1):page189_i26:a" )
			)
			( pin "R8G18.2"
				( objectStatus "@baseboard_fab2_lib.baseboard_fab2(sch_1):page189_i26:b" )
			)
			( pin "R7G16.1"
				( objectStatus "@baseboard_fab2_lib.baseboard_fab2(sch_1):page189_i27:a" )
			)
			( pin "R7G16.2"
				( objectStatus "@baseboard_fab2_lib.baseboard_fab2(sch_1):page189_i27:b" )
			)
			( pin "R7G15.1"
				( objectStatus "@baseboard_fab2_lib.baseboard_fab2(sch_1):page189_i36:a" )
			)
			( pin "R7G15.2"
				( objectStatus "@baseboard_fab2_lib.baseboard_fab2(sch_1):page189_i36:b" )
			)
			( pin "R7G17.1"
				( objectStatus "@baseboard_fab2_lib.baseboard_fab2(sch_1):page189_i37:a" )
			)
			( pin "R7G17.2"
				( objectStatus "@baseboard_fab2_lib.baseboard_fab2(sch_1):page189_i37:b" )
			)
			( pin "R7G14.1"
				( objectStatus "@baseboard_fab2_lib.baseboard_fab2(sch_1):page189_i38:a" )
			)
			( pin "R7G14.2"
				( objectStatus "@baseboard_fab2_lib.baseboard_fab2(sch_1):page189_i38:b" )
			)
			( pin "R3R15.1"
				( objectStatus "@baseboard_fab2_lib.baseboard_fab2(sch_1):page189_i44:a" )
			)
			( pin "R3R15.2"
				( objectStatus "@baseboard_fab2_lib.baseboard_fab2(sch_1):page189_i44:b" )
			)
			( pin "R3R11.1"
				( objectStatus "@baseboard_fab2_lib.baseboard_fab2(sch_1):page189_i45:a" )
			)
			( pin "R3R11.2"
				( objectStatus "@baseboard_fab2_lib.baseboard_fab2(sch_1):page189_i45:b" )
			)
			( pin "J7G2.1"
				( objectStatus "@baseboard_fab2_lib.baseboard_fab2(sch_1):page189_i47:io1" )
			)
			( pin "J7G2.2"
				( objectStatus "@baseboard_fab2_lib.baseboard_fab2(sch_1):page189_i47:io2" )
			)
			( pin "J7G2.3"
				( objectStatus "@baseboard_fab2_lib.baseboard_fab2(sch_1):page189_i47:io3" )
			)
			( pin "J7G2.4"
				( objectStatus "@baseboard_fab2_lib.baseboard_fab2(sch_1):page189_i47:io4" )
			)
			( pin "J7G2.5"
				( objectStatus "@baseboard_fab2_lib.baseboard_fab2(sch_1):page189_i47:io5" )
			)
			( pin "J7G2.6"
				( objectStatus "@baseboard_fab2_lib.baseboard_fab2(sch_1):page189_i47:io6" )
			)
			( pin "J7G2.7"
				( objectStatus "@baseboard_fab2_lib.baseboard_fab2(sch_1):page189_i47:io7" )
			)
			( pin "J7G2.8"
				( objectStatus "@baseboard_fab2_lib.baseboard_fab2(sch_1):page189_i47:io8" )
			)
			( pin "CR3U1.2"
				( objectStatus "@baseboard_fab2_lib.baseboard_fab2(sch_1):page189_i49:a" )
			)
			( pin "CR3U1.1"
				( objectStatus "@baseboard_fab2_lib.baseboard_fab2(sch_1):page189_i49:c" )
			)
			( pin "R8G20.1"
				( objectStatus "@baseboard_fab2_lib.baseboard_fab2(sch_1):page189_i50:a" )
			)
			( pin "R8G20.2"
				( objectStatus "@baseboard_fab2_lib.baseboard_fab2(sch_1):page189_i50:b" )
			)
			( pin "R7G23.1"
				( objectStatus "@baseboard_fab2_lib.baseboard_fab2(sch_1):page189_i51:a" )
			)
			( pin "R7G23.2"
				( objectStatus "@baseboard_fab2_lib.baseboard_fab2(sch_1):page189_i51:b" )
			)
			( pin "R7G22.1"
				( objectStatus "@baseboard_fab2_lib.baseboard_fab2(sch_1):page189_i53:a" )
			)
			( pin "R7G22.2"
				( objectStatus "@baseboard_fab2_lib.baseboard_fab2(sch_1):page189_i53:b" )
			)
			( pin "R8G23.1"
				( objectStatus "@baseboard_fab2_lib.baseboard_fab2(sch_1):page189_i56:a" )
			)
			( pin "R8G23.2"
				( objectStatus "@baseboard_fab2_lib.baseboard_fab2(sch_1):page189_i56:b" )
			)
			( pin "R7G21.1"
				( objectStatus "@baseboard_fab2_lib.baseboard_fab2(sch_1):page189_i63:a" )
			)
			( pin "R7G21.2"
				( objectStatus "@baseboard_fab2_lib.baseboard_fab2(sch_1):page189_i63:b" )
			)
			( pin "R8G19.1"
				( objectStatus "@baseboard_fab2_lib.baseboard_fab2(sch_1):page189_i64:a" )
			)
			( pin "R8G19.2"
				( objectStatus "@baseboard_fab2_lib.baseboard_fab2(sch_1):page189_i64:b" )
			)
			( pin "R8G21.1"
				( objectStatus "@baseboard_fab2_lib.baseboard_fab2(sch_1):page189_i65:a" )
			)
			( pin "R8G21.2"
				( objectStatus "@baseboard_fab2_lib.baseboard_fab2(sch_1):page189_i65:b" )
			)
			( pin "R8G22.1"
				( objectStatus "@baseboard_fab2_lib.baseboard_fab2(sch_1):page189_i66:a" )
			)
			( pin "R8G22.2"
				( objectStatus "@baseboard_fab2_lib.baseboard_fab2(sch_1):page189_i66:b" )
			)
			( pin "R3P34.1"
				( objectStatus "@baseboard_fab2_lib.baseboard_fab2(sch_1):page190_i116:a" )
			)
			( pin "R3P34.2"
				( objectStatus "@baseboard_fab2_lib.baseboard_fab2(sch_1):page190_i116:b" )
			)
			( pin "R3P35.1"
				( objectStatus "@baseboard_fab2_lib.baseboard_fab2(sch_1):page190_i117:a" )
			)
			( pin "R3P35.2"
				( objectStatus "@baseboard_fab2_lib.baseboard_fab2(sch_1):page190_i117:b" )
			)
			( pin "U8D7.P4"
				( objectStatus "@baseboard_fab2_lib.baseboard_fab2(sch_1):page190_i179:pb3a" )
			)
			( pin "U8D7.T4"
				( objectStatus "@baseboard_fab2_lib.baseboard_fab2(sch_1):page190_i179:pb3b" )
			)
			( pin "U8D7.T2"
				( objectStatus "@baseboard_fab2_lib.baseboard_fab2(sch_1):page190_i179:pb3c" )
			)
			( pin "U8D7.R3"
				( objectStatus "@baseboard_fab2_lib.baseboard_fab2(sch_1):page190_i179:pb3d" )
			)
			( pin "U8D7.R5"
				( objectStatus "@baseboard_fab2_lib.baseboard_fab2(sch_1):page190_i179:pb5a_csspin" )
			)
			( pin "U8D7.P5"
				( objectStatus "@baseboard_fab2_lib.baseboard_fab2(sch_1):page190_i179:pb5b" )
			)
			( pin "U8D7.T5"
				( objectStatus "@baseboard_fab2_lib.baseboard_fab2(sch_1):page190_i179:pb6a" )
			)
			( pin "U8D7.R6"
				( objectStatus "@baseboard_fab2_lib.baseboard_fab2(sch_1):page190_i179:pb6b" )
			)
			( pin "U8D7.T3"
				( objectStatus "@baseboard_fab2_lib.baseboard_fab2(sch_1):page190_i179:pb6c" )
			)
			( pin "U8D7.R4"
				( objectStatus "@baseboard_fab2_lib.baseboard_fab2(sch_1):page190_i179:pb6d" )
			)
			( pin "U8D7.P6"
				( objectStatus "@baseboard_fab2_lib.baseboard_fab2(sch_1):page190_i179:pb8a_mclk_cclk" )
			)
			( pin "U8D7.T6"
				( objectStatus "@baseboard_fab2_lib.baseboard_fab2(sch_1):page190_i179:pb8b_so_spiso" )
			)
			( pin "U8D7.N6"
				( objectStatus "@baseboard_fab2_lib.baseboard_fab2(sch_1):page190_i179:pb8c" )
			)
			( pin "U8D7.L7"
				( objectStatus "@baseboard_fab2_lib.baseboard_fab2(sch_1):page190_i179:pb8d" )
			)
			( pin "U8D7.R7"
				( objectStatus "@baseboard_fab2_lib.baseboard_fab2(sch_1):page190_i179:pb9a" )
			)
			( pin "U8D7.P7"
				( objectStatus "@baseboard_fab2_lib.baseboard_fab2(sch_1):page190_i179:pb9b" )
			)
			( pin "U8D7.M7"
				( objectStatus "@baseboard_fab2_lib.baseboard_fab2(sch_1):page190_i179:pb9c" )
			)
			( pin "U8D7.N7"
				( objectStatus "@baseboard_fab2_lib.baseboard_fab2(sch_1):page190_i179:pb9d" )
			)
			( pin "U8D7.T7"
				( objectStatus "@baseboard_fab2_lib.baseboard_fab2(sch_1):page190_i179:pb11a_pclkt2_0" )
			)
			( pin "U8D7.R8"
				( objectStatus "@baseboard_fab2_lib.baseboard_fab2(sch_1):page190_i179:pb11b_pclkc2_0" )
			)
			( pin "U8D7.M6"
				( objectStatus "@baseboard_fab2_lib.baseboard_fab2(sch_1):page190_i179:pb11c" )
			)
			( pin "U8D7.L8"
				( objectStatus "@baseboard_fab2_lib.baseboard_fab2(sch_1):page190_i179:pb11d" )
			)
			( pin "U8D7.P8"
				( objectStatus "@baseboard_fab2_lib.baseboard_fab2(sch_1):page190_i179:pb12a" )
			)
			( pin "U8D7.T8"
				( objectStatus "@baseboard_fab2_lib.baseboard_fab2(sch_1):page190_i179:pb12b" )
			)
			( pin "U8D7.N8"
				( objectStatus "@baseboard_fab2_lib.baseboard_fab2(sch_1):page190_i179:pb12c" )
			)
			( pin "U8D7.L9"
				( objectStatus "@baseboard_fab2_lib.baseboard_fab2(sch_1):page190_i179:pb12d" )
			)
			( pin "U8D7.T9"
				( objectStatus "@baseboard_fab2_lib.baseboard_fab2(sch_1):page190_i179:pb16a_pclkt2_1" )
			)
			( pin "U8D7.P9"
				( objectStatus "@baseboard_fab2_lib.baseboard_fab2(sch_1):page190_i179:pb16b_pclkc2_1" )
			)
			( pin "U8D7.M8"
				( objectStatus "@baseboard_fab2_lib.baseboard_fab2(sch_1):page190_i179:pb16c" )
			)
			( pin "U8D7.N9"
				( objectStatus "@baseboard_fab2_lib.baseboard_fab2(sch_1):page190_i179:pb16d" )
			)
			( pin "U8D7.R9"
				( objectStatus "@baseboard_fab2_lib.baseboard_fab2(sch_1):page190_i179:pb18a" )
			)
			( pin "U8D7.T10"
				( objectStatus "@baseboard_fab2_lib.baseboard_fab2(sch_1):page190_i179:pb18b" )
			)
			( pin "U8D7.M9"
				( objectStatus "@baseboard_fab2_lib.baseboard_fab2(sch_1):page190_i179:pb18c" )
			)
			( pin "U8D7.L10"
				( objectStatus "@baseboard_fab2_lib.baseboard_fab2(sch_1):page190_i179:pb18d" )
			)
			( pin "U8D7.P10"
				( objectStatus "@baseboard_fab2_lib.baseboard_fab2(sch_1):page190_i179:pb19a" )
			)
			( pin "U8D7.R10"
				( objectStatus "@baseboard_fab2_lib.baseboard_fab2(sch_1):page190_i179:pb19b" )
			)
			( pin "U8D7.N10"
				( objectStatus "@baseboard_fab2_lib.baseboard_fab2(sch_1):page190_i179:pb19c" )
			)
			( pin "U8D7.M11"
				( objectStatus "@baseboard_fab2_lib.baseboard_fab2(sch_1):page190_i179:pb19d" )
			)
			( pin "U8D7.T11"
				( objectStatus "@baseboard_fab2_lib.baseboard_fab2(sch_1):page190_i179:pb21a" )
			)
			( pin "U8D7.P11"
				( objectStatus "@baseboard_fab2_lib.baseboard_fab2(sch_1):page190_i179:pb21b" )
			)
			( pin "U8D7.M10"
				( objectStatus "@baseboard_fab2_lib.baseboard_fab2(sch_1):page190_i179:pb21c" )
			)
			( pin "U8D7.N11"
				( objectStatus "@baseboard_fab2_lib.baseboard_fab2(sch_1):page190_i179:pb21d" )
			)
			( pin "U8D7.R11"
				( objectStatus "@baseboard_fab2_lib.baseboard_fab2(sch_1):page190_i179:pb22a" )
			)
			( pin "U8D7.T12"
				( objectStatus "@baseboard_fab2_lib.baseboard_fab2(sch_1):page190_i179:pb22b" )
			)
			( pin "U8D7.R13"
				( objectStatus "@baseboard_fab2_lib.baseboard_fab2(sch_1):page190_i179:pb22c" )
			)
			( pin "U8D7.T14"
				( objectStatus "@baseboard_fab2_lib.baseboard_fab2(sch_1):page190_i179:pb22d" )
			)
			( pin "U8D7.P12"
				( objectStatus "@baseboard_fab2_lib.baseboard_fab2(sch_1):page190_i179:pb24a" )
			)
			( pin "U8D7.T13"
				( objectStatus "@baseboard_fab2_lib.baseboard_fab2(sch_1):page190_i179:pb24b" )
			)
			( pin "U8D7.R12"
				( objectStatus "@baseboard_fab2_lib.baseboard_fab2(sch_1):page190_i179:pb25a_sn" )
			)
			( pin "U8D7.P13"
				( objectStatus "@baseboard_fab2_lib.baseboard_fab2(sch_1):page190_i179:pb25b_si_sispi" )
			)
			( pin "U8D7.T15"
				( objectStatus "@baseboard_fab2_lib.baseboard_fab2(sch_1):page190_i179:pb25c" )
			)
			( pin "U8D7.R14"
				( objectStatus "@baseboard_fab2_lib.baseboard_fab2(sch_1):page190_i179:pb25d" )
			)
			( pin "U8D7.D3"
				( objectStatus "@baseboard_fab2_lib.baseboard_fab2(sch_1):page190_i179:pl1a_l_gpllt_fb" )
			)
			( pin "U8D7.D1"
				( objectStatus "@baseboard_fab2_lib.baseboard_fab2(sch_1):page190_i179:pl1b_l_gpllc_fb" )
			)
			( pin "U8D7.B1"
				( objectStatus "@baseboard_fab2_lib.baseboard_fab2(sch_1):page190_i179:pl1c" )
			)
			( pin "U8D7.C2"
				( objectStatus "@baseboard_fab2_lib.baseboard_fab2(sch_1):page190_i179:pl1d" )
			)
			( pin "U8D7.E2"
				( objectStatus "@baseboard_fab2_lib.baseboard_fab2(sch_1):page190_i179:pl2a_l_gpllt_in" )
			)
			( pin "U8D7.E3"
				( objectStatus "@baseboard_fab2_lib.baseboard_fab2(sch_1):page190_i179:pl2b_l_gpllc_in" )
			)
			( pin "U8D7.C1"
				( objectStatus "@baseboard_fab2_lib.baseboard_fab2(sch_1):page190_i179:pl2c" )
			)
			( pin "U8D7.D2"
				( objectStatus "@baseboard_fab2_lib.baseboard_fab2(sch_1):page190_i179:pl2d" )
			)
			( pin "U8D7.E1"
				( objectStatus "@baseboard_fab2_lib.baseboard_fab2(sch_1):page190_i179:pl3a_pclkt5_0" )
			)
			( pin "U8D7.F2"
				( objectStatus "@baseboard_fab2_lib.baseboard_fab2(sch_1):page190_i179:pl3b_pclkc5_0" )
			)
			( pin "U8D7.F4"
				( objectStatus "@baseboard_fab2_lib.baseboard_fab2(sch_1):page190_i179:pl3c" )
			)
			( pin "U8D7.G6"
				( objectStatus "@baseboard_fab2_lib.baseboard_fab2(sch_1):page190_i179:pl3d" )
			)
			( pin "U8D7.F3"
				( objectStatus "@baseboard_fab2_lib.baseboard_fab2(sch_1):page190_i179:pl4a" )
			)
			( pin "U8D7.F1"
				( objectStatus "@baseboard_fab2_lib.baseboard_fab2(sch_1):page190_i179:pl4b" )
			)
			( pin "U8D7.G5"
				( objectStatus "@baseboard_fab2_lib.baseboard_fab2(sch_1):page190_i179:pl4c" )
			)
			( pin "U8D7.G4"
				( objectStatus "@baseboard_fab2_lib.baseboard_fab2(sch_1):page190_i179:pl4d" )
			)
			( pin "U8D7.G2"
				( objectStatus "@baseboard_fab2_lib.baseboard_fab2(sch_1):page190_i179:pl5a" )
			)
			( pin "U8D7.G3"
				( objectStatus "@baseboard_fab2_lib.baseboard_fab2(sch_1):page190_i179:pl5b" )
			)
			( pin "U8D7.F5"
				( objectStatus "@baseboard_fab2_lib.baseboard_fab2(sch_1):page190_i179:pl5c" )
			)
			( pin "U8D7.H6"
				( objectStatus "@baseboard_fab2_lib.baseboard_fab2(sch_1):page190_i179:pl5d" )
			)
			( pin "U8D7.G1"
				( objectStatus "@baseboard_fab2_lib.baseboard_fab2(sch_1):page190_i179:pl6a" )
			)
			( pin "U8D7.H2"
				( objectStatus "@baseboard_fab2_lib.baseboard_fab2(sch_1):page190_i179:pl6b" )
			)
			( pin "U8D7.H4"
				( objectStatus "@baseboard_fab2_lib.baseboard_fab2(sch_1):page190_i179:pl6c" )
			)
			( pin "U8D7.J6"
				( objectStatus "@baseboard_fab2_lib.baseboard_fab2(sch_1):page190_i179:pl6d" )
			)
			( pin "U8D7.H3"
				( objectStatus "@baseboard_fab2_lib.baseboard_fab2(sch_1):page190_i179:pl7a" )
			)
			( pin "U8D7.H1"
				( objectStatus "@baseboard_fab2_lib.baseboard_fab2(sch_1):page190_i179:pl7b" )
			)
			( pin "U8D7.J1"
				( objectStatus "@baseboard_fab2_lib.baseboard_fab2(sch_1):page190_i179:pl7c_pclkt4_0" )
			)
			( pin "U8D7.J3"
				( objectStatus "@baseboard_fab2_lib.baseboard_fab2(sch_1):page190_i179:pl7d_pclkc4_0" )
			)
			( pin "U8D7.J2"
				( objectStatus "@baseboard_fab2_lib.baseboard_fab2(sch_1):page190_i179:pl9a" )
			)
			( pin "U8D7.K1"
				( objectStatus "@baseboard_fab2_lib.baseboard_fab2(sch_1):page190_i179:pl9b" )
			)
			( pin "U8D7.H5"
				( objectStatus "@baseboard_fab2_lib.baseboard_fab2(sch_1):page190_i179:pl9c" )
			)
			( pin "U8D7.J4"
				( objectStatus "@baseboard_fab2_lib.baseboard_fab2(sch_1):page190_i179:pl9d" )
			)
			( pin "U8D7.K3"
				( objectStatus "@baseboard_fab2_lib.baseboard_fab2(sch_1):page190_i179:pl10a" )
			)
			( pin "U8D7.K2"
				( objectStatus "@baseboard_fab2_lib.baseboard_fab2(sch_1):page190_i179:pl10b" )
			)
			( pin "U8D7.J5"
				( objectStatus "@baseboard_fab2_lib.baseboard_fab2(sch_1):page190_i179:pl10c" )
			)
			( pin "U8D7.K6"
				( objectStatus "@baseboard_fab2_lib.baseboard_fab2(sch_1):page190_i179:pl10d" )
			)
			( pin "U8D7.L1"
				( objectStatus "@baseboard_fab2_lib.baseboard_fab2(sch_1):page190_i179:pl11a" )
			)
			( pin "U8D7.L3"
				( objectStatus "@baseboard_fab2_lib.baseboard_fab2(sch_1):page190_i179:pl11b" )
			)
			( pin "U8D7.K4"
				( objectStatus "@baseboard_fab2_lib.baseboard_fab2(sch_1):page190_i179:pl11c" )
			)
			( pin "U8D7.L5"
				( objectStatus "@baseboard_fab2_lib.baseboard_fab2(sch_1):page190_i179:pl11d" )
			)
			( pin "U8D7.L2"
				( objectStatus "@baseboard_fab2_lib.baseboard_fab2(sch_1):page190_i179:pl12a_pclkt3_0" )
			)
			( pin "U8D7.M1"
				( objectStatus "@baseboard_fab2_lib.baseboard_fab2(sch_1):page190_i179:pl12b_pclkc3_0" )
			)
			( pin "U8D7.K5"
				( objectStatus "@baseboard_fab2_lib.baseboard_fab2(sch_1):page190_i179:pl12c" )
			)
			( pin "U8D7.L4"
				( objectStatus "@baseboard_fab2_lib.baseboard_fab2(sch_1):page190_i179:pl12d" )
			)
			( pin "U8D7.M3"
				( objectStatus "@baseboard_fab2_lib.baseboard_fab2(sch_1):page190_i179:pl13a" )
			)
			( pin "U8D7.N1"
				( objectStatus "@baseboard_fab2_lib.baseboard_fab2(sch_1):page190_i179:pl13b" )
			)
			( pin "U8D7.N2"
				( objectStatus "@baseboard_fab2_lib.baseboard_fab2(sch_1):page190_i179:pl13c" )
			)
			( pin "U8D7.P1"
				( objectStatus "@baseboard_fab2_lib.baseboard_fab2(sch_1):page190_i179:pl13d" )
			)
			( pin "U8D7.M2"
				( objectStatus "@baseboard_fab2_lib.baseboard_fab2(sch_1):page190_i179:pl14a" )
			)
			( pin "U8D7.N3"
				( objectStatus "@baseboard_fab2_lib.baseboard_fab2(sch_1):page190_i179:pl14b" )
			)
			( pin "U8D7.R1"
				( objectStatus "@baseboard_fab2_lib.baseboard_fab2(sch_1):page190_i179:pl14c" )
			)
			( pin "U8D7.P2"
				( objectStatus "@baseboard_fab2_lib.baseboard_fab2(sch_1):page190_i179:pl14d" )
			)
			( pin "R2R2.1"
				( objectStatus "@baseboard_fab2_lib.baseboard_fab2(sch_1):page190_i338:a" )
			)
			( pin "R2R2.2"
				( objectStatus "@baseboard_fab2_lib.baseboard_fab2(sch_1):page190_i338:b" )
			)
			( pin "U8D7.D14"
				( objectStatus "@baseboard_fab2_lib.baseboard_fab2(sch_1):page191_i59:pr1a" )
			)
			( pin "U8D7.E15"
				( objectStatus "@baseboard_fab2_lib.baseboard_fab2(sch_1):page191_i59:pr1b" )
			)
			( pin "U8D7.C15"
				( objectStatus "@baseboard_fab2_lib.baseboard_fab2(sch_1):page191_i59:pr1c" )
			)
			( pin "U8D7.B16"
				( objectStatus "@baseboard_fab2_lib.baseboard_fab2(sch_1):page191_i59:pr1d" )
			)
			( pin "U8D7.D16"
				( objectStatus "@baseboard_fab2_lib.baseboard_fab2(sch_1):page191_i59:pr2a" )
			)
			( pin "U8D7.E14"
				( objectStatus "@baseboard_fab2_lib.baseboard_fab2(sch_1):page191_i59:pr2b" )
			)
			( pin "U8D7.C16"
				( objectStatus "@baseboard_fab2_lib.baseboard_fab2(sch_1):page191_i59:pr2c" )
			)
			( pin "U8D7.D15"
				( objectStatus "@baseboard_fab2_lib.baseboard_fab2(sch_1):page191_i59:pr2d" )
			)
			( pin "U8D7.E16"
				( objectStatus "@baseboard_fab2_lib.baseboard_fab2(sch_1):page191_i59:pr3a" )
			)
			( pin "U8D7.F15"
				( objectStatus "@baseboard_fab2_lib.baseboard_fab2(sch_1):page191_i59:pr3b" )
			)
			( pin "U8D7.F13"
				( objectStatus "@baseboard_fab2_lib.baseboard_fab2(sch_1):page191_i59:pr3c" )
			)
			( pin "U8D7.G12"
				( objectStatus "@baseboard_fab2_lib.baseboard_fab2(sch_1):page191_i59:pr3d" )
			)
			( pin "U8D7.F14"
				( objectStatus "@baseboard_fab2_lib.baseboard_fab2(sch_1):page191_i59:pr4a" )
			)
			( pin "U8D7.F16"
				( objectStatus "@baseboard_fab2_lib.baseboard_fab2(sch_1):page191_i59:pr4b" )
			)
			( pin "U8D7.F12"
				( objectStatus "@baseboard_fab2_lib.baseboard_fab2(sch_1):page191_i59:pr4c" )
			)
			( pin "U8D7.G13"
				( objectStatus "@baseboard_fab2_lib.baseboard_fab2(sch_1):page191_i59:pr4d" )
			)
			( pin "U8D7.G15"
				( objectStatus "@baseboard_fab2_lib.baseboard_fab2(sch_1):page191_i59:pr5a" )
			)
			( pin "U8D7.G14"
				( objectStatus "@baseboard_fab2_lib.baseboard_fab2(sch_1):page191_i59:pr5b" )
			)
			( pin "U8D7.G11"
				( objectStatus "@baseboard_fab2_lib.baseboard_fab2(sch_1):page191_i59:pr5c" )
			)
			( pin "U8D7.H12"
				( objectStatus "@baseboard_fab2_lib.baseboard_fab2(sch_1):page191_i59:pr5d" )
			)
			( pin "U8D7.G16"
				( objectStatus "@baseboard_fab2_lib.baseboard_fab2(sch_1):page191_i59:pr6a" )
			)
			( pin "U8D7.H15"
				( objectStatus "@baseboard_fab2_lib.baseboard_fab2(sch_1):page191_i59:pr6b" )
			)
			( pin "U8D7.H13"
				( objectStatus "@baseboard_fab2_lib.baseboard_fab2(sch_1):page191_i59:pr6c" )
			)
			( pin "U8D7.J12"
				( objectStatus "@baseboard_fab2_lib.baseboard_fab2(sch_1):page191_i59:pr6d" )
			)
			( pin "U8D7.H14"
				( objectStatus "@baseboard_fab2_lib.baseboard_fab2(sch_1):page191_i59:pr7a_pclkt1_0" )
			)
			( pin "U8D7.H16"
				( objectStatus "@baseboard_fab2_lib.baseboard_fab2(sch_1):page191_i59:pr7b_pclkc1_0" )
			)
			( pin "U8D7.J16"
				( objectStatus "@baseboard_fab2_lib.baseboard_fab2(sch_1):page191_i59:pr7c" )
			)
			( pin "U8D7.J14"
				( objectStatus "@baseboard_fab2_lib.baseboard_fab2(sch_1):page191_i59:pr7d" )
			)
			( pin "U8D7.J15"
				( objectStatus "@baseboard_fab2_lib.baseboard_fab2(sch_1):page191_i59:pr9a" )
			)
			( pin "U8D7.K16"
				( objectStatus "@baseboard_fab2_lib.baseboard_fab2(sch_1):page191_i59:pr9b" )
			)
			( pin "U8D7.H11"
				( objectStatus "@baseboard_fab2_lib.baseboard_fab2(sch_1):page191_i59:pr9c" )
			)
			( pin "U8D7.J13"
				( objectStatus "@baseboard_fab2_lib.baseboard_fab2(sch_1):page191_i59:pr9d" )
			)
			( pin "U8D7.K14"
				( objectStatus "@baseboard_fab2_lib.baseboard_fab2(sch_1):page191_i59:pr10a" )
			)
			( pin "U8D7.K15"
				( objectStatus "@baseboard_fab2_lib.baseboard_fab2(sch_1):page191_i59:pr10b" )
			)
			( pin "U8D7.J11"
				( objectStatus "@baseboard_fab2_lib.baseboard_fab2(sch_1):page191_i59:pr10c" )
			)
			( pin "U8D7.L12"
				( objectStatus "@baseboard_fab2_lib.baseboard_fab2(sch_1):page191_i59:pr10d" )
			)
			( pin "U8D7.L16"
				( objectStatus "@baseboard_fab2_lib.baseboard_fab2(sch_1):page191_i59:pr11a" )
			)
			( pin "U8D7.L14"
				( objectStatus "@baseboard_fab2_lib.baseboard_fab2(sch_1):page191_i59:pr11b" )
			)
			( pin "U8D7.K13"
				( objectStatus "@baseboard_fab2_lib.baseboard_fab2(sch_1):page191_i59:pr11c" )
			)
			( pin "U8D7.K12"
				( objectStatus "@baseboard_fab2_lib.baseboard_fab2(sch_1):page191_i59:pr11d" )
			)
			( pin "U8D7.L15"
				( objectStatus "@baseboard_fab2_lib.baseboard_fab2(sch_1):page191_i59:pr12a" )
			)
			( pin "U8D7.M16"
				( objectStatus "@baseboard_fab2_lib.baseboard_fab2(sch_1):page191_i59:pr12b" )
			)
			( pin "U8D7.K11"
				( objectStatus "@baseboard_fab2_lib.baseboard_fab2(sch_1):page191_i59:pr12c" )
			)
			( pin "U8D7.L13"
				( objectStatus "@baseboard_fab2_lib.baseboard_fab2(sch_1):page191_i59:pr12d" )
			)
			( pin "U8D7.M14"
				( objectStatus "@baseboard_fab2_lib.baseboard_fab2(sch_1):page191_i59:pr13a" )
			)
			( pin "U8D7.M15"
				( objectStatus "@baseboard_fab2_lib.baseboard_fab2(sch_1):page191_i59:pr13b" )
			)
			( pin "U8D7.N15"
				( objectStatus "@baseboard_fab2_lib.baseboard_fab2(sch_1):page191_i59:pr13c" )
			)
			( pin "U8D7.P16"
				( objectStatus "@baseboard_fab2_lib.baseboard_fab2(sch_1):page191_i59:pr13d" )
			)
			( pin "U8D7.N16"
				( objectStatus "@baseboard_fab2_lib.baseboard_fab2(sch_1):page191_i59:pr14a" )
			)
			( pin "U8D7.N14"
				( objectStatus "@baseboard_fab2_lib.baseboard_fab2(sch_1):page191_i59:pr14b" )
			)
			( pin "U8D7.P15"
				( objectStatus "@baseboard_fab2_lib.baseboard_fab2(sch_1):page191_i59:pr14c" )
			)
			( pin "U8D7.R16"
				( objectStatus "@baseboard_fab2_lib.baseboard_fab2(sch_1):page191_i59:pr14d" )
			)
			( pin "U8D7.C4"
				( objectStatus "@baseboard_fab2_lib.baseboard_fab2(sch_1):page191_i59:pt9a" )
			)
			( pin "U8D7.B5"
				( objectStatus "@baseboard_fab2_lib.baseboard_fab2(sch_1):page191_i59:pt9b" )
			)
			( pin "U8D7.B3"
				( objectStatus "@baseboard_fab2_lib.baseboard_fab2(sch_1):page191_i59:pt9c" )
			)
			( pin "U8D7.A4"
				( objectStatus "@baseboard_fab2_lib.baseboard_fab2(sch_1):page191_i59:pt10a" )
			)
			( pin "U8D7.C5"
				( objectStatus "@baseboard_fab2_lib.baseboard_fab2(sch_1):page191_i59:pt10b" )
			)
			( pin "U8D7.A5"
				( objectStatus "@baseboard_fab2_lib.baseboard_fab2(sch_1):page191_i59:pt11a" )
			)
			( pin "U8D7.B6"
				( objectStatus "@baseboard_fab2_lib.baseboard_fab2(sch_1):page191_i59:pt11b" )
			)
			( pin "U8D7.A3"
				( objectStatus "@baseboard_fab2_lib.baseboard_fab2(sch_1):page191_i59:pt11c" )
			)
			( pin "U8D7.B4"
				( objectStatus "@baseboard_fab2_lib.baseboard_fab2(sch_1):page191_i59:pt11d" )
			)
			( pin "U8D7.D6"
				( objectStatus "@baseboard_fab2_lib.baseboard_fab2(sch_1):page191_i59:pt12a" )
			)
			( pin "U8D7.E7"
				( objectStatus "@baseboard_fab2_lib.baseboard_fab2(sch_1):page191_i59:pt12b" )
			)
			( pin "U8D7.C6"
				( objectStatus "@baseboard_fab2_lib.baseboard_fab2(sch_1):page191_i59:pt12c_tdo" )
			)
			( pin "U8D7.A6"
				( objectStatus "@baseboard_fab2_lib.baseboard_fab2(sch_1):page191_i59:pt12d_tdi" )
			)
			( pin "U8D7.B7"
				( objectStatus "@baseboard_fab2_lib.baseboard_fab2(sch_1):page191_i59:pt13a" )
			)
			( pin "U8D7.C7"
				( objectStatus "@baseboard_fab2_lib.baseboard_fab2(sch_1):page191_i59:pt13b" )
			)
			( pin "U8D7.E6"
				( objectStatus "@baseboard_fab2_lib.baseboard_fab2(sch_1):page191_i59:pt13c" )
			)
			( pin "U8D7.D7"
				( objectStatus "@baseboard_fab2_lib.baseboard_fab2(sch_1):page191_i59:pt13d" )
			)
			( pin "U8D7.F7"
				( objectStatus "@baseboard_fab2_lib.baseboard_fab2(sch_1):page191_i59:pt16a" )
			)
			( pin "U8D7.E8"
				( objectStatus "@baseboard_fab2_lib.baseboard_fab2(sch_1):page191_i59:pt16b" )
			)
			( pin "U8D7.A7"
				( objectStatus "@baseboard_fab2_lib.baseboard_fab2(sch_1):page191_i59:pt16c_tck" )
			)
			( pin "U8D7.B8"
				( objectStatus "@baseboard_fab2_lib.baseboard_fab2(sch_1):page191_i59:pt16d_tms" )
			)
			( pin "U8D7.C8"
				( objectStatus "@baseboard_fab2_lib.baseboard_fab2(sch_1):page191_i59:pt17a_pclkt0_1" )
			)
			( pin "U8D7.A8"
				( objectStatus "@baseboard_fab2_lib.baseboard_fab2(sch_1):page191_i59:pt17b_pclkc0_1" )
			)
			( pin "U8D7.D8"
				( objectStatus "@baseboard_fab2_lib.baseboard_fab2(sch_1):page191_i59:pt17c" )
			)
			( pin "U8D7.E9"
				( objectStatus "@baseboard_fab2_lib.baseboard_fab2(sch_1):page191_i59:pt17d" )
			)
			( pin "U8D7.F8"
				( objectStatus "@baseboard_fab2_lib.baseboard_fab2(sch_1):page191_i59:pt18a" )
			)
			( pin "U8D7.D9"
				( objectStatus "@baseboard_fab2_lib.baseboard_fab2(sch_1):page191_i59:pt18b" )
			)
			( pin "U8D7.A9"
				( objectStatus "@baseboard_fab2_lib.baseboard_fab2(sch_1):page191_i59:pt18c_scl_pclkt0_0" )
			)
			( pin "U8D7.C9"
				( objectStatus "@baseboard_fab2_lib.baseboard_fab2(sch_1):page191_i59:pt18d_sda_pclkc0_0" )
			)
			( pin "U8D7.B9"
				( objectStatus "@baseboard_fab2_lib.baseboard_fab2(sch_1):page191_i59:pt19a" )
			)
			( pin "U8D7.A10"
				( objectStatus "@baseboard_fab2_lib.baseboard_fab2(sch_1):page191_i59:pt19b" )
			)
			( pin "U8D7.F9"
				( objectStatus "@baseboard_fab2_lib.baseboard_fab2(sch_1):page191_i59:pt19c" )
			)
			( pin "U8D7.E11"
				( objectStatus "@baseboard_fab2_lib.baseboard_fab2(sch_1):page191_i59:pt19d" )
			)
			( pin "U8D7.D10"
				( objectStatus "@baseboard_fab2_lib.baseboard_fab2(sch_1):page191_i59:pt20a" )
			)
			( pin "U8D7.E10"
				( objectStatus "@baseboard_fab2_lib.baseboard_fab2(sch_1):page191_i59:pt20b" )
			)
			( pin "U8D7.C10"
				( objectStatus "@baseboard_fab2_lib.baseboard_fab2(sch_1):page191_i59:pt20c_jtagenb" )
			)
			( pin "U8D7.B10"
				( objectStatus "@baseboard_fab2_lib.baseboard_fab2(sch_1):page191_i59:pt20d_programn" )
			)
			( pin "U8D7.A11"
				( objectStatus "@baseboard_fab2_lib.baseboard_fab2(sch_1):page191_i59:pt21a" )
			)
			( pin "U8D7.C11"
				( objectStatus "@baseboard_fab2_lib.baseboard_fab2(sch_1):page191_i59:pt21b" )
			)
			( pin "U8D7.F10"
				( objectStatus "@baseboard_fab2_lib.baseboard_fab2(sch_1):page191_i59:pt21c" )
			)
			( pin "U8D7.D11"
				( objectStatus "@baseboard_fab2_lib.baseboard_fab2(sch_1):page191_i59:pt21d" )
			)
			( pin "U8D7.B11"
				( objectStatus "@baseboard_fab2_lib.baseboard_fab2(sch_1):page191_i59:pt22a" )
			)
			( pin "U8D7.A12"
				( objectStatus "@baseboard_fab2_lib.baseboard_fab2(sch_1):page191_i59:pt22b" )
			)
			( pin "U8D7.B13"
				( objectStatus "@baseboard_fab2_lib.baseboard_fab2(sch_1):page191_i59:pt22c" )
			)
			( pin "U8D7.A14"
				( objectStatus "@baseboard_fab2_lib.baseboard_fab2(sch_1):page191_i59:pt22d" )
			)
			( pin "U8D7.C12"
				( objectStatus "@baseboard_fab2_lib.baseboard_fab2(sch_1):page191_i59:pt23a" )
			)
			( pin "U8D7.B12"
				( objectStatus "@baseboard_fab2_lib.baseboard_fab2(sch_1):page191_i59:pt23b" )
			)
			( pin "U8D7.B14"
				( objectStatus "@baseboard_fab2_lib.baseboard_fab2(sch_1):page191_i59:pt24a" )
			)
			( pin "U8D7.A15"
				( objectStatus "@baseboard_fab2_lib.baseboard_fab2(sch_1):page191_i59:pt24b" )
			)
			( pin "U8D7.A13"
				( objectStatus "@baseboard_fab2_lib.baseboard_fab2(sch_1):page191_i59:pt24c_initn" )
			)
			( pin "U8D7.C13"
				( objectStatus "@baseboard_fab2_lib.baseboard_fab2(sch_1):page191_i59:pt24d_done" )
			)
			( pin "R2R6.1"
				( objectStatus "@baseboard_fab2_lib.baseboard_fab2(sch_1):page191_i166:a" )
			)
			( pin "R2R6.2"
				( objectStatus "@baseboard_fab2_lib.baseboard_fab2(sch_1):page191_i166:b" )
			)
			( pin "R2R7.1"
				( objectStatus "@baseboard_fab2_lib.baseboard_fab2(sch_1):page191_i172:a" )
			)
			( pin "R2R7.2"
				( objectStatus "@baseboard_fab2_lib.baseboard_fab2(sch_1):page191_i172:b" )
			)
			( pin "R2R4.1"
				( objectStatus "@baseboard_fab2_lib.baseboard_fab2(sch_1):page191_i184:a" )
			)
			( pin "R2R4.2"
				( objectStatus "@baseboard_fab2_lib.baseboard_fab2(sch_1):page191_i184:b" )
			)
			( pin "R7D42.1"
				( objectStatus "@baseboard_fab2_lib.baseboard_fab2(sch_1):page191_i193:a" )
			)
			( pin "R7D42.2"
				( objectStatus "@baseboard_fab2_lib.baseboard_fab2(sch_1):page191_i193:b" )
			)
			( pin "C2P8.1"
				( objectStatus "@baseboard_fab2_lib.baseboard_fab2(sch_1):page192_i1:a" )
			)
			( pin "C2P8.2"
				( objectStatus "@baseboard_fab2_lib.baseboard_fab2(sch_1):page192_i1:b" )
			)
			( pin "C2P5.1"
				( objectStatus "@baseboard_fab2_lib.baseboard_fab2(sch_1):page192_i3:a" )
			)
			( pin "C2P5.2"
				( objectStatus "@baseboard_fab2_lib.baseboard_fab2(sch_1):page192_i3:b" )
			)
			( pin "C3R1.1"
				( objectStatus "@baseboard_fab2_lib.baseboard_fab2(sch_1):page192_i4:a" )
			)
			( pin "C3R1.2"
				( objectStatus "@baseboard_fab2_lib.baseboard_fab2(sch_1):page192_i4:b" )
			)
			( pin "C3P43.1"
				( objectStatus "@baseboard_fab2_lib.baseboard_fab2(sch_1):page192_i6:a" )
			)
			( pin "C3P43.2"
				( objectStatus "@baseboard_fab2_lib.baseboard_fab2(sch_1):page192_i6:b" )
			)
			( pin "C3R3.1"
				( objectStatus "@baseboard_fab2_lib.baseboard_fab2(sch_1):page192_i7:a" )
			)
			( pin "C3R3.2"
				( objectStatus "@baseboard_fab2_lib.baseboard_fab2(sch_1):page192_i7:b" )
			)
			( pin "C2R1.1"
				( objectStatus "@baseboard_fab2_lib.baseboard_fab2(sch_1):page192_i8:a" )
			)
			( pin "C2R1.2"
				( objectStatus "@baseboard_fab2_lib.baseboard_fab2(sch_1):page192_i8:b" )
			)
			( pin "C2P2.1"
				( objectStatus "@baseboard_fab2_lib.baseboard_fab2(sch_1):page192_i9:a" )
			)
			( pin "C2P2.2"
				( objectStatus "@baseboard_fab2_lib.baseboard_fab2(sch_1):page192_i9:b" )
			)
			( pin "C3R2.1"
				( objectStatus "@baseboard_fab2_lib.baseboard_fab2(sch_1):page192_i10:a" )
			)
			( pin "C3R2.2"
				( objectStatus "@baseboard_fab2_lib.baseboard_fab2(sch_1):page192_i10:b" )
			)
			( pin "C3P51.1"
				( objectStatus "@baseboard_fab2_lib.baseboard_fab2(sch_1):page192_i11:a" )
			)
			( pin "C3P51.2"
				( objectStatus "@baseboard_fab2_lib.baseboard_fab2(sch_1):page192_i11:b" )
			)
			( pin "C3P47.1"
				( objectStatus "@baseboard_fab2_lib.baseboard_fab2(sch_1):page192_i12:a" )
			)
			( pin "C3P47.2"
				( objectStatus "@baseboard_fab2_lib.baseboard_fab2(sch_1):page192_i12:b" )
			)
			( pin "U8D7.B2"
				( objectStatus "@baseboard_fab2_lib.baseboard_fab2(sch_1):page192_i14:gnd(0)" )
			)
			( pin "U8D7.B15"
				( objectStatus "@baseboard_fab2_lib.baseboard_fab2(sch_1):page192_i14:gnd(1)" )
			)
			( pin "U8D7.C3"
				( objectStatus "@baseboard_fab2_lib.baseboard_fab2(sch_1):page192_i14:gnd(2)" )
			)
			( pin "U8D7.C14"
				( objectStatus "@baseboard_fab2_lib.baseboard_fab2(sch_1):page192_i14:gnd(3)" )
			)
			( pin "U8D7.D4"
				( objectStatus "@baseboard_fab2_lib.baseboard_fab2(sch_1):page192_i14:gnd(4)" )
			)
			( pin "U8D7.D13"
				( objectStatus "@baseboard_fab2_lib.baseboard_fab2(sch_1):page192_i14:gnd(5)" )
			)
			( pin "U8D7.E5"
				( objectStatus "@baseboard_fab2_lib.baseboard_fab2(sch_1):page192_i14:gnd(6)" )
			)
			( pin "U8D7.E12"
				( objectStatus "@baseboard_fab2_lib.baseboard_fab2(sch_1):page192_i14:gnd(7)" )
			)
			( pin "U8D7.F6"
				( objectStatus "@baseboard_fab2_lib.baseboard_fab2(sch_1):page192_i14:gnd(8)" )
			)
			( pin "U8D7.F11"
				( objectStatus "@baseboard_fab2_lib.baseboard_fab2(sch_1):page192_i14:gnd(9)" )
			)
			( pin "U8D7.H8"
				( objectStatus "@baseboard_fab2_lib.baseboard_fab2(sch_1):page192_i14:gnd(10)" )
			)
			( pin "U8D7.H9"
				( objectStatus "@baseboard_fab2_lib.baseboard_fab2(sch_1):page192_i14:gnd(11)" )
			)
			( pin "U8D7.J8"
				( objectStatus "@baseboard_fab2_lib.baseboard_fab2(sch_1):page192_i14:gnd(12)" )
			)
			( pin "U8D7.J9"
				( objectStatus "@baseboard_fab2_lib.baseboard_fab2(sch_1):page192_i14:gnd(13)" )
			)
			( pin "U8D7.L6"
				( objectStatus "@baseboard_fab2_lib.baseboard_fab2(sch_1):page192_i14:gnd(14)" )
			)
			( pin "U8D7.L11"
				( objectStatus "@baseboard_fab2_lib.baseboard_fab2(sch_1):page192_i14:gnd(15)" )
			)
			( pin "U8D7.M5"
				( objectStatus "@baseboard_fab2_lib.baseboard_fab2(sch_1):page192_i14:gnd(16)" )
			)
			( pin "U8D7.M12"
				( objectStatus "@baseboard_fab2_lib.baseboard_fab2(sch_1):page192_i14:gnd(17)" )
			)
			( pin "U8D7.N4"
				( objectStatus "@baseboard_fab2_lib.baseboard_fab2(sch_1):page192_i14:gnd(18)" )
			)
			( pin "U8D7.N13"
				( objectStatus "@baseboard_fab2_lib.baseboard_fab2(sch_1):page192_i14:gnd(19)" )
			)
			( pin "U8D7.P3"
				( objectStatus "@baseboard_fab2_lib.baseboard_fab2(sch_1):page192_i14:gnd(20)" )
			)
			( pin "U8D7.P14"
				( objectStatus "@baseboard_fab2_lib.baseboard_fab2(sch_1):page192_i14:gnd(21)" )
			)
			( pin "U8D7.R2"
				( objectStatus "@baseboard_fab2_lib.baseboard_fab2(sch_1):page192_i14:gnd(22)" )
			)
			( pin "U8D7.R15"
				( objectStatus "@baseboard_fab2_lib.baseboard_fab2(sch_1):page192_i14:gnd(23)" )
			)
			( pin "U8D7.A2"
				( objectStatus "@baseboard_fab2_lib.baseboard_fab2(sch_1):page192_i14:nc(0)" )
			)
			( pin "U8D7.A1"
				( objectStatus "@baseboard_fab2_lib.baseboard_fab2(sch_1):page192_i14:vcc(0)" )
			)
			( pin "U8D7.A16"
				( objectStatus "@baseboard_fab2_lib.baseboard_fab2(sch_1):page192_i14:vcc(1)" )
			)
			( pin "U8D7.T1"
				( objectStatus "@baseboard_fab2_lib.baseboard_fab2(sch_1):page192_i14:vcc(2)" )
			)
			( pin "U8D7.T16"
				( objectStatus "@baseboard_fab2_lib.baseboard_fab2(sch_1):page192_i14:vcc(3)" )
			)
			( pin "U8D7.G7"
				( objectStatus "@baseboard_fab2_lib.baseboard_fab2(sch_1):page192_i14:vcc(4)" )
			)
			( pin "U8D7.G10"
				( objectStatus "@baseboard_fab2_lib.baseboard_fab2(sch_1):page192_i14:vcc(5)" )
			)
			( pin "U8D7.K7"
				( objectStatus "@baseboard_fab2_lib.baseboard_fab2(sch_1):page192_i14:vcc(6)" )
			)
			( pin "U8D7.K10"
				( objectStatus "@baseboard_fab2_lib.baseboard_fab2(sch_1):page192_i14:vcc(7)" )
			)
			( pin "U8D7.G8"
				( objectStatus "@baseboard_fab2_lib.baseboard_fab2(sch_1):page192_i14:vccio0(0)" )
			)
			( pin "U8D7.D12"
				( objectStatus "@baseboard_fab2_lib.baseboard_fab2(sch_1):page192_i14:vccio0(1)" )
			)
			( pin "U8D7.G9"
				( objectStatus "@baseboard_fab2_lib.baseboard_fab2(sch_1):page192_i14:vccio0(2)" )
			)
			( pin "U8D7.D5"
				( objectStatus "@baseboard_fab2_lib.baseboard_fab2(sch_1):page192_i14:vccio0(3)" )
			)
			( pin "U8D7.E13"
				( objectStatus "@baseboard_fab2_lib.baseboard_fab2(sch_1):page192_i14:vccio1(0)" )
			)
			( pin "U8D7.H10"
				( objectStatus "@baseboard_fab2_lib.baseboard_fab2(sch_1):page192_i14:vccio1(1)" )
			)
			( pin "U8D7.J10"
				( objectStatus "@baseboard_fab2_lib.baseboard_fab2(sch_1):page192_i14:vccio1(2)" )
			)
			( pin "U8D7.M13"
				( objectStatus "@baseboard_fab2_lib.baseboard_fab2(sch_1):page192_i14:vccio1(3)" )
			)
			( pin "U8D7.K9"
				( objectStatus "@baseboard_fab2_lib.baseboard_fab2(sch_1):page192_i14:vccio2(0)" )
			)
			( pin "U8D7.N12"
				( objectStatus "@baseboard_fab2_lib.baseboard_fab2(sch_1):page192_i14:vccio2(1)" )
			)
			( pin "U8D7.K8"
				( objectStatus "@baseboard_fab2_lib.baseboard_fab2(sch_1):page192_i14:vccio2(2)" )
			)
			( pin "U8D7.N5"
				( objectStatus "@baseboard_fab2_lib.baseboard_fab2(sch_1):page192_i14:vccio2(3)" )
			)
			( pin "U8D7.M4"
				( objectStatus "@baseboard_fab2_lib.baseboard_fab2(sch_1):page192_i14:vccio3(0)" )
			)
			( pin "U8D7.J7"
				( objectStatus "@baseboard_fab2_lib.baseboard_fab2(sch_1):page192_i14:vccio4(0)" )
			)
			( pin "U8D7.H7"
				( objectStatus "@baseboard_fab2_lib.baseboard_fab2(sch_1):page192_i14:vccio4(1)" )
			)
			( pin "U8D7.E4"
				( objectStatus "@baseboard_fab2_lib.baseboard_fab2(sch_1):page192_i14:vccio5(0)" )
			)
			( pin "C2R5.1"
				( objectStatus "@baseboard_fab2_lib.baseboard_fab2(sch_1):page192_i15:a" )
			)
			( pin "C2R5.2"
				( objectStatus "@baseboard_fab2_lib.baseboard_fab2(sch_1):page192_i15:b" )
			)
			( pin "C2P4.1"
				( objectStatus "@baseboard_fab2_lib.baseboard_fab2(sch_1):page192_i16:a" )
			)
			( pin "C2P4.2"
				( objectStatus "@baseboard_fab2_lib.baseboard_fab2(sch_1):page192_i16:b" )
			)
			( pin "C3P52.1"
				( objectStatus "@baseboard_fab2_lib.baseboard_fab2(sch_1):page192_i17:a" )
			)
			( pin "C3P52.2"
				( objectStatus "@baseboard_fab2_lib.baseboard_fab2(sch_1):page192_i17:b" )
			)
			( pin "C2P6.1"
				( objectStatus "@baseboard_fab2_lib.baseboard_fab2(sch_1):page192_i18:a" )
			)
			( pin "C2P6.2"
				( objectStatus "@baseboard_fab2_lib.baseboard_fab2(sch_1):page192_i18:b" )
			)
			( pin "C2R3.1"
				( objectStatus "@baseboard_fab2_lib.baseboard_fab2(sch_1):page192_i19:a" )
			)
			( pin "C2R3.2"
				( objectStatus "@baseboard_fab2_lib.baseboard_fab2(sch_1):page192_i19:b" )
			)
			( pin "C2P7.1"
				( objectStatus "@baseboard_fab2_lib.baseboard_fab2(sch_1):page192_i20:a" )
			)
			( pin "C2P7.2"
				( objectStatus "@baseboard_fab2_lib.baseboard_fab2(sch_1):page192_i20:b" )
			)
			( pin "C2R4.1"
				( objectStatus "@baseboard_fab2_lib.baseboard_fab2(sch_1):page192_i21:a" )
			)
			( pin "C2R4.2"
				( objectStatus "@baseboard_fab2_lib.baseboard_fab2(sch_1):page192_i21:b" )
			)
			( pin "C2P3.1"
				( objectStatus "@baseboard_fab2_lib.baseboard_fab2(sch_1):page192_i22:a" )
			)
			( pin "C2P3.2"
				( objectStatus "@baseboard_fab2_lib.baseboard_fab2(sch_1):page192_i22:b" )
			)
			( pin "C3P44.1"
				( objectStatus "@baseboard_fab2_lib.baseboard_fab2(sch_1):page192_i23:a" )
			)
			( pin "C3P44.2"
				( objectStatus "@baseboard_fab2_lib.baseboard_fab2(sch_1):page192_i23:b" )
			)
			( pin "C3P48.1"
				( objectStatus "@baseboard_fab2_lib.baseboard_fab2(sch_1):page192_i25:a" )
			)
			( pin "C3P48.2"
				( objectStatus "@baseboard_fab2_lib.baseboard_fab2(sch_1):page192_i25:b" )
			)
			( pin "C2R2.1"
				( objectStatus "@baseboard_fab2_lib.baseboard_fab2(sch_1):page192_i28:a" )
			)
			( pin "C2R2.2"
				( objectStatus "@baseboard_fab2_lib.baseboard_fab2(sch_1):page192_i28:b" )
			)
			( pin "R7E6.1"
				( objectStatus "@baseboard_fab2_lib.baseboard_fab2(sch_1):page192_i33:a" )
			)
			( pin "R7E6.2"
				( objectStatus "@baseboard_fab2_lib.baseboard_fab2(sch_1):page192_i33:b" )
			)
			( pin "R2R1.1"
				( objectStatus "@baseboard_fab2_lib.baseboard_fab2(sch_1):page192_i34:a" )
			)
			( pin "R2R1.2"
				( objectStatus "@baseboard_fab2_lib.baseboard_fab2(sch_1):page192_i34:b" )
			)
			( pin "R7E5.1"
				( objectStatus "@baseboard_fab2_lib.baseboard_fab2(sch_1):page192_i38:a" )
			)
			( pin "R7E5.2"
				( objectStatus "@baseboard_fab2_lib.baseboard_fab2(sch_1):page192_i38:b" )
			)
			( pin "R2R3.1"
				( objectStatus "@baseboard_fab2_lib.baseboard_fab2(sch_1):page192_i41:a" )
			)
			( pin "R2R3.2"
				( objectStatus "@baseboard_fab2_lib.baseboard_fab2(sch_1):page192_i41:b" )
			)
			( pin "R3R16.1"
				( objectStatus "@baseboard_fab2_lib.baseboard_fab2(sch_1):page192_i48:a" )
			)
			( pin "R3R16.2"
				( objectStatus "@baseboard_fab2_lib.baseboard_fab2(sch_1):page192_i48:b" )
			)
			( pin "R6M9.1"
				( objectStatus "@baseboard_fab2_lib.baseboard_fab2(sch_1):page192_i49:a" )
			)
			( pin "R6M9.2"
				( objectStatus "@baseboard_fab2_lib.baseboard_fab2(sch_1):page192_i49:b" )
			)
			( pin "R7E18.1"
				( objectStatus "@baseboard_fab2_lib.baseboard_fab2(sch_1):page192_i55:a" )
			)
			( pin "R7E18.2"
				( objectStatus "@baseboard_fab2_lib.baseboard_fab2(sch_1):page192_i55:b" )
			)
			( pin "R7E19.1"
				( objectStatus "@baseboard_fab2_lib.baseboard_fab2(sch_1):page192_i57:a" )
			)
			( pin "R7E19.2"
				( objectStatus "@baseboard_fab2_lib.baseboard_fab2(sch_1):page192_i57:b" )
			)
			( pin "R7E20.1"
				( objectStatus "@baseboard_fab2_lib.baseboard_fab2(sch_1):page192_i59:a" )
			)
			( pin "R7E20.2"
				( objectStatus "@baseboard_fab2_lib.baseboard_fab2(sch_1):page192_i59:b" )
			)
			( pin "C4C1.1"
				( objectStatus "@baseboard_fab2_lib.baseboard_fab2(sch_1):page193_i29:a" )
			)
			( pin "C4C1.2"
				( objectStatus "@baseboard_fab2_lib.baseboard_fab2(sch_1):page193_i29:b" )
			)
			( pin "C3C2.1"
				( objectStatus "@baseboard_fab2_lib.baseboard_fab2(sch_1):page193_i31:a" )
			)
			( pin "C3C2.2"
				( objectStatus "@baseboard_fab2_lib.baseboard_fab2(sch_1):page193_i31:b" )
			)
			( pin "C3C1.1"
				( objectStatus "@baseboard_fab2_lib.baseboard_fab2(sch_1):page193_i38:a" )
			)
			( pin "C3C1.2"
				( objectStatus "@baseboard_fab2_lib.baseboard_fab2(sch_1):page193_i38:b" )
			)
			( pin "J4E1.A1"
				( objectStatus "@baseboard_fab2_lib.baseboard_fab2(sch_1):page193_i45:ioa1" )
			)
			( pin "J4E1.A2"
				( objectStatus "@baseboard_fab2_lib.baseboard_fab2(sch_1):page193_i45:ioa2" )
			)
			( pin "J4E1.A3"
				( objectStatus "@baseboard_fab2_lib.baseboard_fab2(sch_1):page193_i45:ioa3" )
			)
			( pin "J4E1.A4"
				( objectStatus "@baseboard_fab2_lib.baseboard_fab2(sch_1):page193_i45:ioa4" )
			)
			( pin "J4E1.A5"
				( objectStatus "@baseboard_fab2_lib.baseboard_fab2(sch_1):page193_i45:ioa5" )
			)
			( pin "J4E1.A6"
				( objectStatus "@baseboard_fab2_lib.baseboard_fab2(sch_1):page193_i45:ioa6" )
			)
			( pin "J4E1.A7"
				( objectStatus "@baseboard_fab2_lib.baseboard_fab2(sch_1):page193_i45:ioa7" )
			)
			( pin "J4E1.A8"
				( objectStatus "@baseboard_fab2_lib.baseboard_fab2(sch_1):page193_i45:ioa8" )
			)
			( pin "J4E1.A9"
				( objectStatus "@baseboard_fab2_lib.baseboard_fab2(sch_1):page193_i45:ioa9" )
			)
			( pin "J4E1.A10"
				( objectStatus "@baseboard_fab2_lib.baseboard_fab2(sch_1):page193_i45:ioa10" )
			)
			( pin "J4E1.A11"
				( objectStatus "@baseboard_fab2_lib.baseboard_fab2(sch_1):page193_i45:ioa11" )
			)
			( pin "J4E1.A12"
				( objectStatus "@baseboard_fab2_lib.baseboard_fab2(sch_1):page193_i45:ioa12" )
			)
			( pin "J4E1.A13"
				( objectStatus "@baseboard_fab2_lib.baseboard_fab2(sch_1):page193_i45:ioa13" )
			)
			( pin "J4E1.A14"
				( objectStatus "@baseboard_fab2_lib.baseboard_fab2(sch_1):page193_i45:ioa14" )
			)
			( pin "J4E1.A15"
				( objectStatus "@baseboard_fab2_lib.baseboard_fab2(sch_1):page193_i45:ioa15" )
			)
			( pin "J4E1.A16"
				( objectStatus "@baseboard_fab2_lib.baseboard_fab2(sch_1):page193_i45:ioa16" )
			)
			( pin "J4E1.A17"
				( objectStatus "@baseboard_fab2_lib.baseboard_fab2(sch_1):page193_i45:ioa17" )
			)
			( pin "J4E1.A18"
				( objectStatus "@baseboard_fab2_lib.baseboard_fab2(sch_1):page193_i45:ioa18" )
			)
			( pin "J4E1.A19"
				( objectStatus "@baseboard_fab2_lib.baseboard_fab2(sch_1):page193_i45:ioa19" )
			)
			( pin "J4E1.A20"
				( objectStatus "@baseboard_fab2_lib.baseboard_fab2(sch_1):page193_i45:ioa20" )
			)
			( pin "J4E1.B1"
				( objectStatus "@baseboard_fab2_lib.baseboard_fab2(sch_1):page193_i45:iob1" )
			)
			( pin "J4E1.B2"
				( objectStatus "@baseboard_fab2_lib.baseboard_fab2(sch_1):page193_i45:iob2" )
			)
			( pin "J4E1.B3"
				( objectStatus "@baseboard_fab2_lib.baseboard_fab2(sch_1):page193_i45:iob3" )
			)
			( pin "J4E1.B4"
				( objectStatus "@baseboard_fab2_lib.baseboard_fab2(sch_1):page193_i45:iob4" )
			)
			( pin "J4E1.B5"
				( objectStatus "@baseboard_fab2_lib.baseboard_fab2(sch_1):page193_i45:iob5" )
			)
			( pin "J4E1.B6"
				( objectStatus "@baseboard_fab2_lib.baseboard_fab2(sch_1):page193_i45:iob6" )
			)
			( pin "J4E1.B7"
				( objectStatus "@baseboard_fab2_lib.baseboard_fab2(sch_1):page193_i45:iob7" )
			)
			( pin "J4E1.B8"
				( objectStatus "@baseboard_fab2_lib.baseboard_fab2(sch_1):page193_i45:iob8" )
			)
			( pin "J4E1.B9"
				( objectStatus "@baseboard_fab2_lib.baseboard_fab2(sch_1):page193_i45:iob9" )
			)
			( pin "J4E1.B10"
				( objectStatus "@baseboard_fab2_lib.baseboard_fab2(sch_1):page193_i45:iob10" )
			)
			( pin "J4E1.B11"
				( objectStatus "@baseboard_fab2_lib.baseboard_fab2(sch_1):page193_i45:iob11" )
			)
			( pin "J4E1.B12"
				( objectStatus "@baseboard_fab2_lib.baseboard_fab2(sch_1):page193_i45:iob12" )
			)
			( pin "J4E1.B13"
				( objectStatus "@baseboard_fab2_lib.baseboard_fab2(sch_1):page193_i45:iob13" )
			)
			( pin "J4E1.B14"
				( objectStatus "@baseboard_fab2_lib.baseboard_fab2(sch_1):page193_i45:iob14" )
			)
			( pin "J4E1.B15"
				( objectStatus "@baseboard_fab2_lib.baseboard_fab2(sch_1):page193_i45:iob15" )
			)
			( pin "J4E1.B16"
				( objectStatus "@baseboard_fab2_lib.baseboard_fab2(sch_1):page193_i45:iob16" )
			)
			( pin "J4E1.B17"
				( objectStatus "@baseboard_fab2_lib.baseboard_fab2(sch_1):page193_i45:iob17" )
			)
			( pin "J4E1.B18"
				( objectStatus "@baseboard_fab2_lib.baseboard_fab2(sch_1):page193_i45:iob18" )
			)
			( pin "J4E1.B19"
				( objectStatus "@baseboard_fab2_lib.baseboard_fab2(sch_1):page193_i45:iob19" )
			)
			( pin "J4E1.B20"
				( objectStatus "@baseboard_fab2_lib.baseboard_fab2(sch_1):page193_i45:iob20" )
			)
			( pin "J4E1.C1"
				( objectStatus "@baseboard_fab2_lib.baseboard_fab2(sch_1):page193_i45:ioc1" )
			)
			( pin "J4E1.C2"
				( objectStatus "@baseboard_fab2_lib.baseboard_fab2(sch_1):page193_i45:ioc2" )
			)
			( pin "J4E1.C3"
				( objectStatus "@baseboard_fab2_lib.baseboard_fab2(sch_1):page193_i45:ioc3" )
			)
			( pin "J4E1.C4"
				( objectStatus "@baseboard_fab2_lib.baseboard_fab2(sch_1):page193_i45:ioc4" )
			)
			( pin "J4E1.C5"
				( objectStatus "@baseboard_fab2_lib.baseboard_fab2(sch_1):page193_i45:ioc5" )
			)
			( pin "J4E1.C6"
				( objectStatus "@baseboard_fab2_lib.baseboard_fab2(sch_1):page193_i45:ioc6" )
			)
			( pin "J4E1.C7"
				( objectStatus "@baseboard_fab2_lib.baseboard_fab2(sch_1):page193_i45:ioc7" )
			)
			( pin "J4E1.C8"
				( objectStatus "@baseboard_fab2_lib.baseboard_fab2(sch_1):page193_i45:ioc8" )
			)
			( pin "J4E1.C9"
				( objectStatus "@baseboard_fab2_lib.baseboard_fab2(sch_1):page193_i45:ioc9" )
			)
			( pin "J4E1.C10"
				( objectStatus "@baseboard_fab2_lib.baseboard_fab2(sch_1):page193_i45:ioc10" )
			)
			( pin "J4E1.C11"
				( objectStatus "@baseboard_fab2_lib.baseboard_fab2(sch_1):page193_i45:ioc11" )
			)
			( pin "J4E1.C12"
				( objectStatus "@baseboard_fab2_lib.baseboard_fab2(sch_1):page193_i45:ioc12" )
			)
			( pin "J4E1.C13"
				( objectStatus "@baseboard_fab2_lib.baseboard_fab2(sch_1):page193_i45:ioc13" )
			)
			( pin "J4E1.C14"
				( objectStatus "@baseboard_fab2_lib.baseboard_fab2(sch_1):page193_i45:ioc14" )
			)
			( pin "J4E1.C15"
				( objectStatus "@baseboard_fab2_lib.baseboard_fab2(sch_1):page193_i45:ioc15" )
			)
			( pin "J4E1.C16"
				( objectStatus "@baseboard_fab2_lib.baseboard_fab2(sch_1):page193_i45:ioc16" )
			)
			( pin "J4E1.C17"
				( objectStatus "@baseboard_fab2_lib.baseboard_fab2(sch_1):page193_i45:ioc17" )
			)
			( pin "J4E1.C18"
				( objectStatus "@baseboard_fab2_lib.baseboard_fab2(sch_1):page193_i45:ioc18" )
			)
			( pin "J4E1.C19"
				( objectStatus "@baseboard_fab2_lib.baseboard_fab2(sch_1):page193_i45:ioc19" )
			)
			( pin "J4E1.C20"
				( objectStatus "@baseboard_fab2_lib.baseboard_fab2(sch_1):page193_i45:ioc20" )
			)
			( pin "J4E1.D1"
				( objectStatus "@baseboard_fab2_lib.baseboard_fab2(sch_1):page193_i45:iod1" )
			)
			( pin "J4E1.D2"
				( objectStatus "@baseboard_fab2_lib.baseboard_fab2(sch_1):page193_i45:iod2" )
			)
			( pin "J4E1.D3"
				( objectStatus "@baseboard_fab2_lib.baseboard_fab2(sch_1):page193_i45:iod3" )
			)
			( pin "J4E1.D4"
				( objectStatus "@baseboard_fab2_lib.baseboard_fab2(sch_1):page193_i45:iod4" )
			)
			( pin "J4E1.D5"
				( objectStatus "@baseboard_fab2_lib.baseboard_fab2(sch_1):page193_i45:iod5" )
			)
			( pin "J4E1.D6"
				( objectStatus "@baseboard_fab2_lib.baseboard_fab2(sch_1):page193_i45:iod6" )
			)
			( pin "J4E1.D7"
				( objectStatus "@baseboard_fab2_lib.baseboard_fab2(sch_1):page193_i45:iod7" )
			)
			( pin "J4E1.D8"
				( objectStatus "@baseboard_fab2_lib.baseboard_fab2(sch_1):page193_i45:iod8" )
			)
			( pin "J4E1.D9"
				( objectStatus "@baseboard_fab2_lib.baseboard_fab2(sch_1):page193_i45:iod9" )
			)
			( pin "J4E1.D10"
				( objectStatus "@baseboard_fab2_lib.baseboard_fab2(sch_1):page193_i45:iod10" )
			)
			( pin "J4E1.D11"
				( objectStatus "@baseboard_fab2_lib.baseboard_fab2(sch_1):page193_i45:iod11" )
			)
			( pin "J4E1.D12"
				( objectStatus "@baseboard_fab2_lib.baseboard_fab2(sch_1):page193_i45:iod12" )
			)
			( pin "J4E1.D13"
				( objectStatus "@baseboard_fab2_lib.baseboard_fab2(sch_1):page193_i45:iod13" )
			)
			( pin "J4E1.D14"
				( objectStatus "@baseboard_fab2_lib.baseboard_fab2(sch_1):page193_i45:iod14" )
			)
			( pin "J4E1.D15"
				( objectStatus "@baseboard_fab2_lib.baseboard_fab2(sch_1):page193_i45:iod15" )
			)
			( pin "J4E1.D16"
				( objectStatus "@baseboard_fab2_lib.baseboard_fab2(sch_1):page193_i45:iod16" )
			)
			( pin "J4E1.D17"
				( objectStatus "@baseboard_fab2_lib.baseboard_fab2(sch_1):page193_i45:iod17" )
			)
			( pin "J4E1.D18"
				( objectStatus "@baseboard_fab2_lib.baseboard_fab2(sch_1):page193_i45:iod18" )
			)
			( pin "J4E1.D19"
				( objectStatus "@baseboard_fab2_lib.baseboard_fab2(sch_1):page193_i45:iod19" )
			)
			( pin "J4E1.D20"
				( objectStatus "@baseboard_fab2_lib.baseboard_fab2(sch_1):page193_i45:iod20" )
			)
			( pin "J4E1.E1"
				( objectStatus "@baseboard_fab2_lib.baseboard_fab2(sch_1):page193_i45:ioe1" )
			)
			( pin "J4E1.E2"
				( objectStatus "@baseboard_fab2_lib.baseboard_fab2(sch_1):page193_i45:ioe2" )
			)
			( pin "J4E1.E3"
				( objectStatus "@baseboard_fab2_lib.baseboard_fab2(sch_1):page193_i45:ioe3" )
			)
			( pin "J4E1.E4"
				( objectStatus "@baseboard_fab2_lib.baseboard_fab2(sch_1):page193_i45:ioe4" )
			)
			( pin "J4E1.E5"
				( objectStatus "@baseboard_fab2_lib.baseboard_fab2(sch_1):page193_i45:ioe5" )
			)
			( pin "J4E1.E6"
				( objectStatus "@baseboard_fab2_lib.baseboard_fab2(sch_1):page193_i45:ioe6" )
			)
			( pin "J4E1.E7"
				( objectStatus "@baseboard_fab2_lib.baseboard_fab2(sch_1):page193_i45:ioe7" )
			)
			( pin "J4E1.E8"
				( objectStatus "@baseboard_fab2_lib.baseboard_fab2(sch_1):page193_i45:ioe8" )
			)
			( pin "J4E1.E9"
				( objectStatus "@baseboard_fab2_lib.baseboard_fab2(sch_1):page193_i45:ioe9" )
			)
			( pin "J4E1.E10"
				( objectStatus "@baseboard_fab2_lib.baseboard_fab2(sch_1):page193_i45:ioe10" )
			)
			( pin "J4E1.E11"
				( objectStatus "@baseboard_fab2_lib.baseboard_fab2(sch_1):page193_i45:ioe11" )
			)
			( pin "J4E1.E12"
				( objectStatus "@baseboard_fab2_lib.baseboard_fab2(sch_1):page193_i45:ioe12" )
			)
			( pin "J4E1.E13"
				( objectStatus "@baseboard_fab2_lib.baseboard_fab2(sch_1):page193_i45:ioe13" )
			)
			( pin "J4E1.E14"
				( objectStatus "@baseboard_fab2_lib.baseboard_fab2(sch_1):page193_i45:ioe14" )
			)
			( pin "J4E1.E15"
				( objectStatus "@baseboard_fab2_lib.baseboard_fab2(sch_1):page193_i45:ioe15" )
			)
			( pin "J4E1.E16"
				( objectStatus "@baseboard_fab2_lib.baseboard_fab2(sch_1):page193_i45:ioe16" )
			)
			( pin "J4E1.E17"
				( objectStatus "@baseboard_fab2_lib.baseboard_fab2(sch_1):page193_i45:ioe17" )
			)
			( pin "J4E1.E18"
				( objectStatus "@baseboard_fab2_lib.baseboard_fab2(sch_1):page193_i45:ioe18" )
			)
			( pin "J4E1.E19"
				( objectStatus "@baseboard_fab2_lib.baseboard_fab2(sch_1):page193_i45:ioe19" )
			)
			( pin "J4E1.E20"
				( objectStatus "@baseboard_fab2_lib.baseboard_fab2(sch_1):page193_i45:ioe20" )
			)
			( pin "J4E1.F1"
				( objectStatus "@baseboard_fab2_lib.baseboard_fab2(sch_1):page193_i45:iof1" )
			)
			( pin "J4E1.F2"
				( objectStatus "@baseboard_fab2_lib.baseboard_fab2(sch_1):page193_i45:iof2" )
			)
			( pin "J4E1.F3"
				( objectStatus "@baseboard_fab2_lib.baseboard_fab2(sch_1):page193_i45:iof3" )
			)
			( pin "J4E1.F4"
				( objectStatus "@baseboard_fab2_lib.baseboard_fab2(sch_1):page193_i45:iof4" )
			)
			( pin "J4E1.F5"
				( objectStatus "@baseboard_fab2_lib.baseboard_fab2(sch_1):page193_i45:iof5" )
			)
			( pin "J4E1.F6"
				( objectStatus "@baseboard_fab2_lib.baseboard_fab2(sch_1):page193_i45:iof6" )
			)
			( pin "J4E1.F7"
				( objectStatus "@baseboard_fab2_lib.baseboard_fab2(sch_1):page193_i45:iof7" )
			)
			( pin "J4E1.F8"
				( objectStatus "@baseboard_fab2_lib.baseboard_fab2(sch_1):page193_i45:iof8" )
			)
			( pin "J4E1.F9"
				( objectStatus "@baseboard_fab2_lib.baseboard_fab2(sch_1):page193_i45:iof9" )
			)
			( pin "J4E1.F10"
				( objectStatus "@baseboard_fab2_lib.baseboard_fab2(sch_1):page193_i45:iof10" )
			)
			( pin "J4E1.F11"
				( objectStatus "@baseboard_fab2_lib.baseboard_fab2(sch_1):page193_i45:iof11" )
			)
			( pin "J4E1.F12"
				( objectStatus "@baseboard_fab2_lib.baseboard_fab2(sch_1):page193_i45:iof12" )
			)
			( pin "J4E1.F13"
				( objectStatus "@baseboard_fab2_lib.baseboard_fab2(sch_1):page193_i45:iof13" )
			)
			( pin "J4E1.F14"
				( objectStatus "@baseboard_fab2_lib.baseboard_fab2(sch_1):page193_i45:iof14" )
			)
			( pin "J4E1.F15"
				( objectStatus "@baseboard_fab2_lib.baseboard_fab2(sch_1):page193_i45:iof15" )
			)
			( pin "J4E1.F16"
				( objectStatus "@baseboard_fab2_lib.baseboard_fab2(sch_1):page193_i45:iof16" )
			)
			( pin "J4E1.F17"
				( objectStatus "@baseboard_fab2_lib.baseboard_fab2(sch_1):page193_i45:iof17" )
			)
			( pin "J4E1.F18"
				( objectStatus "@baseboard_fab2_lib.baseboard_fab2(sch_1):page193_i45:iof18" )
			)
			( pin "J4E1.F19"
				( objectStatus "@baseboard_fab2_lib.baseboard_fab2(sch_1):page193_i45:iof19" )
			)
			( pin "J4E1.F20"
				( objectStatus "@baseboard_fab2_lib.baseboard_fab2(sch_1):page193_i45:iof20" )
			)
			( pin "J4B2.A1"
				( objectStatus "@baseboard_fab2_lib.baseboard_fab2(sch_1):page193_i46:ioa1" )
			)
			( pin "J4B2.A2"
				( objectStatus "@baseboard_fab2_lib.baseboard_fab2(sch_1):page193_i46:ioa2" )
			)
			( pin "J4B2.A3"
				( objectStatus "@baseboard_fab2_lib.baseboard_fab2(sch_1):page193_i46:ioa3" )
			)
			( pin "J4B2.A4"
				( objectStatus "@baseboard_fab2_lib.baseboard_fab2(sch_1):page193_i46:ioa4" )
			)
			( pin "J4B2.A5"
				( objectStatus "@baseboard_fab2_lib.baseboard_fab2(sch_1):page193_i46:ioa5" )
			)
			( pin "J4B2.A6"
				( objectStatus "@baseboard_fab2_lib.baseboard_fab2(sch_1):page193_i46:ioa6" )
			)
			( pin "J4B2.A7"
				( objectStatus "@baseboard_fab2_lib.baseboard_fab2(sch_1):page193_i46:ioa7" )
			)
			( pin "J4B2.A8"
				( objectStatus "@baseboard_fab2_lib.baseboard_fab2(sch_1):page193_i46:ioa8" )
			)
			( pin "J4B2.A9"
				( objectStatus "@baseboard_fab2_lib.baseboard_fab2(sch_1):page193_i46:ioa9" )
			)
			( pin "J4B2.A10"
				( objectStatus "@baseboard_fab2_lib.baseboard_fab2(sch_1):page193_i46:ioa10" )
			)
			( pin "J4B2.A11"
				( objectStatus "@baseboard_fab2_lib.baseboard_fab2(sch_1):page193_i46:ioa11" )
			)
			( pin "J4B2.A12"
				( objectStatus "@baseboard_fab2_lib.baseboard_fab2(sch_1):page193_i46:ioa12" )
			)
			( pin "J4B2.A13"
				( objectStatus "@baseboard_fab2_lib.baseboard_fab2(sch_1):page193_i46:ioa13" )
			)
			( pin "J4B2.A14"
				( objectStatus "@baseboard_fab2_lib.baseboard_fab2(sch_1):page193_i46:ioa14" )
			)
			( pin "J4B2.A15"
				( objectStatus "@baseboard_fab2_lib.baseboard_fab2(sch_1):page193_i46:ioa15" )
			)
			( pin "J4B2.A16"
				( objectStatus "@baseboard_fab2_lib.baseboard_fab2(sch_1):page193_i46:ioa16" )
			)
			( pin "J4B2.A17"
				( objectStatus "@baseboard_fab2_lib.baseboard_fab2(sch_1):page193_i46:ioa17" )
			)
			( pin "J4B2.A18"
				( objectStatus "@baseboard_fab2_lib.baseboard_fab2(sch_1):page193_i46:ioa18" )
			)
			( pin "J4B2.A19"
				( objectStatus "@baseboard_fab2_lib.baseboard_fab2(sch_1):page193_i46:ioa19" )
			)
			( pin "J4B2.A20"
				( objectStatus "@baseboard_fab2_lib.baseboard_fab2(sch_1):page193_i46:ioa20" )
			)
			( pin "J4B2.B1"
				( objectStatus "@baseboard_fab2_lib.baseboard_fab2(sch_1):page193_i46:iob1" )
			)
			( pin "J4B2.B2"
				( objectStatus "@baseboard_fab2_lib.baseboard_fab2(sch_1):page193_i46:iob2" )
			)
			( pin "J4B2.B3"
				( objectStatus "@baseboard_fab2_lib.baseboard_fab2(sch_1):page193_i46:iob3" )
			)
			( pin "J4B2.B4"
				( objectStatus "@baseboard_fab2_lib.baseboard_fab2(sch_1):page193_i46:iob4" )
			)
			( pin "J4B2.B5"
				( objectStatus "@baseboard_fab2_lib.baseboard_fab2(sch_1):page193_i46:iob5" )
			)
			( pin "J4B2.B6"
				( objectStatus "@baseboard_fab2_lib.baseboard_fab2(sch_1):page193_i46:iob6" )
			)
			( pin "J4B2.B7"
				( objectStatus "@baseboard_fab2_lib.baseboard_fab2(sch_1):page193_i46:iob7" )
			)
			( pin "J4B2.B8"
				( objectStatus "@baseboard_fab2_lib.baseboard_fab2(sch_1):page193_i46:iob8" )
			)
			( pin "J4B2.B9"
				( objectStatus "@baseboard_fab2_lib.baseboard_fab2(sch_1):page193_i46:iob9" )
			)
			( pin "J4B2.B10"
				( objectStatus "@baseboard_fab2_lib.baseboard_fab2(sch_1):page193_i46:iob10" )
			)
			( pin "J4B2.B11"
				( objectStatus "@baseboard_fab2_lib.baseboard_fab2(sch_1):page193_i46:iob11" )
			)
			( pin "J4B2.B12"
				( objectStatus "@baseboard_fab2_lib.baseboard_fab2(sch_1):page193_i46:iob12" )
			)
			( pin "J4B2.B13"
				( objectStatus "@baseboard_fab2_lib.baseboard_fab2(sch_1):page193_i46:iob13" )
			)
			( pin "J4B2.B14"
				( objectStatus "@baseboard_fab2_lib.baseboard_fab2(sch_1):page193_i46:iob14" )
			)
			( pin "J4B2.B15"
				( objectStatus "@baseboard_fab2_lib.baseboard_fab2(sch_1):page193_i46:iob15" )
			)
			( pin "J4B2.B16"
				( objectStatus "@baseboard_fab2_lib.baseboard_fab2(sch_1):page193_i46:iob16" )
			)
			( pin "J4B2.B17"
				( objectStatus "@baseboard_fab2_lib.baseboard_fab2(sch_1):page193_i46:iob17" )
			)
			( pin "J4B2.B18"
				( objectStatus "@baseboard_fab2_lib.baseboard_fab2(sch_1):page193_i46:iob18" )
			)
			( pin "J4B2.B19"
				( objectStatus "@baseboard_fab2_lib.baseboard_fab2(sch_1):page193_i46:iob19" )
			)
			( pin "J4B2.B20"
				( objectStatus "@baseboard_fab2_lib.baseboard_fab2(sch_1):page193_i46:iob20" )
			)
			( pin "J4B2.C1"
				( objectStatus "@baseboard_fab2_lib.baseboard_fab2(sch_1):page193_i46:ioc1" )
			)
			( pin "J4B2.C2"
				( objectStatus "@baseboard_fab2_lib.baseboard_fab2(sch_1):page193_i46:ioc2" )
			)
			( pin "J4B2.C3"
				( objectStatus "@baseboard_fab2_lib.baseboard_fab2(sch_1):page193_i46:ioc3" )
			)
			( pin "J4B2.C4"
				( objectStatus "@baseboard_fab2_lib.baseboard_fab2(sch_1):page193_i46:ioc4" )
			)
			( pin "J4B2.C5"
				( objectStatus "@baseboard_fab2_lib.baseboard_fab2(sch_1):page193_i46:ioc5" )
			)
			( pin "J4B2.C6"
				( objectStatus "@baseboard_fab2_lib.baseboard_fab2(sch_1):page193_i46:ioc6" )
			)
			( pin "J4B2.C7"
				( objectStatus "@baseboard_fab2_lib.baseboard_fab2(sch_1):page193_i46:ioc7" )
			)
			( pin "J4B2.C8"
				( objectStatus "@baseboard_fab2_lib.baseboard_fab2(sch_1):page193_i46:ioc8" )
			)
			( pin "J4B2.C9"
				( objectStatus "@baseboard_fab2_lib.baseboard_fab2(sch_1):page193_i46:ioc9" )
			)
			( pin "J4B2.C10"
				( objectStatus "@baseboard_fab2_lib.baseboard_fab2(sch_1):page193_i46:ioc10" )
			)
			( pin "J4B2.C11"
				( objectStatus "@baseboard_fab2_lib.baseboard_fab2(sch_1):page193_i46:ioc11" )
			)
			( pin "J4B2.C12"
				( objectStatus "@baseboard_fab2_lib.baseboard_fab2(sch_1):page193_i46:ioc12" )
			)
			( pin "J4B2.C13"
				( objectStatus "@baseboard_fab2_lib.baseboard_fab2(sch_1):page193_i46:ioc13" )
			)
			( pin "J4B2.C14"
				( objectStatus "@baseboard_fab2_lib.baseboard_fab2(sch_1):page193_i46:ioc14" )
			)
			( pin "J4B2.C15"
				( objectStatus "@baseboard_fab2_lib.baseboard_fab2(sch_1):page193_i46:ioc15" )
			)
			( pin "J4B2.C16"
				( objectStatus "@baseboard_fab2_lib.baseboard_fab2(sch_1):page193_i46:ioc16" )
			)
			( pin "J4B2.C17"
				( objectStatus "@baseboard_fab2_lib.baseboard_fab2(sch_1):page193_i46:ioc17" )
			)
			( pin "J4B2.C18"
				( objectStatus "@baseboard_fab2_lib.baseboard_fab2(sch_1):page193_i46:ioc18" )
			)
			( pin "J4B2.C19"
				( objectStatus "@baseboard_fab2_lib.baseboard_fab2(sch_1):page193_i46:ioc19" )
			)
			( pin "J4B2.C20"
				( objectStatus "@baseboard_fab2_lib.baseboard_fab2(sch_1):page193_i46:ioc20" )
			)
			( pin "J4B2.D1"
				( objectStatus "@baseboard_fab2_lib.baseboard_fab2(sch_1):page193_i46:iod1" )
			)
			( pin "J4B2.D2"
				( objectStatus "@baseboard_fab2_lib.baseboard_fab2(sch_1):page193_i46:iod2" )
			)
			( pin "J4B2.D3"
				( objectStatus "@baseboard_fab2_lib.baseboard_fab2(sch_1):page193_i46:iod3" )
			)
			( pin "J4B2.D4"
				( objectStatus "@baseboard_fab2_lib.baseboard_fab2(sch_1):page193_i46:iod4" )
			)
			( pin "J4B2.D5"
				( objectStatus "@baseboard_fab2_lib.baseboard_fab2(sch_1):page193_i46:iod5" )
			)
			( pin "J4B2.D6"
				( objectStatus "@baseboard_fab2_lib.baseboard_fab2(sch_1):page193_i46:iod6" )
			)
			( pin "J4B2.D7"
				( objectStatus "@baseboard_fab2_lib.baseboard_fab2(sch_1):page193_i46:iod7" )
			)
			( pin "J4B2.D8"
				( objectStatus "@baseboard_fab2_lib.baseboard_fab2(sch_1):page193_i46:iod8" )
			)
			( pin "J4B2.D9"
				( objectStatus "@baseboard_fab2_lib.baseboard_fab2(sch_1):page193_i46:iod9" )
			)
			( pin "J4B2.D10"
				( objectStatus "@baseboard_fab2_lib.baseboard_fab2(sch_1):page193_i46:iod10" )
			)
			( pin "J4B2.D11"
				( objectStatus "@baseboard_fab2_lib.baseboard_fab2(sch_1):page193_i46:iod11" )
			)
			( pin "J4B2.D12"
				( objectStatus "@baseboard_fab2_lib.baseboard_fab2(sch_1):page193_i46:iod12" )
			)
			( pin "J4B2.D13"
				( objectStatus "@baseboard_fab2_lib.baseboard_fab2(sch_1):page193_i46:iod13" )
			)
			( pin "J4B2.D14"
				( objectStatus "@baseboard_fab2_lib.baseboard_fab2(sch_1):page193_i46:iod14" )
			)
			( pin "J4B2.D15"
				( objectStatus "@baseboard_fab2_lib.baseboard_fab2(sch_1):page193_i46:iod15" )
			)
			( pin "J4B2.D16"
				( objectStatus "@baseboard_fab2_lib.baseboard_fab2(sch_1):page193_i46:iod16" )
			)
			( pin "J4B2.D17"
				( objectStatus "@baseboard_fab2_lib.baseboard_fab2(sch_1):page193_i46:iod17" )
			)
			( pin "J4B2.D18"
				( objectStatus "@baseboard_fab2_lib.baseboard_fab2(sch_1):page193_i46:iod18" )
			)
			( pin "J4B2.D19"
				( objectStatus "@baseboard_fab2_lib.baseboard_fab2(sch_1):page193_i46:iod19" )
			)
			( pin "J4B2.D20"
				( objectStatus "@baseboard_fab2_lib.baseboard_fab2(sch_1):page193_i46:iod20" )
			)
			( pin "J4B2.E1"
				( objectStatus "@baseboard_fab2_lib.baseboard_fab2(sch_1):page193_i46:ioe1" )
			)
			( pin "J4B2.E2"
				( objectStatus "@baseboard_fab2_lib.baseboard_fab2(sch_1):page193_i46:ioe2" )
			)
			( pin "J4B2.E3"
				( objectStatus "@baseboard_fab2_lib.baseboard_fab2(sch_1):page193_i46:ioe3" )
			)
			( pin "J4B2.E4"
				( objectStatus "@baseboard_fab2_lib.baseboard_fab2(sch_1):page193_i46:ioe4" )
			)
			( pin "J4B2.E5"
				( objectStatus "@baseboard_fab2_lib.baseboard_fab2(sch_1):page193_i46:ioe5" )
			)
			( pin "J4B2.E6"
				( objectStatus "@baseboard_fab2_lib.baseboard_fab2(sch_1):page193_i46:ioe6" )
			)
			( pin "J4B2.E7"
				( objectStatus "@baseboard_fab2_lib.baseboard_fab2(sch_1):page193_i46:ioe7" )
			)
			( pin "J4B2.E8"
				( objectStatus "@baseboard_fab2_lib.baseboard_fab2(sch_1):page193_i46:ioe8" )
			)
			( pin "J4B2.E9"
				( objectStatus "@baseboard_fab2_lib.baseboard_fab2(sch_1):page193_i46:ioe9" )
			)
			( pin "J4B2.E10"
				( objectStatus "@baseboard_fab2_lib.baseboard_fab2(sch_1):page193_i46:ioe10" )
			)
			( pin "J4B2.E11"
				( objectStatus "@baseboard_fab2_lib.baseboard_fab2(sch_1):page193_i46:ioe11" )
			)
			( pin "J4B2.E12"
				( objectStatus "@baseboard_fab2_lib.baseboard_fab2(sch_1):page193_i46:ioe12" )
			)
			( pin "J4B2.E13"
				( objectStatus "@baseboard_fab2_lib.baseboard_fab2(sch_1):page193_i46:ioe13" )
			)
			( pin "J4B2.E14"
				( objectStatus "@baseboard_fab2_lib.baseboard_fab2(sch_1):page193_i46:ioe14" )
			)
			( pin "J4B2.E15"
				( objectStatus "@baseboard_fab2_lib.baseboard_fab2(sch_1):page193_i46:ioe15" )
			)
			( pin "J4B2.E16"
				( objectStatus "@baseboard_fab2_lib.baseboard_fab2(sch_1):page193_i46:ioe16" )
			)
			( pin "J4B2.E17"
				( objectStatus "@baseboard_fab2_lib.baseboard_fab2(sch_1):page193_i46:ioe17" )
			)
			( pin "J4B2.E18"
				( objectStatus "@baseboard_fab2_lib.baseboard_fab2(sch_1):page193_i46:ioe18" )
			)
			( pin "J4B2.E19"
				( objectStatus "@baseboard_fab2_lib.baseboard_fab2(sch_1):page193_i46:ioe19" )
			)
			( pin "J4B2.E20"
				( objectStatus "@baseboard_fab2_lib.baseboard_fab2(sch_1):page193_i46:ioe20" )
			)
			( pin "J4B2.F1"
				( objectStatus "@baseboard_fab2_lib.baseboard_fab2(sch_1):page193_i46:iof1" )
			)
			( pin "J4B2.F2"
				( objectStatus "@baseboard_fab2_lib.baseboard_fab2(sch_1):page193_i46:iof2" )
			)
			( pin "J4B2.F3"
				( objectStatus "@baseboard_fab2_lib.baseboard_fab2(sch_1):page193_i46:iof3" )
			)
			( pin "J4B2.F4"
				( objectStatus "@baseboard_fab2_lib.baseboard_fab2(sch_1):page193_i46:iof4" )
			)
			( pin "J4B2.F5"
				( objectStatus "@baseboard_fab2_lib.baseboard_fab2(sch_1):page193_i46:iof5" )
			)
			( pin "J4B2.F6"
				( objectStatus "@baseboard_fab2_lib.baseboard_fab2(sch_1):page193_i46:iof6" )
			)
			( pin "J4B2.F7"
				( objectStatus "@baseboard_fab2_lib.baseboard_fab2(sch_1):page193_i46:iof7" )
			)
			( pin "J4B2.F8"
				( objectStatus "@baseboard_fab2_lib.baseboard_fab2(sch_1):page193_i46:iof8" )
			)
			( pin "J4B2.F9"
				( objectStatus "@baseboard_fab2_lib.baseboard_fab2(sch_1):page193_i46:iof9" )
			)
			( pin "J4B2.F10"
				( objectStatus "@baseboard_fab2_lib.baseboard_fab2(sch_1):page193_i46:iof10" )
			)
			( pin "J4B2.F11"
				( objectStatus "@baseboard_fab2_lib.baseboard_fab2(sch_1):page193_i46:iof11" )
			)
			( pin "J4B2.F12"
				( objectStatus "@baseboard_fab2_lib.baseboard_fab2(sch_1):page193_i46:iof12" )
			)
			( pin "J4B2.F13"
				( objectStatus "@baseboard_fab2_lib.baseboard_fab2(sch_1):page193_i46:iof13" )
			)
			( pin "J4B2.F14"
				( objectStatus "@baseboard_fab2_lib.baseboard_fab2(sch_1):page193_i46:iof14" )
			)
			( pin "J4B2.F15"
				( objectStatus "@baseboard_fab2_lib.baseboard_fab2(sch_1):page193_i46:iof15" )
			)
			( pin "J4B2.F16"
				( objectStatus "@baseboard_fab2_lib.baseboard_fab2(sch_1):page193_i46:iof16" )
			)
			( pin "J4B2.F17"
				( objectStatus "@baseboard_fab2_lib.baseboard_fab2(sch_1):page193_i46:iof17" )
			)
			( pin "J4B2.F18"
				( objectStatus "@baseboard_fab2_lib.baseboard_fab2(sch_1):page193_i46:iof18" )
			)
			( pin "J4B2.F19"
				( objectStatus "@baseboard_fab2_lib.baseboard_fab2(sch_1):page193_i46:iof19" )
			)
			( pin "J4B2.F20"
				( objectStatus "@baseboard_fab2_lib.baseboard_fab2(sch_1):page193_i46:iof20" )
			)
			( pin "C4E24.1"
				( objectStatus "@baseboard_fab2_lib.baseboard_fab2(sch_1):page193_i61:a" )
			)
			( pin "C4E24.2"
				( objectStatus "@baseboard_fab2_lib.baseboard_fab2(sch_1):page193_i61:b" )
			)
			( pin "C6R16.1"
				( objectStatus "@baseboard_fab2_lib.baseboard_fab2(sch_1):page193_i62:a" )
			)
			( pin "C6R16.2"
				( objectStatus "@baseboard_fab2_lib.baseboard_fab2(sch_1):page193_i62:b" )
			)
			( pin "C4F1.1"
				( objectStatus "@baseboard_fab2_lib.baseboard_fab2(sch_1):page193_i68:a" )
			)
			( pin "C4F1.2"
				( objectStatus "@baseboard_fab2_lib.baseboard_fab2(sch_1):page193_i68:b" )
			)
			( pin "C4F3.1"
				( objectStatus "@baseboard_fab2_lib.baseboard_fab2(sch_1):page193_i70:a" )
			)
			( pin "C4F3.2"
				( objectStatus "@baseboard_fab2_lib.baseboard_fab2(sch_1):page193_i70:b" )
			)
			( pin "C3F1.1"
				( objectStatus "@baseboard_fab2_lib.baseboard_fab2(sch_1):page193_i140:a" )
			)
			( pin "C3F1.2"
				( objectStatus "@baseboard_fab2_lib.baseboard_fab2(sch_1):page193_i140:b" )
			)
			( pin "C4F2.1"
				( objectStatus "@baseboard_fab2_lib.baseboard_fab2(sch_1):page193_i141:a" )
			)
			( pin "C4F2.2"
				( objectStatus "@baseboard_fab2_lib.baseboard_fab2(sch_1):page193_i141:b" )
			)
			( pin "R4C12.1"
				( objectStatus "@baseboard_fab2_lib.baseboard_fab2(sch_1):page193_i169:a" )
			)
			( pin "R4C12.2"
				( objectStatus "@baseboard_fab2_lib.baseboard_fab2(sch_1):page193_i169:b" )
			)
			( pin "R4C11.1"
				( objectStatus "@baseboard_fab2_lib.baseboard_fab2(sch_1):page193_i170:a" )
			)
			( pin "R4C11.2"
				( objectStatus "@baseboard_fab2_lib.baseboard_fab2(sch_1):page193_i170:b" )
			)
			( pin "C4T2.1"
				( objectStatus "@baseboard_fab2_lib.baseboard_fab2(sch_1):page194_i9:a" )
			)
			( pin "C4T2.2"
				( objectStatus "@baseboard_fab2_lib.baseboard_fab2(sch_1):page194_i9:b" )
			)
			( pin "C4T1.1"
				( objectStatus "@baseboard_fab2_lib.baseboard_fab2(sch_1):page194_i16:a" )
			)
			( pin "C4T1.2"
				( objectStatus "@baseboard_fab2_lib.baseboard_fab2(sch_1):page194_i16:b" )
			)
			( pin "C4R1.1"
				( objectStatus "@baseboard_fab2_lib.baseboard_fab2(sch_1):page194_i29:a" )
			)
			( pin "C4R1.2"
				( objectStatus "@baseboard_fab2_lib.baseboard_fab2(sch_1):page194_i29:b" )
			)
			( pin "C3R4.1"
				( objectStatus "@baseboard_fab2_lib.baseboard_fab2(sch_1):page194_i31:a" )
			)
			( pin "C3R4.2"
				( objectStatus "@baseboard_fab2_lib.baseboard_fab2(sch_1):page194_i31:b" )
			)
			( pin "J6E1.A1"
				( objectStatus "@baseboard_fab2_lib.baseboard_fab2(sch_1):page194_i55:ioa1" )
			)
			( pin "J6E1.A2"
				( objectStatus "@baseboard_fab2_lib.baseboard_fab2(sch_1):page194_i55:ioa2" )
			)
			( pin "J6E1.A3"
				( objectStatus "@baseboard_fab2_lib.baseboard_fab2(sch_1):page194_i55:ioa3" )
			)
			( pin "J6E1.A4"
				( objectStatus "@baseboard_fab2_lib.baseboard_fab2(sch_1):page194_i55:ioa4" )
			)
			( pin "J6E1.A5"
				( objectStatus "@baseboard_fab2_lib.baseboard_fab2(sch_1):page194_i55:ioa5" )
			)
			( pin "J6E1.A6"
				( objectStatus "@baseboard_fab2_lib.baseboard_fab2(sch_1):page194_i55:ioa6" )
			)
			( pin "J6E1.A7"
				( objectStatus "@baseboard_fab2_lib.baseboard_fab2(sch_1):page194_i55:ioa7" )
			)
			( pin "J6E1.A8"
				( objectStatus "@baseboard_fab2_lib.baseboard_fab2(sch_1):page194_i55:ioa8" )
			)
			( pin "J6E1.A9"
				( objectStatus "@baseboard_fab2_lib.baseboard_fab2(sch_1):page194_i55:ioa9" )
			)
			( pin "J6E1.A10"
				( objectStatus "@baseboard_fab2_lib.baseboard_fab2(sch_1):page194_i55:ioa10" )
			)
			( pin "J6E1.A11"
				( objectStatus "@baseboard_fab2_lib.baseboard_fab2(sch_1):page194_i55:ioa11" )
			)
			( pin "J6E1.A12"
				( objectStatus "@baseboard_fab2_lib.baseboard_fab2(sch_1):page194_i55:ioa12" )
			)
			( pin "J6E1.A13"
				( objectStatus "@baseboard_fab2_lib.baseboard_fab2(sch_1):page194_i55:ioa13" )
			)
			( pin "J6E1.A14"
				( objectStatus "@baseboard_fab2_lib.baseboard_fab2(sch_1):page194_i55:ioa14" )
			)
			( pin "J6E1.A15"
				( objectStatus "@baseboard_fab2_lib.baseboard_fab2(sch_1):page194_i55:ioa15" )
			)
			( pin "J6E1.A16"
				( objectStatus "@baseboard_fab2_lib.baseboard_fab2(sch_1):page194_i55:ioa16" )
			)
			( pin "J6E1.A17"
				( objectStatus "@baseboard_fab2_lib.baseboard_fab2(sch_1):page194_i55:ioa17" )
			)
			( pin "J6E1.A18"
				( objectStatus "@baseboard_fab2_lib.baseboard_fab2(sch_1):page194_i55:ioa18" )
			)
			( pin "J6E1.A19"
				( objectStatus "@baseboard_fab2_lib.baseboard_fab2(sch_1):page194_i55:ioa19" )
			)
			( pin "J6E1.A20"
				( objectStatus "@baseboard_fab2_lib.baseboard_fab2(sch_1):page194_i55:ioa20" )
			)
			( pin "J6E1.B1"
				( objectStatus "@baseboard_fab2_lib.baseboard_fab2(sch_1):page194_i55:iob1" )
			)
			( pin "J6E1.B2"
				( objectStatus "@baseboard_fab2_lib.baseboard_fab2(sch_1):page194_i55:iob2" )
			)
			( pin "J6E1.B3"
				( objectStatus "@baseboard_fab2_lib.baseboard_fab2(sch_1):page194_i55:iob3" )
			)
			( pin "J6E1.B4"
				( objectStatus "@baseboard_fab2_lib.baseboard_fab2(sch_1):page194_i55:iob4" )
			)
			( pin "J6E1.B5"
				( objectStatus "@baseboard_fab2_lib.baseboard_fab2(sch_1):page194_i55:iob5" )
			)
			( pin "J6E1.B6"
				( objectStatus "@baseboard_fab2_lib.baseboard_fab2(sch_1):page194_i55:iob6" )
			)
			( pin "J6E1.B7"
				( objectStatus "@baseboard_fab2_lib.baseboard_fab2(sch_1):page194_i55:iob7" )
			)
			( pin "J6E1.B8"
				( objectStatus "@baseboard_fab2_lib.baseboard_fab2(sch_1):page194_i55:iob8" )
			)
			( pin "J6E1.B9"
				( objectStatus "@baseboard_fab2_lib.baseboard_fab2(sch_1):page194_i55:iob9" )
			)
			( pin "J6E1.B10"
				( objectStatus "@baseboard_fab2_lib.baseboard_fab2(sch_1):page194_i55:iob10" )
			)
			( pin "J6E1.B11"
				( objectStatus "@baseboard_fab2_lib.baseboard_fab2(sch_1):page194_i55:iob11" )
			)
			( pin "J6E1.B12"
				( objectStatus "@baseboard_fab2_lib.baseboard_fab2(sch_1):page194_i55:iob12" )
			)
			( pin "J6E1.B13"
				( objectStatus "@baseboard_fab2_lib.baseboard_fab2(sch_1):page194_i55:iob13" )
			)
			( pin "J6E1.B14"
				( objectStatus "@baseboard_fab2_lib.baseboard_fab2(sch_1):page194_i55:iob14" )
			)
			( pin "J6E1.B15"
				( objectStatus "@baseboard_fab2_lib.baseboard_fab2(sch_1):page194_i55:iob15" )
			)
			( pin "J6E1.B16"
				( objectStatus "@baseboard_fab2_lib.baseboard_fab2(sch_1):page194_i55:iob16" )
			)
			( pin "J6E1.B17"
				( objectStatus "@baseboard_fab2_lib.baseboard_fab2(sch_1):page194_i55:iob17" )
			)
			( pin "J6E1.B18"
				( objectStatus "@baseboard_fab2_lib.baseboard_fab2(sch_1):page194_i55:iob18" )
			)
			( pin "J6E1.B19"
				( objectStatus "@baseboard_fab2_lib.baseboard_fab2(sch_1):page194_i55:iob19" )
			)
			( pin "J6E1.B20"
				( objectStatus "@baseboard_fab2_lib.baseboard_fab2(sch_1):page194_i55:iob20" )
			)
			( pin "J6E1.C1"
				( objectStatus "@baseboard_fab2_lib.baseboard_fab2(sch_1):page194_i55:ioc1" )
			)
			( pin "J6E1.C2"
				( objectStatus "@baseboard_fab2_lib.baseboard_fab2(sch_1):page194_i55:ioc2" )
			)
			( pin "J6E1.C3"
				( objectStatus "@baseboard_fab2_lib.baseboard_fab2(sch_1):page194_i55:ioc3" )
			)
			( pin "J6E1.C4"
				( objectStatus "@baseboard_fab2_lib.baseboard_fab2(sch_1):page194_i55:ioc4" )
			)
			( pin "J6E1.C5"
				( objectStatus "@baseboard_fab2_lib.baseboard_fab2(sch_1):page194_i55:ioc5" )
			)
			( pin "J6E1.C6"
				( objectStatus "@baseboard_fab2_lib.baseboard_fab2(sch_1):page194_i55:ioc6" )
			)
			( pin "J6E1.C7"
				( objectStatus "@baseboard_fab2_lib.baseboard_fab2(sch_1):page194_i55:ioc7" )
			)
			( pin "J6E1.C8"
				( objectStatus "@baseboard_fab2_lib.baseboard_fab2(sch_1):page194_i55:ioc8" )
			)
			( pin "J6E1.C9"
				( objectStatus "@baseboard_fab2_lib.baseboard_fab2(sch_1):page194_i55:ioc9" )
			)
			( pin "J6E1.C10"
				( objectStatus "@baseboard_fab2_lib.baseboard_fab2(sch_1):page194_i55:ioc10" )
			)
			( pin "J6E1.C11"
				( objectStatus "@baseboard_fab2_lib.baseboard_fab2(sch_1):page194_i55:ioc11" )
			)
			( pin "J6E1.C12"
				( objectStatus "@baseboard_fab2_lib.baseboard_fab2(sch_1):page194_i55:ioc12" )
			)
			( pin "J6E1.C13"
				( objectStatus "@baseboard_fab2_lib.baseboard_fab2(sch_1):page194_i55:ioc13" )
			)
			( pin "J6E1.C14"
				( objectStatus "@baseboard_fab2_lib.baseboard_fab2(sch_1):page194_i55:ioc14" )
			)
			( pin "J6E1.C15"
				( objectStatus "@baseboard_fab2_lib.baseboard_fab2(sch_1):page194_i55:ioc15" )
			)
			( pin "J6E1.C16"
				( objectStatus "@baseboard_fab2_lib.baseboard_fab2(sch_1):page194_i55:ioc16" )
			)
			( pin "J6E1.C17"
				( objectStatus "@baseboard_fab2_lib.baseboard_fab2(sch_1):page194_i55:ioc17" )
			)
			( pin "J6E1.C18"
				( objectStatus "@baseboard_fab2_lib.baseboard_fab2(sch_1):page194_i55:ioc18" )
			)
			( pin "J6E1.C19"
				( objectStatus "@baseboard_fab2_lib.baseboard_fab2(sch_1):page194_i55:ioc19" )
			)
			( pin "J6E1.C20"
				( objectStatus "@baseboard_fab2_lib.baseboard_fab2(sch_1):page194_i55:ioc20" )
			)
			( pin "J6E1.D1"
				( objectStatus "@baseboard_fab2_lib.baseboard_fab2(sch_1):page194_i55:iod1" )
			)
			( pin "J6E1.D2"
				( objectStatus "@baseboard_fab2_lib.baseboard_fab2(sch_1):page194_i55:iod2" )
			)
			( pin "J6E1.D3"
				( objectStatus "@baseboard_fab2_lib.baseboard_fab2(sch_1):page194_i55:iod3" )
			)
			( pin "J6E1.D4"
				( objectStatus "@baseboard_fab2_lib.baseboard_fab2(sch_1):page194_i55:iod4" )
			)
			( pin "J6E1.D5"
				( objectStatus "@baseboard_fab2_lib.baseboard_fab2(sch_1):page194_i55:iod5" )
			)
			( pin "J6E1.D6"
				( objectStatus "@baseboard_fab2_lib.baseboard_fab2(sch_1):page194_i55:iod6" )
			)
			( pin "J6E1.D7"
				( objectStatus "@baseboard_fab2_lib.baseboard_fab2(sch_1):page194_i55:iod7" )
			)
			( pin "J6E1.D8"
				( objectStatus "@baseboard_fab2_lib.baseboard_fab2(sch_1):page194_i55:iod8" )
			)
			( pin "J6E1.D9"
				( objectStatus "@baseboard_fab2_lib.baseboard_fab2(sch_1):page194_i55:iod9" )
			)
			( pin "J6E1.D10"
				( objectStatus "@baseboard_fab2_lib.baseboard_fab2(sch_1):page194_i55:iod10" )
			)
			( pin "J6E1.D11"
				( objectStatus "@baseboard_fab2_lib.baseboard_fab2(sch_1):page194_i55:iod11" )
			)
			( pin "J6E1.D12"
				( objectStatus "@baseboard_fab2_lib.baseboard_fab2(sch_1):page194_i55:iod12" )
			)
			( pin "J6E1.D13"
				( objectStatus "@baseboard_fab2_lib.baseboard_fab2(sch_1):page194_i55:iod13" )
			)
			( pin "J6E1.D14"
				( objectStatus "@baseboard_fab2_lib.baseboard_fab2(sch_1):page194_i55:iod14" )
			)
			( pin "J6E1.D15"
				( objectStatus "@baseboard_fab2_lib.baseboard_fab2(sch_1):page194_i55:iod15" )
			)
			( pin "J6E1.D16"
				( objectStatus "@baseboard_fab2_lib.baseboard_fab2(sch_1):page194_i55:iod16" )
			)
			( pin "J6E1.D17"
				( objectStatus "@baseboard_fab2_lib.baseboard_fab2(sch_1):page194_i55:iod17" )
			)
			( pin "J6E1.D18"
				( objectStatus "@baseboard_fab2_lib.baseboard_fab2(sch_1):page194_i55:iod18" )
			)
			( pin "J6E1.D19"
				( objectStatus "@baseboard_fab2_lib.baseboard_fab2(sch_1):page194_i55:iod19" )
			)
			( pin "J6E1.D20"
				( objectStatus "@baseboard_fab2_lib.baseboard_fab2(sch_1):page194_i55:iod20" )
			)
			( pin "J6E1.E1"
				( objectStatus "@baseboard_fab2_lib.baseboard_fab2(sch_1):page194_i55:ioe1" )
			)
			( pin "J6E1.E2"
				( objectStatus "@baseboard_fab2_lib.baseboard_fab2(sch_1):page194_i55:ioe2" )
			)
			( pin "J6E1.E3"
				( objectStatus "@baseboard_fab2_lib.baseboard_fab2(sch_1):page194_i55:ioe3" )
			)
			( pin "J6E1.E4"
				( objectStatus "@baseboard_fab2_lib.baseboard_fab2(sch_1):page194_i55:ioe4" )
			)
			( pin "J6E1.E5"
				( objectStatus "@baseboard_fab2_lib.baseboard_fab2(sch_1):page194_i55:ioe5" )
			)
			( pin "J6E1.E6"
				( objectStatus "@baseboard_fab2_lib.baseboard_fab2(sch_1):page194_i55:ioe6" )
			)
			( pin "J6E1.E7"
				( objectStatus "@baseboard_fab2_lib.baseboard_fab2(sch_1):page194_i55:ioe7" )
			)
			( pin "J6E1.E8"
				( objectStatus "@baseboard_fab2_lib.baseboard_fab2(sch_1):page194_i55:ioe8" )
			)
			( pin "J6E1.E9"
				( objectStatus "@baseboard_fab2_lib.baseboard_fab2(sch_1):page194_i55:ioe9" )
			)
			( pin "J6E1.E10"
				( objectStatus "@baseboard_fab2_lib.baseboard_fab2(sch_1):page194_i55:ioe10" )
			)
			( pin "J6E1.E11"
				( objectStatus "@baseboard_fab2_lib.baseboard_fab2(sch_1):page194_i55:ioe11" )
			)
			( pin "J6E1.E12"
				( objectStatus "@baseboard_fab2_lib.baseboard_fab2(sch_1):page194_i55:ioe12" )
			)
			( pin "J6E1.E13"
				( objectStatus "@baseboard_fab2_lib.baseboard_fab2(sch_1):page194_i55:ioe13" )
			)
			( pin "J6E1.E14"
				( objectStatus "@baseboard_fab2_lib.baseboard_fab2(sch_1):page194_i55:ioe14" )
			)
			( pin "J6E1.E15"
				( objectStatus "@baseboard_fab2_lib.baseboard_fab2(sch_1):page194_i55:ioe15" )
			)
			( pin "J6E1.E16"
				( objectStatus "@baseboard_fab2_lib.baseboard_fab2(sch_1):page194_i55:ioe16" )
			)
			( pin "J6E1.E17"
				( objectStatus "@baseboard_fab2_lib.baseboard_fab2(sch_1):page194_i55:ioe17" )
			)
			( pin "J6E1.E18"
				( objectStatus "@baseboard_fab2_lib.baseboard_fab2(sch_1):page194_i55:ioe18" )
			)
			( pin "J6E1.E19"
				( objectStatus "@baseboard_fab2_lib.baseboard_fab2(sch_1):page194_i55:ioe19" )
			)
			( pin "J6E1.E20"
				( objectStatus "@baseboard_fab2_lib.baseboard_fab2(sch_1):page194_i55:ioe20" )
			)
			( pin "J6E1.F1"
				( objectStatus "@baseboard_fab2_lib.baseboard_fab2(sch_1):page194_i55:iof1" )
			)
			( pin "J6E1.F2"
				( objectStatus "@baseboard_fab2_lib.baseboard_fab2(sch_1):page194_i55:iof2" )
			)
			( pin "J6E1.F3"
				( objectStatus "@baseboard_fab2_lib.baseboard_fab2(sch_1):page194_i55:iof3" )
			)
			( pin "J6E1.F4"
				( objectStatus "@baseboard_fab2_lib.baseboard_fab2(sch_1):page194_i55:iof4" )
			)
			( pin "J6E1.F5"
				( objectStatus "@baseboard_fab2_lib.baseboard_fab2(sch_1):page194_i55:iof5" )
			)
			( pin "J6E1.F6"
				( objectStatus "@baseboard_fab2_lib.baseboard_fab2(sch_1):page194_i55:iof6" )
			)
			( pin "J6E1.F7"
				( objectStatus "@baseboard_fab2_lib.baseboard_fab2(sch_1):page194_i55:iof7" )
			)
			( pin "J6E1.F8"
				( objectStatus "@baseboard_fab2_lib.baseboard_fab2(sch_1):page194_i55:iof8" )
			)
			( pin "J6E1.F9"
				( objectStatus "@baseboard_fab2_lib.baseboard_fab2(sch_1):page194_i55:iof9" )
			)
			( pin "J6E1.F10"
				( objectStatus "@baseboard_fab2_lib.baseboard_fab2(sch_1):page194_i55:iof10" )
			)
			( pin "J6E1.F11"
				( objectStatus "@baseboard_fab2_lib.baseboard_fab2(sch_1):page194_i55:iof11" )
			)
			( pin "J6E1.F12"
				( objectStatus "@baseboard_fab2_lib.baseboard_fab2(sch_1):page194_i55:iof12" )
			)
			( pin "J6E1.F13"
				( objectStatus "@baseboard_fab2_lib.baseboard_fab2(sch_1):page194_i55:iof13" )
			)
			( pin "J6E1.F14"
				( objectStatus "@baseboard_fab2_lib.baseboard_fab2(sch_1):page194_i55:iof14" )
			)
			( pin "J6E1.F15"
				( objectStatus "@baseboard_fab2_lib.baseboard_fab2(sch_1):page194_i55:iof15" )
			)
			( pin "J6E1.F16"
				( objectStatus "@baseboard_fab2_lib.baseboard_fab2(sch_1):page194_i55:iof16" )
			)
			( pin "J6E1.F17"
				( objectStatus "@baseboard_fab2_lib.baseboard_fab2(sch_1):page194_i55:iof17" )
			)
			( pin "J6E1.F18"
				( objectStatus "@baseboard_fab2_lib.baseboard_fab2(sch_1):page194_i55:iof18" )
			)
			( pin "J6E1.F19"
				( objectStatus "@baseboard_fab2_lib.baseboard_fab2(sch_1):page194_i55:iof19" )
			)
			( pin "J6E1.F20"
				( objectStatus "@baseboard_fab2_lib.baseboard_fab2(sch_1):page194_i55:iof20" )
			)
			( pin "J6B1.A1"
				( objectStatus "@baseboard_fab2_lib.baseboard_fab2(sch_1):page194_i56:ioa1" )
			)
			( pin "J6B1.A2"
				( objectStatus "@baseboard_fab2_lib.baseboard_fab2(sch_1):page194_i56:ioa2" )
			)
			( pin "J6B1.A3"
				( objectStatus "@baseboard_fab2_lib.baseboard_fab2(sch_1):page194_i56:ioa3" )
			)
			( pin "J6B1.A4"
				( objectStatus "@baseboard_fab2_lib.baseboard_fab2(sch_1):page194_i56:ioa4" )
			)
			( pin "J6B1.A5"
				( objectStatus "@baseboard_fab2_lib.baseboard_fab2(sch_1):page194_i56:ioa5" )
			)
			( pin "J6B1.A6"
				( objectStatus "@baseboard_fab2_lib.baseboard_fab2(sch_1):page194_i56:ioa6" )
			)
			( pin "J6B1.A7"
				( objectStatus "@baseboard_fab2_lib.baseboard_fab2(sch_1):page194_i56:ioa7" )
			)
			( pin "J6B1.A8"
				( objectStatus "@baseboard_fab2_lib.baseboard_fab2(sch_1):page194_i56:ioa8" )
			)
			( pin "J6B1.A9"
				( objectStatus "@baseboard_fab2_lib.baseboard_fab2(sch_1):page194_i56:ioa9" )
			)
			( pin "J6B1.A10"
				( objectStatus "@baseboard_fab2_lib.baseboard_fab2(sch_1):page194_i56:ioa10" )
			)
			( pin "J6B1.A11"
				( objectStatus "@baseboard_fab2_lib.baseboard_fab2(sch_1):page194_i56:ioa11" )
			)
			( pin "J6B1.A12"
				( objectStatus "@baseboard_fab2_lib.baseboard_fab2(sch_1):page194_i56:ioa12" )
			)
			( pin "J6B1.A13"
				( objectStatus "@baseboard_fab2_lib.baseboard_fab2(sch_1):page194_i56:ioa13" )
			)
			( pin "J6B1.A14"
				( objectStatus "@baseboard_fab2_lib.baseboard_fab2(sch_1):page194_i56:ioa14" )
			)
			( pin "J6B1.A15"
				( objectStatus "@baseboard_fab2_lib.baseboard_fab2(sch_1):page194_i56:ioa15" )
			)
			( pin "J6B1.A16"
				( objectStatus "@baseboard_fab2_lib.baseboard_fab2(sch_1):page194_i56:ioa16" )
			)
			( pin "J6B1.A17"
				( objectStatus "@baseboard_fab2_lib.baseboard_fab2(sch_1):page194_i56:ioa17" )
			)
			( pin "J6B1.A18"
				( objectStatus "@baseboard_fab2_lib.baseboard_fab2(sch_1):page194_i56:ioa18" )
			)
			( pin "J6B1.A19"
				( objectStatus "@baseboard_fab2_lib.baseboard_fab2(sch_1):page194_i56:ioa19" )
			)
			( pin "J6B1.A20"
				( objectStatus "@baseboard_fab2_lib.baseboard_fab2(sch_1):page194_i56:ioa20" )
			)
			( pin "J6B1.B1"
				( objectStatus "@baseboard_fab2_lib.baseboard_fab2(sch_1):page194_i56:iob1" )
			)
			( pin "J6B1.B2"
				( objectStatus "@baseboard_fab2_lib.baseboard_fab2(sch_1):page194_i56:iob2" )
			)
			( pin "J6B1.B3"
				( objectStatus "@baseboard_fab2_lib.baseboard_fab2(sch_1):page194_i56:iob3" )
			)
			( pin "J6B1.B4"
				( objectStatus "@baseboard_fab2_lib.baseboard_fab2(sch_1):page194_i56:iob4" )
			)
			( pin "J6B1.B5"
				( objectStatus "@baseboard_fab2_lib.baseboard_fab2(sch_1):page194_i56:iob5" )
			)
			( pin "J6B1.B6"
				( objectStatus "@baseboard_fab2_lib.baseboard_fab2(sch_1):page194_i56:iob6" )
			)
			( pin "J6B1.B7"
				( objectStatus "@baseboard_fab2_lib.baseboard_fab2(sch_1):page194_i56:iob7" )
			)
			( pin "J6B1.B8"
				( objectStatus "@baseboard_fab2_lib.baseboard_fab2(sch_1):page194_i56:iob8" )
			)
			( pin "J6B1.B9"
				( objectStatus "@baseboard_fab2_lib.baseboard_fab2(sch_1):page194_i56:iob9" )
			)
			( pin "J6B1.B10"
				( objectStatus "@baseboard_fab2_lib.baseboard_fab2(sch_1):page194_i56:iob10" )
			)
			( pin "J6B1.B11"
				( objectStatus "@baseboard_fab2_lib.baseboard_fab2(sch_1):page194_i56:iob11" )
			)
			( pin "J6B1.B12"
				( objectStatus "@baseboard_fab2_lib.baseboard_fab2(sch_1):page194_i56:iob12" )
			)
			( pin "J6B1.B13"
				( objectStatus "@baseboard_fab2_lib.baseboard_fab2(sch_1):page194_i56:iob13" )
			)
			( pin "J6B1.B14"
				( objectStatus "@baseboard_fab2_lib.baseboard_fab2(sch_1):page194_i56:iob14" )
			)
			( pin "J6B1.B15"
				( objectStatus "@baseboard_fab2_lib.baseboard_fab2(sch_1):page194_i56:iob15" )
			)
			( pin "J6B1.B16"
				( objectStatus "@baseboard_fab2_lib.baseboard_fab2(sch_1):page194_i56:iob16" )
			)
			( pin "J6B1.B17"
				( objectStatus "@baseboard_fab2_lib.baseboard_fab2(sch_1):page194_i56:iob17" )
			)
			( pin "J6B1.B18"
				( objectStatus "@baseboard_fab2_lib.baseboard_fab2(sch_1):page194_i56:iob18" )
			)
			( pin "J6B1.B19"
				( objectStatus "@baseboard_fab2_lib.baseboard_fab2(sch_1):page194_i56:iob19" )
			)
			( pin "J6B1.B20"
				( objectStatus "@baseboard_fab2_lib.baseboard_fab2(sch_1):page194_i56:iob20" )
			)
			( pin "J6B1.C1"
				( objectStatus "@baseboard_fab2_lib.baseboard_fab2(sch_1):page194_i56:ioc1" )
			)
			( pin "J6B1.C2"
				( objectStatus "@baseboard_fab2_lib.baseboard_fab2(sch_1):page194_i56:ioc2" )
			)
			( pin "J6B1.C3"
				( objectStatus "@baseboard_fab2_lib.baseboard_fab2(sch_1):page194_i56:ioc3" )
			)
			( pin "J6B1.C4"
				( objectStatus "@baseboard_fab2_lib.baseboard_fab2(sch_1):page194_i56:ioc4" )
			)
			( pin "J6B1.C5"
				( objectStatus "@baseboard_fab2_lib.baseboard_fab2(sch_1):page194_i56:ioc5" )
			)
			( pin "J6B1.C6"
				( objectStatus "@baseboard_fab2_lib.baseboard_fab2(sch_1):page194_i56:ioc6" )
			)
			( pin "J6B1.C7"
				( objectStatus "@baseboard_fab2_lib.baseboard_fab2(sch_1):page194_i56:ioc7" )
			)
			( pin "J6B1.C8"
				( objectStatus "@baseboard_fab2_lib.baseboard_fab2(sch_1):page194_i56:ioc8" )
			)
			( pin "J6B1.C9"
				( objectStatus "@baseboard_fab2_lib.baseboard_fab2(sch_1):page194_i56:ioc9" )
			)
			( pin "J6B1.C10"
				( objectStatus "@baseboard_fab2_lib.baseboard_fab2(sch_1):page194_i56:ioc10" )
			)
			( pin "J6B1.C11"
				( objectStatus "@baseboard_fab2_lib.baseboard_fab2(sch_1):page194_i56:ioc11" )
			)
			( pin "J6B1.C12"
				( objectStatus "@baseboard_fab2_lib.baseboard_fab2(sch_1):page194_i56:ioc12" )
			)
			( pin "J6B1.C13"
				( objectStatus "@baseboard_fab2_lib.baseboard_fab2(sch_1):page194_i56:ioc13" )
			)
			( pin "J6B1.C14"
				( objectStatus "@baseboard_fab2_lib.baseboard_fab2(sch_1):page194_i56:ioc14" )
			)
			( pin "J6B1.C15"
				( objectStatus "@baseboard_fab2_lib.baseboard_fab2(sch_1):page194_i56:ioc15" )
			)
			( pin "J6B1.C16"
				( objectStatus "@baseboard_fab2_lib.baseboard_fab2(sch_1):page194_i56:ioc16" )
			)
			( pin "J6B1.C17"
				( objectStatus "@baseboard_fab2_lib.baseboard_fab2(sch_1):page194_i56:ioc17" )
			)
			( pin "J6B1.C18"
				( objectStatus "@baseboard_fab2_lib.baseboard_fab2(sch_1):page194_i56:ioc18" )
			)
			( pin "J6B1.C19"
				( objectStatus "@baseboard_fab2_lib.baseboard_fab2(sch_1):page194_i56:ioc19" )
			)
			( pin "J6B1.C20"
				( objectStatus "@baseboard_fab2_lib.baseboard_fab2(sch_1):page194_i56:ioc20" )
			)
			( pin "J6B1.D1"
				( objectStatus "@baseboard_fab2_lib.baseboard_fab2(sch_1):page194_i56:iod1" )
			)
			( pin "J6B1.D2"
				( objectStatus "@baseboard_fab2_lib.baseboard_fab2(sch_1):page194_i56:iod2" )
			)
			( pin "J6B1.D3"
				( objectStatus "@baseboard_fab2_lib.baseboard_fab2(sch_1):page194_i56:iod3" )
			)
			( pin "J6B1.D4"
				( objectStatus "@baseboard_fab2_lib.baseboard_fab2(sch_1):page194_i56:iod4" )
			)
			( pin "J6B1.D5"
				( objectStatus "@baseboard_fab2_lib.baseboard_fab2(sch_1):page194_i56:iod5" )
			)
			( pin "J6B1.D6"
				( objectStatus "@baseboard_fab2_lib.baseboard_fab2(sch_1):page194_i56:iod6" )
			)
			( pin "J6B1.D7"
				( objectStatus "@baseboard_fab2_lib.baseboard_fab2(sch_1):page194_i56:iod7" )
			)
			( pin "J6B1.D8"
				( objectStatus "@baseboard_fab2_lib.baseboard_fab2(sch_1):page194_i56:iod8" )
			)
			( pin "J6B1.D9"
				( objectStatus "@baseboard_fab2_lib.baseboard_fab2(sch_1):page194_i56:iod9" )
			)
			( pin "J6B1.D10"
				( objectStatus "@baseboard_fab2_lib.baseboard_fab2(sch_1):page194_i56:iod10" )
			)
			( pin "J6B1.D11"
				( objectStatus "@baseboard_fab2_lib.baseboard_fab2(sch_1):page194_i56:iod11" )
			)
			( pin "J6B1.D12"
				( objectStatus "@baseboard_fab2_lib.baseboard_fab2(sch_1):page194_i56:iod12" )
			)
			( pin "J6B1.D13"
				( objectStatus "@baseboard_fab2_lib.baseboard_fab2(sch_1):page194_i56:iod13" )
			)
			( pin "J6B1.D14"
				( objectStatus "@baseboard_fab2_lib.baseboard_fab2(sch_1):page194_i56:iod14" )
			)
			( pin "J6B1.D15"
				( objectStatus "@baseboard_fab2_lib.baseboard_fab2(sch_1):page194_i56:iod15" )
			)
			( pin "J6B1.D16"
				( objectStatus "@baseboard_fab2_lib.baseboard_fab2(sch_1):page194_i56:iod16" )
			)
			( pin "J6B1.D17"
				( objectStatus "@baseboard_fab2_lib.baseboard_fab2(sch_1):page194_i56:iod17" )
			)
			( pin "J6B1.D18"
				( objectStatus "@baseboard_fab2_lib.baseboard_fab2(sch_1):page194_i56:iod18" )
			)
			( pin "J6B1.D19"
				( objectStatus "@baseboard_fab2_lib.baseboard_fab2(sch_1):page194_i56:iod19" )
			)
			( pin "J6B1.D20"
				( objectStatus "@baseboard_fab2_lib.baseboard_fab2(sch_1):page194_i56:iod20" )
			)
			( pin "J6B1.E1"
				( objectStatus "@baseboard_fab2_lib.baseboard_fab2(sch_1):page194_i56:ioe1" )
			)
			( pin "J6B1.E2"
				( objectStatus "@baseboard_fab2_lib.baseboard_fab2(sch_1):page194_i56:ioe2" )
			)
			( pin "J6B1.E3"
				( objectStatus "@baseboard_fab2_lib.baseboard_fab2(sch_1):page194_i56:ioe3" )
			)
			( pin "J6B1.E4"
				( objectStatus "@baseboard_fab2_lib.baseboard_fab2(sch_1):page194_i56:ioe4" )
			)
			( pin "J6B1.E5"
				( objectStatus "@baseboard_fab2_lib.baseboard_fab2(sch_1):page194_i56:ioe5" )
			)
			( pin "J6B1.E6"
				( objectStatus "@baseboard_fab2_lib.baseboard_fab2(sch_1):page194_i56:ioe6" )
			)
			( pin "J6B1.E7"
				( objectStatus "@baseboard_fab2_lib.baseboard_fab2(sch_1):page194_i56:ioe7" )
			)
			( pin "J6B1.E8"
				( objectStatus "@baseboard_fab2_lib.baseboard_fab2(sch_1):page194_i56:ioe8" )
			)
			( pin "J6B1.E9"
				( objectStatus "@baseboard_fab2_lib.baseboard_fab2(sch_1):page194_i56:ioe9" )
			)
			( pin "J6B1.E10"
				( objectStatus "@baseboard_fab2_lib.baseboard_fab2(sch_1):page194_i56:ioe10" )
			)
			( pin "J6B1.E11"
				( objectStatus "@baseboard_fab2_lib.baseboard_fab2(sch_1):page194_i56:ioe11" )
			)
			( pin "J6B1.E12"
				( objectStatus "@baseboard_fab2_lib.baseboard_fab2(sch_1):page194_i56:ioe12" )
			)
			( pin "J6B1.E13"
				( objectStatus "@baseboard_fab2_lib.baseboard_fab2(sch_1):page194_i56:ioe13" )
			)
			( pin "J6B1.E14"
				( objectStatus "@baseboard_fab2_lib.baseboard_fab2(sch_1):page194_i56:ioe14" )
			)
			( pin "J6B1.E15"
				( objectStatus "@baseboard_fab2_lib.baseboard_fab2(sch_1):page194_i56:ioe15" )
			)
			( pin "J6B1.E16"
				( objectStatus "@baseboard_fab2_lib.baseboard_fab2(sch_1):page194_i56:ioe16" )
			)
			( pin "J6B1.E17"
				( objectStatus "@baseboard_fab2_lib.baseboard_fab2(sch_1):page194_i56:ioe17" )
			)
			( pin "J6B1.E18"
				( objectStatus "@baseboard_fab2_lib.baseboard_fab2(sch_1):page194_i56:ioe18" )
			)
			( pin "J6B1.E19"
				( objectStatus "@baseboard_fab2_lib.baseboard_fab2(sch_1):page194_i56:ioe19" )
			)
			( pin "J6B1.E20"
				( objectStatus "@baseboard_fab2_lib.baseboard_fab2(sch_1):page194_i56:ioe20" )
			)
			( pin "J6B1.F1"
				( objectStatus "@baseboard_fab2_lib.baseboard_fab2(sch_1):page194_i56:iof1" )
			)
			( pin "J6B1.F2"
				( objectStatus "@baseboard_fab2_lib.baseboard_fab2(sch_1):page194_i56:iof2" )
			)
			( pin "J6B1.F3"
				( objectStatus "@baseboard_fab2_lib.baseboard_fab2(sch_1):page194_i56:iof3" )
			)
			( pin "J6B1.F4"
				( objectStatus "@baseboard_fab2_lib.baseboard_fab2(sch_1):page194_i56:iof4" )
			)
			( pin "J6B1.F5"
				( objectStatus "@baseboard_fab2_lib.baseboard_fab2(sch_1):page194_i56:iof5" )
			)
			( pin "J6B1.F6"
				( objectStatus "@baseboard_fab2_lib.baseboard_fab2(sch_1):page194_i56:iof6" )
			)
			( pin "J6B1.F7"
				( objectStatus "@baseboard_fab2_lib.baseboard_fab2(sch_1):page194_i56:iof7" )
			)
			( pin "J6B1.F8"
				( objectStatus "@baseboard_fab2_lib.baseboard_fab2(sch_1):page194_i56:iof8" )
			)
			( pin "J6B1.F9"
				( objectStatus "@baseboard_fab2_lib.baseboard_fab2(sch_1):page194_i56:iof9" )
			)
			( pin "J6B1.F10"
				( objectStatus "@baseboard_fab2_lib.baseboard_fab2(sch_1):page194_i56:iof10" )
			)
			( pin "J6B1.F11"
				( objectStatus "@baseboard_fab2_lib.baseboard_fab2(sch_1):page194_i56:iof11" )
			)
			( pin "J6B1.F12"
				( objectStatus "@baseboard_fab2_lib.baseboard_fab2(sch_1):page194_i56:iof12" )
			)
			( pin "J6B1.F13"
				( objectStatus "@baseboard_fab2_lib.baseboard_fab2(sch_1):page194_i56:iof13" )
			)
			( pin "J6B1.F14"
				( objectStatus "@baseboard_fab2_lib.baseboard_fab2(sch_1):page194_i56:iof14" )
			)
			( pin "J6B1.F15"
				( objectStatus "@baseboard_fab2_lib.baseboard_fab2(sch_1):page194_i56:iof15" )
			)
			( pin "J6B1.F16"
				( objectStatus "@baseboard_fab2_lib.baseboard_fab2(sch_1):page194_i56:iof16" )
			)
			( pin "J6B1.F17"
				( objectStatus "@baseboard_fab2_lib.baseboard_fab2(sch_1):page194_i56:iof17" )
			)
			( pin "J6B1.F18"
				( objectStatus "@baseboard_fab2_lib.baseboard_fab2(sch_1):page194_i56:iof18" )
			)
			( pin "J6B1.F19"
				( objectStatus "@baseboard_fab2_lib.baseboard_fab2(sch_1):page194_i56:iof19" )
			)
			( pin "J6B1.F20"
				( objectStatus "@baseboard_fab2_lib.baseboard_fab2(sch_1):page194_i56:iof20" )
			)
			( pin "C3N40.1"
				( objectStatus "@baseboard_fab2_lib.baseboard_fab2(sch_1):page194_i86:a" )
			)
			( pin "C3N40.2"
				( objectStatus "@baseboard_fab2_lib.baseboard_fab2(sch_1):page194_i86:b" )
			)
			( pin "C3M46.1"
				( objectStatus "@baseboard_fab2_lib.baseboard_fab2(sch_1):page194_i99:a" )
			)
			( pin "C3M46.2"
				( objectStatus "@baseboard_fab2_lib.baseboard_fab2(sch_1):page194_i99:b" )
			)
			( pin "C3N14.1"
				( objectStatus "@baseboard_fab2_lib.baseboard_fab2(sch_1):page194_i101:a" )
			)
			( pin "C3N14.2"
				( objectStatus "@baseboard_fab2_lib.baseboard_fab2(sch_1):page194_i101:b" )
			)
			( pin "C3T1.1"
				( objectStatus "@baseboard_fab2_lib.baseboard_fab2(sch_1):page194_i149:a" )
			)
			( pin "C3T1.2"
				( objectStatus "@baseboard_fab2_lib.baseboard_fab2(sch_1):page194_i149:b" )
			)
			( pin "C3T2.1"
				( objectStatus "@baseboard_fab2_lib.baseboard_fab2(sch_1):page194_i150:a" )
			)
			( pin "C3T2.2"
				( objectStatus "@baseboard_fab2_lib.baseboard_fab2(sch_1):page194_i150:b" )
			)
			( pin "R7C24.1"
				( objectStatus "@baseboard_fab2_lib.baseboard_fab2(sch_1):page194_i155:a" )
			)
			( pin "R7C24.2"
				( objectStatus "@baseboard_fab2_lib.baseboard_fab2(sch_1):page194_i155:b" )
			)
			( pin "R3N29.1"
				( objectStatus "@baseboard_fab2_lib.baseboard_fab2(sch_1):page194_i156:a" )
			)
			( pin "R3N29.2"
				( objectStatus "@baseboard_fab2_lib.baseboard_fab2(sch_1):page194_i156:b" )
			)
			( pin "RM1E1.1"
				( objectStatus "@baseboard_fab2_lib.baseboard_fab2(sch_1):page195_i26:io1" )
			)
			( pin "RM1E1.2"
				( objectStatus "@baseboard_fab2_lib.baseboard_fab2(sch_1):page195_i26:io2" )
			)
			( pin "RM1E1.3"
				( objectStatus "@baseboard_fab2_lib.baseboard_fab2(sch_1):page195_i26:io3" )
			)
			( pin "C9R5.1"
				( objectStatus "@baseboard_fab2_lib.baseboard_fab2(sch_1):page195_i31:a" )
			)
			( pin "C9R5.2"
				( objectStatus "@baseboard_fab2_lib.baseboard_fab2(sch_1):page195_i31:b" )
			)
			( pin "C1E12.1"
				( objectStatus "@baseboard_fab2_lib.baseboard_fab2(sch_1):page195_i32:a" )
			)
			( pin "C1E12.2"
				( objectStatus "@baseboard_fab2_lib.baseboard_fab2(sch_1):page195_i32:b" )
			)
			( pin "C1E15.1"
				( objectStatus "@baseboard_fab2_lib.baseboard_fab2(sch_1):page195_i35:a" )
			)
			( pin "C1E15.2"
				( objectStatus "@baseboard_fab2_lib.baseboard_fab2(sch_1):page195_i35:b" )
			)
			( pin "C9R12.1"
				( objectStatus "@baseboard_fab2_lib.baseboard_fab2(sch_1):page195_i36:a" )
			)
			( pin "C9R12.2"
				( objectStatus "@baseboard_fab2_lib.baseboard_fab2(sch_1):page195_i36:b" )
			)
			( pin "C9R6.1"
				( objectStatus "@baseboard_fab2_lib.baseboard_fab2(sch_1):page195_i37:a" )
			)
			( pin "C9R6.2"
				( objectStatus "@baseboard_fab2_lib.baseboard_fab2(sch_1):page195_i37:b" )
			)
			( pin "C1E17.1"
				( objectStatus "@baseboard_fab2_lib.baseboard_fab2(sch_1):page195_i38:a" )
			)
			( pin "C1E17.2"
				( objectStatus "@baseboard_fab2_lib.baseboard_fab2(sch_1):page195_i38:b" )
			)
			( pin "C1E16.1"
				( objectStatus "@baseboard_fab2_lib.baseboard_fab2(sch_1):page195_i39:a" )
			)
			( pin "C1E16.2"
				( objectStatus "@baseboard_fab2_lib.baseboard_fab2(sch_1):page195_i39:b" )
			)
			( pin "TH4G1.1"
				( objectStatus "@baseboard_fab2_lib.baseboard_fab2(sch_1):page195_i49:\1\" )
			)
			( pin "TH9G1.1"
				( objectStatus "@baseboard_fab2_lib.baseboard_fab2(sch_1):page195_i52:\1\" )
			)
			( pin "TH9A1.1"
				( objectStatus "@baseboard_fab2_lib.baseboard_fab2(sch_1):page195_i54:\1\" )
			)
			( pin "TH1A1.1"
				( objectStatus "@baseboard_fab2_lib.baseboard_fab2(sch_1):page195_i56:\1\" )
			)
			( pin "TH4A1.1"
				( objectStatus "@baseboard_fab2_lib.baseboard_fab2(sch_1):page195_i62:\1\" )
			)
			( pin "TH7A1.1"
				( objectStatus "@baseboard_fab2_lib.baseboard_fab2(sch_1):page195_i65:\1\" )
			)
			( pin "TH7G1.1"
				( objectStatus "@baseboard_fab2_lib.baseboard_fab2(sch_1):page195_i67:\1\" )
			)
			( pin "C4F6.1"
				( objectStatus "@baseboard_fab2_lib.baseboard_fab2(sch_1):page195_i82:a" )
			)
			( pin "C4F6.2"
				( objectStatus "@baseboard_fab2_lib.baseboard_fab2(sch_1):page195_i82:b" )
			)
			( pin "C4B13.1"
				( objectStatus "@baseboard_fab2_lib.baseboard_fab2(sch_1):page195_i83:a" )
			)
			( pin "C4B13.2"
				( objectStatus "@baseboard_fab2_lib.baseboard_fab2(sch_1):page195_i83:b" )
			)
			( pin "C1B14.1"
				( objectStatus "@baseboard_fab2_lib.baseboard_fab2(sch_1):page195_i84:a" )
			)
			( pin "C1B14.2"
				( objectStatus "@baseboard_fab2_lib.baseboard_fab2(sch_1):page195_i84:b" )
			)
			( pin "C1F7.1"
				( objectStatus "@baseboard_fab2_lib.baseboard_fab2(sch_1):page195_i85:a" )
			)
			( pin "C1F7.2"
				( objectStatus "@baseboard_fab2_lib.baseboard_fab2(sch_1):page195_i85:b" )
			)
			( pin "C4F5.1"
				( objectStatus "@baseboard_fab2_lib.baseboard_fab2(sch_1):page195_i96:a" )
			)
			( pin "C4F5.2"
				( objectStatus "@baseboard_fab2_lib.baseboard_fab2(sch_1):page195_i96:b" )
			)
			( pin "C4B14.1"
				( objectStatus "@baseboard_fab2_lib.baseboard_fab2(sch_1):page195_i97:a" )
			)
			( pin "C4B14.2"
				( objectStatus "@baseboard_fab2_lib.baseboard_fab2(sch_1):page195_i97:b" )
			)
			( pin "C3T6.1"
				( objectStatus "@baseboard_fab2_lib.baseboard_fab2(sch_1):page195_i98:a" )
			)
			( pin "C3T6.2"
				( objectStatus "@baseboard_fab2_lib.baseboard_fab2(sch_1):page195_i98:b" )
			)
			( pin "C9M3.1"
				( objectStatus "@baseboard_fab2_lib.baseboard_fab2(sch_1):page195_i99:a" )
			)
			( pin "C9M3.2"
				( objectStatus "@baseboard_fab2_lib.baseboard_fab2(sch_1):page195_i99:b" )
			)
			( pin "C3B6.1"
				( objectStatus "@baseboard_fab2_lib.baseboard_fab2(sch_1):page195_i100:a" )
			)
			( pin "C3B6.2"
				( objectStatus "@baseboard_fab2_lib.baseboard_fab2(sch_1):page195_i100:b" )
			)
			( pin "C1R23.1"
				( objectStatus "@baseboard_fab2_lib.baseboard_fab2(sch_1):page195_i101:a" )
			)
			( pin "C1R23.2"
				( objectStatus "@baseboard_fab2_lib.baseboard_fab2(sch_1):page195_i101:b" )
			)
			( pin "C4M6.1"
				( objectStatus "@baseboard_fab2_lib.baseboard_fab2(sch_1):page195_i102:a" )
			)
			( pin "C4M6.2"
				( objectStatus "@baseboard_fab2_lib.baseboard_fab2(sch_1):page195_i102:b" )
			)
			( pin "C1M5.1"
				( objectStatus "@baseboard_fab2_lib.baseboard_fab2(sch_1):page195_i103:a" )
			)
			( pin "C1M5.2"
				( objectStatus "@baseboard_fab2_lib.baseboard_fab2(sch_1):page195_i103:b" )
			)
			( pin "C3T13.1"
				( objectStatus "@baseboard_fab2_lib.baseboard_fab2(sch_1):page195_i104:a" )
			)
			( pin "C3T13.2"
				( objectStatus "@baseboard_fab2_lib.baseboard_fab2(sch_1):page195_i104:b" )
			)
			( pin "C4M7.1"
				( objectStatus "@baseboard_fab2_lib.baseboard_fab2(sch_1):page195_i105:a" )
			)
			( pin "C4M7.2"
				( objectStatus "@baseboard_fab2_lib.baseboard_fab2(sch_1):page195_i105:b" )
			)
			( pin "C3T15.1"
				( objectStatus "@baseboard_fab2_lib.baseboard_fab2(sch_1):page195_i106:a" )
			)
			( pin "C3T15.2"
				( objectStatus "@baseboard_fab2_lib.baseboard_fab2(sch_1):page195_i106:b" )
			)
			( pin "C7M6.1"
				( objectStatus "@baseboard_fab2_lib.baseboard_fab2(sch_1):page195_i108:a" )
			)
			( pin "C7M6.2"
				( objectStatus "@baseboard_fab2_lib.baseboard_fab2(sch_1):page195_i108:b" )
			)
			( pin "C6N5.1"
				( objectStatus "@baseboard_fab2_lib.baseboard_fab2(sch_1):page195_i109:a" )
			)
			( pin "C6N5.2"
				( objectStatus "@baseboard_fab2_lib.baseboard_fab2(sch_1):page195_i109:b" )
			)
			( pin "C9T3.1"
				( objectStatus "@baseboard_fab2_lib.baseboard_fab2(sch_1):page195_i111:a" )
			)
			( pin "C9T3.2"
				( objectStatus "@baseboard_fab2_lib.baseboard_fab2(sch_1):page195_i111:b" )
			)
			( pin "C4F4.1"
				( objectStatus "@baseboard_fab2_lib.baseboard_fab2(sch_1):page195_i112:a" )
			)
			( pin "C4F4.2"
				( objectStatus "@baseboard_fab2_lib.baseboard_fab2(sch_1):page195_i112:b" )
			)
			( pin "C3T3.1"
				( objectStatus "@baseboard_fab2_lib.baseboard_fab2(sch_1):page195_i113:a" )
			)
			( pin "C3T3.2"
				( objectStatus "@baseboard_fab2_lib.baseboard_fab2(sch_1):page195_i113:b" )
			)
			( pin "R2U43.1"
				( objectStatus "@baseboard_fab2_lib.baseboard_fab2(sch_1):page196_i46:a" )
			)
			( pin "R2U43.2"
				( objectStatus "@baseboard_fab2_lib.baseboard_fab2(sch_1):page196_i46:b" )
			)
			( pin "XBT8G1.3"
				( objectStatus "@baseboard_fab2_lib.baseboard_fab2(sch_1):page196_i51:n" )
			)
			( pin "XBT8G1.1"
				( objectStatus "@baseboard_fab2_lib.baseboard_fab2(sch_1):page196_i51:p1" )
			)
			( pin "XBT8G1.2"
				( objectStatus "@baseboard_fab2_lib.baseboard_fab2(sch_1):page196_i51:p2" )
			)
			( pin "CR2U1.1"
				( objectStatus "@baseboard_fab2_lib.baseboard_fab2(sch_1):page196_i53:a1" )
			)
			( pin "CR2U1.2"
				( objectStatus "@baseboard_fab2_lib.baseboard_fab2(sch_1):page196_i53:a2" )
			)
			( pin "CR2U1.3"
				( objectStatus "@baseboard_fab2_lib.baseboard_fab2(sch_1):page196_i53:c" )
			)
			( pin "R3P44.1"
				( objectStatus "@baseboard_fab2_lib.baseboard_fab2(sch_1):page196_i59:a" )
			)
			( pin "R3P44.2"
				( objectStatus "@baseboard_fab2_lib.baseboard_fab2(sch_1):page196_i59:b" )
			)
			( pin "C3P45.1"
				( objectStatus "@baseboard_fab2_lib.baseboard_fab2(sch_1):page196_i60:a" )
			)
			( pin "C3P45.2"
				( objectStatus "@baseboard_fab2_lib.baseboard_fab2(sch_1):page196_i60:b" )
			)
			( pin "R2P20.1"
				( objectStatus "@baseboard_fab2_lib.baseboard_fab2(sch_1):page196_i65:a" )
			)
			( pin "R2P20.2"
				( objectStatus "@baseboard_fab2_lib.baseboard_fab2(sch_1):page196_i65:b" )
			)
			( pin "R1L16.1"
				( objectStatus "@baseboard_fab2_lib.baseboard_fab2(sch_1):page196_i68:a" )
			)
			( pin "R1L16.2"
				( objectStatus "@baseboard_fab2_lib.baseboard_fab2(sch_1):page196_i68:b" )
			)
			( pin "U7D3.5"
				( objectStatus "@baseboard_fab2_lib.baseboard_fab2(sch_1):page196_i70:cext" )
			)
			( pin "U7D3.1"
				( objectStatus "@baseboard_fab2_lib.baseboard_fab2(sch_1):page196_i70:enin" )
			)
			( pin "U7D3.4"
				( objectStatus "@baseboard_fab2_lib.baseboard_fab2(sch_1):page196_i70:enout" )
			)
			( pin "U7D3.2"
				( objectStatus "@baseboard_fab2_lib.baseboard_fab2(sch_1):page196_i70:gnd" )
			)
			( pin "U7D3.6"
				( objectStatus "@baseboard_fab2_lib.baseboard_fab2(sch_1):page196_i70:vcc" )
			)
			( pin "U7D3.3"
				( objectStatus "@baseboard_fab2_lib.baseboard_fab2(sch_1):page196_i70:vin" )
			)
			( pin "R3P50.1"
				( objectStatus "@baseboard_fab2_lib.baseboard_fab2(sch_1):page196_i71:a" )
			)
			( pin "R3P50.2"
				( objectStatus "@baseboard_fab2_lib.baseboard_fab2(sch_1):page196_i71:b" )
			)
			( pin "C3P46.1"
				( objectStatus "@baseboard_fab2_lib.baseboard_fab2(sch_1):page196_i72:a" )
			)
			( pin "C3P46.2"
				( objectStatus "@baseboard_fab2_lib.baseboard_fab2(sch_1):page196_i72:b" )
			)
			( pin "R3P48.1"
				( objectStatus "@baseboard_fab2_lib.baseboard_fab2(sch_1):page196_i74:a" )
			)
			( pin "R3P48.2"
				( objectStatus "@baseboard_fab2_lib.baseboard_fab2(sch_1):page196_i74:b" )
			)
			( pin "R3P51.1"
				( objectStatus "@baseboard_fab2_lib.baseboard_fab2(sch_1):page196_i75:a" )
			)
			( pin "R3P51.2"
				( objectStatus "@baseboard_fab2_lib.baseboard_fab2(sch_1):page196_i75:b" )
			)
			( pin "U1L3.2"
				( objectStatus "@baseboard_fab2_lib.baseboard_fab2(sch_1):page196_i80:reset_n" )
			)
			( pin "U1L3.3"
				( objectStatus "@baseboard_fab2_lib.baseboard_fab2(sch_1):page196_i80:vcc" )
			)
			( pin "C1L16.1"
				( objectStatus "@baseboard_fab2_lib.baseboard_fab2(sch_1):page196_i81:a" )
			)
			( pin "C1L16.2"
				( objectStatus "@baseboard_fab2_lib.baseboard_fab2(sch_1):page196_i81:b" )
			)
			( pin "U8E2.2"
				( objectStatus "@baseboard_fab2_lib.baseboard_fab2(sch_1):page196_i89:reset_n" )
			)
			( pin "U8E2.3"
				( objectStatus "@baseboard_fab2_lib.baseboard_fab2(sch_1):page196_i89:vcc" )
			)
			( pin "R8E7.1"
				( objectStatus "@baseboard_fab2_lib.baseboard_fab2(sch_1):page196_i90:a" )
			)
			( pin "R8E7.2"
				( objectStatus "@baseboard_fab2_lib.baseboard_fab2(sch_1):page196_i90:b" )
			)
			( pin "C8E3.1"
				( objectStatus "@baseboard_fab2_lib.baseboard_fab2(sch_1):page196_i94:a" )
			)
			( pin "C8E3.2"
				( objectStatus "@baseboard_fab2_lib.baseboard_fab2(sch_1):page196_i94:b" )
			)
			( pin "C2U26.1"
				( objectStatus "@baseboard_fab2_lib.baseboard_fab2(sch_1):page196_i102:a" )
			)
			( pin "C2U26.2"
				( objectStatus "@baseboard_fab2_lib.baseboard_fab2(sch_1):page196_i102:b" )
			)
			( pin "CR7E1.2"
				( objectStatus "@baseboard_fab2_lib.baseboard_fab2(sch_1):page196_i103:a" )
			)
			( pin "CR7E1.1"
				( objectStatus "@baseboard_fab2_lib.baseboard_fab2(sch_1):page196_i103:c" )
			)
			( pin "U8D8.5"
				( objectStatus "@baseboard_fab2_lib.baseboard_fab2(sch_1):page196_i104:gnd" )
			)
			( pin "U8D8.4"
				( objectStatus "@baseboard_fab2_lib.baseboard_fab2(sch_1):page196_i104:inap" )
			)
			( pin "U8D8.3"
				( objectStatus "@baseboard_fab2_lib.baseboard_fab2(sch_1):page196_i104:inbn" )
			)
			( pin "U8D8.6"
				( objectStatus "@baseboard_fab2_lib.baseboard_fab2(sch_1):page196_i104:outa" )
			)
			( pin "U8D8.1"
				( objectStatus "@baseboard_fab2_lib.baseboard_fab2(sch_1):page196_i104:outb" )
			)
			( pin "U8D8.2"
				( objectStatus "@baseboard_fab2_lib.baseboard_fab2(sch_1):page196_i104:vdd" )
			)
			( pin "C8D4.1"
				( objectStatus "@baseboard_fab2_lib.baseboard_fab2(sch_1):page196_i105:a" )
			)
			( pin "C8D4.2"
				( objectStatus "@baseboard_fab2_lib.baseboard_fab2(sch_1):page196_i105:b" )
			)
			( pin "R8D42.1"
				( objectStatus "@baseboard_fab2_lib.baseboard_fab2(sch_1):page196_i106:a" )
			)
			( pin "R8D42.2"
				( objectStatus "@baseboard_fab2_lib.baseboard_fab2(sch_1):page196_i106:b" )
			)
			( pin "R8D38.1"
				( objectStatus "@baseboard_fab2_lib.baseboard_fab2(sch_1):page196_i112:a" )
			)
			( pin "R8D38.2"
				( objectStatus "@baseboard_fab2_lib.baseboard_fab2(sch_1):page196_i112:b" )
			)
			( pin "R9P9.1"
				( objectStatus "@baseboard_fab2_lib.baseboard_fab2(sch_1):page200_i251:a" )
			)
			( pin "R9P9.2"
				( objectStatus "@baseboard_fab2_lib.baseboard_fab2(sch_1):page200_i251:b" )
			)
			( pin "R8D39.1"
				( objectStatus "@baseboard_fab2_lib.baseboard_fab2(sch_1):page196_i114:a" )
			)
			( pin "R8D39.2"
				( objectStatus "@baseboard_fab2_lib.baseboard_fab2(sch_1):page196_i114:b" )
			)
			( pin "R8D37.1"
				( objectStatus "@baseboard_fab2_lib.baseboard_fab2(sch_1):page196_i115:a" )
			)
			( pin "R8D37.2"
				( objectStatus "@baseboard_fab2_lib.baseboard_fab2(sch_1):page196_i115:b" )
			)
			( pin "R8D41.1"
				( objectStatus "@baseboard_fab2_lib.baseboard_fab2(sch_1):page196_i120:a" )
			)
			( pin "R8D41.2"
				( objectStatus "@baseboard_fab2_lib.baseboard_fab2(sch_1):page196_i120:b" )
			)
			( pin "R2P18.1"
				( objectStatus "@baseboard_fab2_lib.baseboard_fab2(sch_1):page196_i121:a" )
			)
			( pin "R2P18.2"
				( objectStatus "@baseboard_fab2_lib.baseboard_fab2(sch_1):page196_i121:b" )
			)
			( pin "R2P21.1"
				( objectStatus "@baseboard_fab2_lib.baseboard_fab2(sch_1):page196_i122:a" )
			)
			( pin "R2P21.2"
				( objectStatus "@baseboard_fab2_lib.baseboard_fab2(sch_1):page196_i122:b" )
			)
			( pin "Q7D1.3"
				( objectStatus "@baseboard_fab2_lib.baseboard_fab2(sch_1):page134_i14:drn" )
			)
			( pin "Q7D1.1"
				( objectStatus "@baseboard_fab2_lib.baseboard_fab2(sch_1):page134_i14:gate" )
			)
			( pin "Q7D1.2"
				( objectStatus "@baseboard_fab2_lib.baseboard_fab2(sch_1):page134_i14:src" )
			)
			( pin "CR8E1.2"
				( objectStatus "@baseboard_fab2_lib.baseboard_fab2(sch_1):page196_i128:a" )
			)
			( pin "CR8E1.1"
				( objectStatus "@baseboard_fab2_lib.baseboard_fab2(sch_1):page196_i128:c" )
			)
			( pin "EU2T1.5"
				( objectStatus "@baseboard_fab2_lib.baseboard_fab2(sch_1):page198_i1:d" )
			)
			( pin "EU2T1.7"
				( objectStatus "@baseboard_fab2_lib.baseboard_fab2(sch_1):page198_i1:g" )
			)
			( pin "EU2T1.4"
				( objectStatus "@baseboard_fab2_lib.baseboard_fab2(sch_1):page198_i1:gnd" )
			)
			( pin "EU2T1.2"
				( objectStatus "@baseboard_fab2_lib.baseboard_fab2(sch_1):page198_i1:\on\" )
			)
			( pin "EU2T1.8"
				( objectStatus "@baseboard_fab2_lib.baseboard_fab2(sch_1):page198_i1:pg" )
			)
			( pin "EU2T1.6"
				( objectStatus "@baseboard_fab2_lib.baseboard_fab2(sch_1):page198_i1:s" )
			)
			( pin "EU2T1.3"
				( objectStatus "@baseboard_fab2_lib.baseboard_fab2(sch_1):page198_i1:shdn_n" )
			)
			( pin "EU2T1.9"
				( objectStatus "@baseboard_fab2_lib.baseboard_fab2(sch_1):page198_i1:thpad" )
			)
			( pin "EU2T1.1"
				( objectStatus "@baseboard_fab2_lib.baseboard_fab2(sch_1):page198_i1:vcc" )
			)
			( pin "EU8B1.5"
				( objectStatus "@baseboard_fab2_lib.baseboard_fab2(sch_1):page198_i13:d" )
			)
			( pin "EU8B1.7"
				( objectStatus "@baseboard_fab2_lib.baseboard_fab2(sch_1):page198_i13:g" )
			)
			( pin "EU8B1.4"
				( objectStatus "@baseboard_fab2_lib.baseboard_fab2(sch_1):page198_i13:gnd" )
			)
			( pin "EU8B1.2"
				( objectStatus "@baseboard_fab2_lib.baseboard_fab2(sch_1):page198_i13:\on\" )
			)
			( pin "EU8B1.8"
				( objectStatus "@baseboard_fab2_lib.baseboard_fab2(sch_1):page198_i13:pg" )
			)
			( pin "EU8B1.6"
				( objectStatus "@baseboard_fab2_lib.baseboard_fab2(sch_1):page198_i13:s" )
			)
			( pin "EU8B1.3"
				( objectStatus "@baseboard_fab2_lib.baseboard_fab2(sch_1):page198_i13:shdn_n" )
			)
			( pin "EU8B1.9"
				( objectStatus "@baseboard_fab2_lib.baseboard_fab2(sch_1):page198_i13:thpad" )
			)
			( pin "EU8B1.1"
				( objectStatus "@baseboard_fab2_lib.baseboard_fab2(sch_1):page198_i13:vcc" )
			)
			( pin "EU7E1.5"
				( objectStatus "@baseboard_fab2_lib.baseboard_fab2(sch_1):page198_i19:d" )
			)
			( pin "EU7E1.7"
				( objectStatus "@baseboard_fab2_lib.baseboard_fab2(sch_1):page198_i19:g" )
			)
			( pin "EU7E1.4"
				( objectStatus "@baseboard_fab2_lib.baseboard_fab2(sch_1):page198_i19:gnd" )
			)
			( pin "EU7E1.2"
				( objectStatus "@baseboard_fab2_lib.baseboard_fab2(sch_1):page198_i19:\on\" )
			)
			( pin "EU7E1.8"
				( objectStatus "@baseboard_fab2_lib.baseboard_fab2(sch_1):page198_i19:pg" )
			)
			( pin "EU7E1.6"
				( objectStatus "@baseboard_fab2_lib.baseboard_fab2(sch_1):page198_i19:s" )
			)
			( pin "EU7E1.3"
				( objectStatus "@baseboard_fab2_lib.baseboard_fab2(sch_1):page198_i19:shdn_n" )
			)
			( pin "EU7E1.9"
				( objectStatus "@baseboard_fab2_lib.baseboard_fab2(sch_1):page198_i19:thpad" )
			)
			( pin "EU7E1.1"
				( objectStatus "@baseboard_fab2_lib.baseboard_fab2(sch_1):page198_i19:vcc" )
			)
			( pin "C8F17.1"
				( objectStatus "@baseboard_fab2_lib.baseboard_fab2(sch_1):page198_i24:a" )
			)
			( pin "C8F17.2"
				( objectStatus "@baseboard_fab2_lib.baseboard_fab2(sch_1):page198_i24:b" )
			)
			( pin "C8B8.1"
				( objectStatus "@baseboard_fab2_lib.baseboard_fab2(sch_1):page198_i26:a" )
			)
			( pin "C8B8.2"
				( objectStatus "@baseboard_fab2_lib.baseboard_fab2(sch_1):page198_i26:b" )
			)
			( pin "C8E19.1"
				( objectStatus "@baseboard_fab2_lib.baseboard_fab2(sch_1):page198_i28:a" )
			)
			( pin "C8E19.2"
				( objectStatus "@baseboard_fab2_lib.baseboard_fab2(sch_1):page198_i28:b" )
			)
			( pin "C8B5.1"
				( objectStatus "@baseboard_fab2_lib.baseboard_fab2(sch_1):page198_i37:a" )
			)
			( pin "C8B5.2"
				( objectStatus "@baseboard_fab2_lib.baseboard_fab2(sch_1):page198_i37:b" )
			)
			( pin "C8B12.1"
				( objectStatus "@baseboard_fab2_lib.baseboard_fab2(sch_1):page198_i38:a" )
			)
			( pin "C8B12.2"
				( objectStatus "@baseboard_fab2_lib.baseboard_fab2(sch_1):page198_i38:b" )
			)
			( pin "C8B6.1"
				( objectStatus "@baseboard_fab2_lib.baseboard_fab2(sch_1):page198_i40:a" )
			)
			( pin "C8B6.2"
				( objectStatus "@baseboard_fab2_lib.baseboard_fab2(sch_1):page198_i40:b" )
			)
			( pin "C8B7.1"
				( objectStatus "@baseboard_fab2_lib.baseboard_fab2(sch_1):page198_i41:a" )
			)
			( pin "C8B7.2"
				( objectStatus "@baseboard_fab2_lib.baseboard_fab2(sch_1):page198_i41:b" )
			)
			( pin "C2T36.1"
				( objectStatus "@baseboard_fab2_lib.baseboard_fab2(sch_1):page198_i43:a" )
			)
			( pin "C2T36.2"
				( objectStatus "@baseboard_fab2_lib.baseboard_fab2(sch_1):page198_i43:b" )
			)
			( pin "C2U1.1"
				( objectStatus "@baseboard_fab2_lib.baseboard_fab2(sch_1):page198_i44:a" )
			)
			( pin "C2U1.2"
				( objectStatus "@baseboard_fab2_lib.baseboard_fab2(sch_1):page198_i44:b" )
			)
			( pin "C2U19.1"
				( objectStatus "@baseboard_fab2_lib.baseboard_fab2(sch_1):page198_i46:a" )
			)
			( pin "C2U19.2"
				( objectStatus "@baseboard_fab2_lib.baseboard_fab2(sch_1):page198_i46:b" )
			)
			( pin "C2U2.1"
				( objectStatus "@baseboard_fab2_lib.baseboard_fab2(sch_1):page198_i47:a" )
			)
			( pin "C2U2.2"
				( objectStatus "@baseboard_fab2_lib.baseboard_fab2(sch_1):page198_i47:b" )
			)
			( pin "C7E9.1"
				( objectStatus "@baseboard_fab2_lib.baseboard_fab2(sch_1):page198_i49:a" )
			)
			( pin "C7E9.2"
				( objectStatus "@baseboard_fab2_lib.baseboard_fab2(sch_1):page198_i49:b" )
			)
			( pin "C7E8.1"
				( objectStatus "@baseboard_fab2_lib.baseboard_fab2(sch_1):page198_i50:a" )
			)
			( pin "C7E8.2"
				( objectStatus "@baseboard_fab2_lib.baseboard_fab2(sch_1):page198_i50:b" )
			)
			( pin "C7E5.1"
				( objectStatus "@baseboard_fab2_lib.baseboard_fab2(sch_1):page198_i52:a" )
			)
			( pin "C7E5.2"
				( objectStatus "@baseboard_fab2_lib.baseboard_fab2(sch_1):page198_i52:b" )
			)
			( pin "C7E6.1"
				( objectStatus "@baseboard_fab2_lib.baseboard_fab2(sch_1):page198_i53:a" )
			)
			( pin "C7E6.2"
				( objectStatus "@baseboard_fab2_lib.baseboard_fab2(sch_1):page198_i53:b" )
			)
			( pin "C1B18.1"
				( objectStatus "@baseboard_fab2_lib.baseboard_fab2(sch_1):page198_i61:a" )
			)
			( pin "C1B18.2"
				( objectStatus "@baseboard_fab2_lib.baseboard_fab2(sch_1):page198_i61:b" )
			)
			( pin "C1B19.1"
				( objectStatus "@baseboard_fab2_lib.baseboard_fab2(sch_1):page198_i64:a" )
			)
			( pin "C1B19.2"
				( objectStatus "@baseboard_fab2_lib.baseboard_fab2(sch_1):page198_i64:b" )
			)
			( pin "C9M6.1"
				( objectStatus "@baseboard_fab2_lib.baseboard_fab2(sch_1):page198_i67:a" )
			)
			( pin "C9M6.2"
				( objectStatus "@baseboard_fab2_lib.baseboard_fab2(sch_1):page198_i67:b" )
			)
			( pin "EU9M1.5"
				( objectStatus "@baseboard_fab2_lib.baseboard_fab2(sch_1):page198_i69:d" )
			)
			( pin "EU9M1.7"
				( objectStatus "@baseboard_fab2_lib.baseboard_fab2(sch_1):page198_i69:g" )
			)
			( pin "EU9M1.4"
				( objectStatus "@baseboard_fab2_lib.baseboard_fab2(sch_1):page198_i69:gnd" )
			)
			( pin "EU9M1.2"
				( objectStatus "@baseboard_fab2_lib.baseboard_fab2(sch_1):page198_i69:\on\" )
			)
			( pin "EU9M1.8"
				( objectStatus "@baseboard_fab2_lib.baseboard_fab2(sch_1):page198_i69:pg" )
			)
			( pin "EU9M1.6"
				( objectStatus "@baseboard_fab2_lib.baseboard_fab2(sch_1):page198_i69:s" )
			)
			( pin "EU9M1.3"
				( objectStatus "@baseboard_fab2_lib.baseboard_fab2(sch_1):page198_i69:shdn_n" )
			)
			( pin "EU9M1.9"
				( objectStatus "@baseboard_fab2_lib.baseboard_fab2(sch_1):page198_i69:thpad" )
			)
			( pin "EU9M1.1"
				( objectStatus "@baseboard_fab2_lib.baseboard_fab2(sch_1):page198_i69:vcc" )
			)
			( pin "C9M10.1"
				( objectStatus "@baseboard_fab2_lib.baseboard_fab2(sch_1):page198_i74:a" )
			)
			( pin "C9M10.2"
				( objectStatus "@baseboard_fab2_lib.baseboard_fab2(sch_1):page198_i74:b" )
			)
			( pin "C9M9.1"
				( objectStatus "@baseboard_fab2_lib.baseboard_fab2(sch_1):page198_i76:a" )
			)
			( pin "C9M9.2"
				( objectStatus "@baseboard_fab2_lib.baseboard_fab2(sch_1):page198_i76:b" )
			)
			( pin "R8E12.1"
				( objectStatus "@baseboard_fab2_lib.baseboard_fab2(sch_1):page198_i78:a" )
			)
			( pin "R8E12.2"
				( objectStatus "@baseboard_fab2_lib.baseboard_fab2(sch_1):page198_i78:b" )
			)
			( pin "R8B4.1"
				( objectStatus "@baseboard_fab2_lib.baseboard_fab2(sch_1):page198_i83:a" )
			)
			( pin "R8B4.2"
				( objectStatus "@baseboard_fab2_lib.baseboard_fab2(sch_1):page198_i83:b" )
			)
			( pin "Q8G1.5"
				( objectStatus "@baseboard_fab2_lib.baseboard_fab2(sch_1):page198_i85:drn" )
			)
			( pin "Q8G1.4"
				( objectStatus "@baseboard_fab2_lib.baseboard_fab2(sch_1):page198_i85:gate" )
			)
			( pin "Q8G1.1"
				( objectStatus "@baseboard_fab2_lib.baseboard_fab2(sch_1):page198_i85:src" )
			)
			( pin "Q1B1.5"
				( objectStatus "@baseboard_fab2_lib.baseboard_fab2(sch_1):page198_i86:drn" )
			)
			( pin "Q1B1.4"
				( objectStatus "@baseboard_fab2_lib.baseboard_fab2(sch_1):page198_i86:gate" )
			)
			( pin "Q1B1.1"
				( objectStatus "@baseboard_fab2_lib.baseboard_fab2(sch_1):page198_i86:src" )
			)
			( pin "Q8B1.5"
				( objectStatus "@baseboard_fab2_lib.baseboard_fab2(sch_1):page198_i87:drn" )
			)
			( pin "Q8B1.4"
				( objectStatus "@baseboard_fab2_lib.baseboard_fab2(sch_1):page198_i87:gate" )
			)
			( pin "Q8B1.1"
				( objectStatus "@baseboard_fab2_lib.baseboard_fab2(sch_1):page198_i87:src" )
			)
			( pin "Q7E7.5"
				( objectStatus "@baseboard_fab2_lib.baseboard_fab2(sch_1):page198_i88:drn" )
			)
			( pin "Q7E7.4"
				( objectStatus "@baseboard_fab2_lib.baseboard_fab2(sch_1):page198_i88:gate" )
			)
			( pin "Q7E7.1"
				( objectStatus "@baseboard_fab2_lib.baseboard_fab2(sch_1):page198_i88:src" )
			)
			( pin "R9P30.1"
				( objectStatus "@baseboard_fab2_lib.baseboard_fab2(sch_1):page199_i2:a" )
			)
			( pin "R9P30.2"
				( objectStatus "@baseboard_fab2_lib.baseboard_fab2(sch_1):page199_i2:b" )
			)
			( pin "C1D25.1"
				( objectStatus "@baseboard_fab2_lib.baseboard_fab2(sch_1):page199_i3:a" )
			)
			( pin "C1D25.2"
				( objectStatus "@baseboard_fab2_lib.baseboard_fab2(sch_1):page199_i3:b" )
			)
			( pin "C1D27.1"
				( objectStatus "@baseboard_fab2_lib.baseboard_fab2(sch_1):page199_i7:a" )
			)
			( pin "C1D27.2"
				( objectStatus "@baseboard_fab2_lib.baseboard_fab2(sch_1):page199_i7:b" )
			)
			( pin "R1D43.1"
				( objectStatus "@baseboard_fab2_lib.baseboard_fab2(sch_1):page199_i9:a" )
			)
			( pin "R1D43.2"
				( objectStatus "@baseboard_fab2_lib.baseboard_fab2(sch_1):page199_i9:b" )
			)
			( pin "EU1D2.7"
				( objectStatus "@baseboard_fab2_lib.baseboard_fab2(sch_1):page199_i10:adr1" )
			)
			( pin "EU1D2.8"
				( objectStatus "@baseboard_fab2_lib.baseboard_fab2(sch_1):page199_i10:adr2" )
			)
			( pin "EU1D2.19"
				( objectStatus "@baseboard_fab2_lib.baseboard_fab2(sch_1):page199_i10:csout" )
			)
			( pin "EU1D2.12"
				( objectStatus "@baseboard_fab2_lib.baseboard_fab2(sch_1):page199_i10:enable" )
			)
			( pin "EU1D2.33"
				( objectStatus "@baseboard_fab2_lib.baseboard_fab2(sch_1):page199_i10:ep" )
			)
			( pin "EU1D2.6"
				( objectStatus "@baseboard_fab2_lib.baseboard_fab2(sch_1):page199_i10:fault_n" )
			)
			( pin "EU1D2.24"
				( objectStatus "@baseboard_fab2_lib.baseboard_fab2(sch_1):page199_i10:gate" )
			)
			( pin "EU1D2.22"
				( objectStatus "@baseboard_fab2_lib.baseboard_fab2(sch_1):page199_i10:gnd" )
			)
			( pin "EU1D2.13"
				( objectStatus "@baseboard_fab2_lib.baseboard_fab2(sch_1):page199_i10:gpo1_alert1_n_conv" )
			)
			( pin "EU1D2.14"
				( objectStatus "@baseboard_fab2_lib.baseboard_fab2(sch_1):page199_i10:gpo2_alert2_n" )
			)
			( pin "EU1D2.27"
				( objectStatus "@baseboard_fab2_lib.baseboard_fab2(sch_1):page199_i10:hsn" )
			)
			( pin "EU1D2.28"
				( objectStatus "@baseboard_fab2_lib.baseboard_fab2(sch_1):page199_i10:hsp" )
			)
			( pin "EU1D2.3"
				( objectStatus "@baseboard_fab2_lib.baseboard_fab2(sch_1):page199_i10:iset" )
			)
			( pin "EU1D2.4"
				( objectStatus "@baseboard_fab2_lib.baseboard_fab2(sch_1):page199_i10:istart" )
			)
			( pin "EU1D2.10"
				( objectStatus "@baseboard_fab2_lib.baseboard_fab2(sch_1):page199_i10:mclk" )
			)
			( pin "EU1D2.11"
				( objectStatus "@baseboard_fab2_lib.baseboard_fab2(sch_1):page199_i10:mdat" )
			)
			( pin "EU1D2.26"
				( objectStatus "@baseboard_fab2_lib.baseboard_fab2(sch_1):page199_i10:mon" )
			)
			( pin "EU1D2.29"
				( objectStatus "@baseboard_fab2_lib.baseboard_fab2(sch_1):page199_i10:mop" )
			)
			( pin "EU1D2.32"
				( objectStatus "@baseboard_fab2_lib.baseboard_fab2(sch_1):page199_i10:ov" )
			)
			( pin "EU1D2.23"
				( objectStatus "@baseboard_fab2_lib.baseboard_fab2(sch_1):page199_i10:pgnd" )
			)
			( pin "EU1D2.1"
				( objectStatus "@baseboard_fab2_lib.baseboard_fab2(sch_1):page199_i10:pset" )
			)
			( pin "EU1D2.21"
				( objectStatus "@baseboard_fab2_lib.baseboard_fab2(sch_1):page199_i10:pwgin" )
			)
			( pin "EU1D2.18"
				( objectStatus "@baseboard_fab2_lib.baseboard_fab2(sch_1):page199_i10:pwrgd" )
			)
			( pin "EU1D2.17"
				( objectStatus "@baseboard_fab2_lib.baseboard_fab2(sch_1):page199_i10:retry_n" )
			)
			( pin "EU1D2.16"
				( objectStatus "@baseboard_fab2_lib.baseboard_fab2(sch_1):page199_i10:scl" )
			)
			( pin "EU1D2.15"
				( objectStatus "@baseboard_fab2_lib.baseboard_fab2(sch_1):page199_i10:sda" )
			)
			( pin "EU1D2.9"
				( objectStatus "@baseboard_fab2_lib.baseboard_fab2(sch_1):page199_i10:spiss_n" )
			)
			( pin "EU1D2.25"
				( objectStatus "@baseboard_fab2_lib.baseboard_fab2(sch_1):page199_i10:temp" )
			)
			( pin "EU1D2.5"
				( objectStatus "@baseboard_fab2_lib.baseboard_fab2(sch_1):page199_i10:timer" )
			)
			( pin "EU1D2.31"
				( objectStatus "@baseboard_fab2_lib.baseboard_fab2(sch_1):page199_i10:uv" )
			)
			( pin "EU1D2.2"
				( objectStatus "@baseboard_fab2_lib.baseboard_fab2(sch_1):page199_i10:vcap" )
			)
			( pin "EU1D2.30"
				( objectStatus "@baseboard_fab2_lib.baseboard_fab2(sch_1):page199_i10:vcc" )
			)
			( pin "EU1D2.20"
				( objectStatus "@baseboard_fab2_lib.baseboard_fab2(sch_1):page199_i10:vout" )
			)
			( pin "R9P29.1"
				( objectStatus "@baseboard_fab2_lib.baseboard_fab2(sch_1):page199_i12:a" )
			)
			( pin "R9P29.2"
				( objectStatus "@baseboard_fab2_lib.baseboard_fab2(sch_1):page199_i12:b" )
			)
			( pin "R1D42.1"
				( objectStatus "@baseboard_fab2_lib.baseboard_fab2(sch_1):page199_i13:a" )
			)
			( pin "R1D42.2"
				( objectStatus "@baseboard_fab2_lib.baseboard_fab2(sch_1):page199_i13:b" )
			)
			( pin "R1D37.1"
				( objectStatus "@baseboard_fab2_lib.baseboard_fab2(sch_1):page199_i15:a" )
			)
			( pin "R1D37.2"
				( objectStatus "@baseboard_fab2_lib.baseboard_fab2(sch_1):page199_i15:b" )
			)
			( pin "R1D39.1"
				( objectStatus "@baseboard_fab2_lib.baseboard_fab2(sch_1):page199_i16:a" )
			)
			( pin "R1D39.2"
				( objectStatus "@baseboard_fab2_lib.baseboard_fab2(sch_1):page199_i16:b" )
			)
			( pin "R1D32.1"
				( objectStatus "@baseboard_fab2_lib.baseboard_fab2(sch_1):page199_i17:a" )
			)
			( pin "R1D32.2"
				( objectStatus "@baseboard_fab2_lib.baseboard_fab2(sch_1):page199_i17:b" )
			)
			( pin "R1D41.1"
				( objectStatus "@baseboard_fab2_lib.baseboard_fab2(sch_1):page199_i19:a" )
			)
			( pin "R1D41.2"
				( objectStatus "@baseboard_fab2_lib.baseboard_fab2(sch_1):page199_i19:b" )
			)
			( pin "C9P14.1"
				( objectStatus "@baseboard_fab2_lib.baseboard_fab2(sch_1):page199_i24:a" )
			)
			( pin "C9P14.2"
				( objectStatus "@baseboard_fab2_lib.baseboard_fab2(sch_1):page199_i24:b" )
			)
			( pin "R1D28.1"
				( objectStatus "@baseboard_fab2_lib.baseboard_fab2(sch_1):page199_i26:a" )
			)
			( pin "R1D28.2"
				( objectStatus "@baseboard_fab2_lib.baseboard_fab2(sch_1):page199_i26:b" )
			)
			( pin "R1D24.1"
				( objectStatus "@baseboard_fab2_lib.baseboard_fab2(sch_1):page199_i27:a" )
			)
			( pin "R1D24.2"
				( objectStatus "@baseboard_fab2_lib.baseboard_fab2(sch_1):page199_i27:b" )
			)
			( pin "R1D25.1"
				( objectStatus "@baseboard_fab2_lib.baseboard_fab2(sch_1):page199_i28:a" )
			)
			( pin "R1D25.2"
				( objectStatus "@baseboard_fab2_lib.baseboard_fab2(sch_1):page199_i28:b" )
			)
			( pin "R9P17.1"
				( objectStatus "@baseboard_fab2_lib.baseboard_fab2(sch_1):page199_i33:a" )
			)
			( pin "R9P17.2"
				( objectStatus "@baseboard_fab2_lib.baseboard_fab2(sch_1):page199_i33:b" )
			)
			( pin "R9P16.1"
				( objectStatus "@baseboard_fab2_lib.baseboard_fab2(sch_1):page199_i36:a" )
			)
			( pin "R9P16.2"
				( objectStatus "@baseboard_fab2_lib.baseboard_fab2(sch_1):page199_i36:b" )
			)
			( pin "R1D27.1"
				( objectStatus "@baseboard_fab2_lib.baseboard_fab2(sch_1):page199_i38:a" )
			)
			( pin "R1D27.2"
				( objectStatus "@baseboard_fab2_lib.baseboard_fab2(sch_1):page199_i38:b" )
			)
			( pin "R9P18.1"
				( objectStatus "@baseboard_fab2_lib.baseboard_fab2(sch_1):page199_i41:a" )
			)
			( pin "R9P18.2"
				( objectStatus "@baseboard_fab2_lib.baseboard_fab2(sch_1):page199_i41:b" )
			)
			( pin "R1D31.1"
				( objectStatus "@baseboard_fab2_lib.baseboard_fab2(sch_1):page199_i43:a" )
			)
			( pin "R1D31.2"
				( objectStatus "@baseboard_fab2_lib.baseboard_fab2(sch_1):page199_i43:b" )
			)
			( pin "C1D11.1"
				( objectStatus "@baseboard_fab2_lib.baseboard_fab2(sch_1):page199_i53:a" )
			)
			( pin "C1D11.2"
				( objectStatus "@baseboard_fab2_lib.baseboard_fab2(sch_1):page199_i53:b" )
			)
			( pin "R9P23.1"
				( objectStatus "@baseboard_fab2_lib.baseboard_fab2(sch_1):page199_i54:a" )
			)
			( pin "R9P23.2"
				( objectStatus "@baseboard_fab2_lib.baseboard_fab2(sch_1):page199_i54:b" )
			)
			( pin "R9P24.1"
				( objectStatus "@baseboard_fab2_lib.baseboard_fab2(sch_1):page199_i55:a" )
			)
			( pin "R9P24.2"
				( objectStatus "@baseboard_fab2_lib.baseboard_fab2(sch_1):page199_i55:b" )
			)
			( pin "Q1D3.1"
				( objectStatus "@baseboard_fab2_lib.baseboard_fab2(sch_1):page199_i58:b" )
			)
			( pin "Q1D3.3"
				( objectStatus "@baseboard_fab2_lib.baseboard_fab2(sch_1):page199_i58:c" )
			)
			( pin "Q1D3.2"
				( objectStatus "@baseboard_fab2_lib.baseboard_fab2(sch_1):page199_i58:e" )
			)
			( pin "R1D36.1"
				( objectStatus "@baseboard_fab2_lib.baseboard_fab2(sch_1):page199_i65:a" )
			)
			( pin "R1D36.2"
				( objectStatus "@baseboard_fab2_lib.baseboard_fab2(sch_1):page199_i65:b" )
			)
			( pin "C9P12.1"
				( objectStatus "@baseboard_fab2_lib.baseboard_fab2(sch_1):page199_i67:a" )
			)
			( pin "C9P12.2"
				( objectStatus "@baseboard_fab2_lib.baseboard_fab2(sch_1):page199_i67:b" )
			)
			( pin "Q1D1.3"
				( objectStatus "@baseboard_fab2_lib.baseboard_fab2(sch_1):page199_i82:drain(0)" )
			)
			( pin "Q1D1.5"
				( objectStatus "@baseboard_fab2_lib.baseboard_fab2(sch_1):page199_i82:gate(0)" )
			)
			( pin "Q1D1.4"
				( objectStatus "@baseboard_fab2_lib.baseboard_fab2(sch_1):page199_i82:source(0)" )
			)
			( pin "R1D13.1"
				( objectStatus "@baseboard_fab2_lib.baseboard_fab2(sch_1):page199_i84:a" )
			)
			( pin "R1D13.2"
				( objectStatus "@baseboard_fab2_lib.baseboard_fab2(sch_1):page199_i84:b" )
			)
			( pin "R1D16.1"
				( objectStatus "@baseboard_fab2_lib.baseboard_fab2(sch_1):page199_i85:a" )
			)
			( pin "R1D16.2"
				( objectStatus "@baseboard_fab2_lib.baseboard_fab2(sch_1):page199_i85:b" )
			)
			( pin "Q1D1.6"
				( objectStatus "@baseboard_fab2_lib.baseboard_fab2(sch_1):page199_i86:drain(0)" )
			)
			( pin "Q1D1.2"
				( objectStatus "@baseboard_fab2_lib.baseboard_fab2(sch_1):page199_i86:gate(0)" )
			)
			( pin "Q1D1.1"
				( objectStatus "@baseboard_fab2_lib.baseboard_fab2(sch_1):page199_i86:source(0)" )
			)
			( pin "R1D11.1"
				( objectStatus "@baseboard_fab2_lib.baseboard_fab2(sch_1):page199_i88:a" )
			)
			( pin "R1D11.2"
				( objectStatus "@baseboard_fab2_lib.baseboard_fab2(sch_1):page199_i88:b" )
			)
			( pin "R1D15.1"
				( objectStatus "@baseboard_fab2_lib.baseboard_fab2(sch_1):page199_i92:a" )
			)
			( pin "R1D15.2"
				( objectStatus "@baseboard_fab2_lib.baseboard_fab2(sch_1):page199_i92:b" )
			)
			( pin "VR1D1.2"
				( objectStatus "@baseboard_fab2_lib.baseboard_fab2(sch_1):page199_i99:a" )
			)
			( pin "VR1D1.1"
				( objectStatus "@baseboard_fab2_lib.baseboard_fab2(sch_1):page199_i99:c" )
			)
			( pin "R1D40.1"
				( objectStatus "@baseboard_fab2_lib.baseboard_fab2(sch_1):page199_i100:a" )
			)
			( pin "R1D40.2"
				( objectStatus "@baseboard_fab2_lib.baseboard_fab2(sch_1):page199_i100:b" )
			)
			( pin "R1D34.1"
				( objectStatus "@baseboard_fab2_lib.baseboard_fab2(sch_1):page199_i102:a" )
			)
			( pin "R1D34.2"
				( objectStatus "@baseboard_fab2_lib.baseboard_fab2(sch_1):page199_i102:b" )
			)
			( pin "C9P15.1"
				( objectStatus "@baseboard_fab2_lib.baseboard_fab2(sch_1):page199_i105:a" )
			)
			( pin "C9P15.2"
				( objectStatus "@baseboard_fab2_lib.baseboard_fab2(sch_1):page199_i105:b" )
			)
			( pin "C1D26.1"
				( objectStatus "@baseboard_fab2_lib.baseboard_fab2(sch_1):page199_i107:a" )
			)
			( pin "C1D26.2"
				( objectStatus "@baseboard_fab2_lib.baseboard_fab2(sch_1):page199_i107:b" )
			)
			( pin "R1D33.1"
				( objectStatus "@baseboard_fab2_lib.baseboard_fab2(sch_1):page199_i108:a" )
			)
			( pin "R1D33.2"
				( objectStatus "@baseboard_fab2_lib.baseboard_fab2(sch_1):page199_i108:b" )
			)
			( pin "R1D26.1"
				( objectStatus "@baseboard_fab2_lib.baseboard_fab2(sch_1):page199_i109:a" )
			)
			( pin "R1D26.2"
				( objectStatus "@baseboard_fab2_lib.baseboard_fab2(sch_1):page199_i109:b" )
			)
			( pin "R1D30.1"
				( objectStatus "@baseboard_fab2_lib.baseboard_fab2(sch_1):page199_i110:a" )
			)
			( pin "R1D30.2"
				( objectStatus "@baseboard_fab2_lib.baseboard_fab2(sch_1):page199_i110:b" )
			)
			( pin "C1D19.1"
				( objectStatus "@baseboard_fab2_lib.baseboard_fab2(sch_1):page199_i119:a" )
			)
			( pin "C1D19.2"
				( objectStatus "@baseboard_fab2_lib.baseboard_fab2(sch_1):page199_i119:b" )
			)
			( pin "C1D21.1"
				( objectStatus "@baseboard_fab2_lib.baseboard_fab2(sch_1):page199_i121:a" )
			)
			( pin "C1D21.2"
				( objectStatus "@baseboard_fab2_lib.baseboard_fab2(sch_1):page199_i121:b" )
			)
			( pin "C9P17.1"
				( objectStatus "@baseboard_fab2_lib.baseboard_fab2(sch_1):page200_i36:a" )
			)
			( pin "C9P17.2"
				( objectStatus "@baseboard_fab2_lib.baseboard_fab2(sch_1):page200_i36:b" )
			)
			( pin "C9P16.1"
				( objectStatus "@baseboard_fab2_lib.baseboard_fab2(sch_1):page200_i40:a" )
			)
			( pin "C9P16.2"
				( objectStatus "@baseboard_fab2_lib.baseboard_fab2(sch_1):page200_i40:b" )
			)
			( pin "C1D22.1"
				( objectStatus "@baseboard_fab2_lib.baseboard_fab2(sch_1):page200_i42:a" )
			)
			( pin "C1D22.2"
				( objectStatus "@baseboard_fab2_lib.baseboard_fab2(sch_1):page200_i42:b" )
			)
			( pin "R1D45.1"
				( objectStatus "@baseboard_fab2_lib.baseboard_fab2(sch_1):page200_i43:a" )
			)
			( pin "R1D45.2"
				( objectStatus "@baseboard_fab2_lib.baseboard_fab2(sch_1):page200_i43:b" )
			)
			( pin "R1D44.1"
				( objectStatus "@baseboard_fab2_lib.baseboard_fab2(sch_1):page200_i44:a" )
			)
			( pin "R1D44.2"
				( objectStatus "@baseboard_fab2_lib.baseboard_fab2(sch_1):page200_i44:b" )
			)
			( pin "R9P27.1"
				( objectStatus "@baseboard_fab2_lib.baseboard_fab2(sch_1):page200_i47:a" )
			)
			( pin "R9P27.2"
				( objectStatus "@baseboard_fab2_lib.baseboard_fab2(sch_1):page200_i47:b" )
			)
			( pin "R1D46.1"
				( objectStatus "@baseboard_fab2_lib.baseboard_fab2(sch_1):page200_i48:a" )
			)
			( pin "R1D46.2"
				( objectStatus "@baseboard_fab2_lib.baseboard_fab2(sch_1):page200_i48:b" )
			)
			( pin "R9R1.1"
				( objectStatus "@baseboard_fab2_lib.baseboard_fab2(sch_1):page200_i49:\1\" )
			)
			( pin "R9R1.2"
				( objectStatus "@baseboard_fab2_lib.baseboard_fab2(sch_1):page200_i49:\2\" )
			)
			( pin "R9R1.3"
				( objectStatus "@baseboard_fab2_lib.baseboard_fab2(sch_1):page200_i49:\3\" )
			)
			( pin "R9R1.4"
				( objectStatus "@baseboard_fab2_lib.baseboard_fab2(sch_1):page200_i49:\4\" )
			)
			( pin "R9R1.5"
				( objectStatus "@baseboard_fab2_lib.baseboard_fab2(sch_1):page200_i49:\5\" )
			)
			( pin "R9R1.6"
				( objectStatus "@baseboard_fab2_lib.baseboard_fab2(sch_1):page200_i49:\6\" )
			)
			( pin "R1D49.1"
				( objectStatus "@baseboard_fab2_lib.baseboard_fab2(sch_1):page200_i50:\1\" )
			)
			( pin "R1D49.2"
				( objectStatus "@baseboard_fab2_lib.baseboard_fab2(sch_1):page200_i50:\2\" )
			)
			( pin "R1D49.3"
				( objectStatus "@baseboard_fab2_lib.baseboard_fab2(sch_1):page200_i50:\3\" )
			)
			( pin "R1D49.4"
				( objectStatus "@baseboard_fab2_lib.baseboard_fab2(sch_1):page200_i50:\4\" )
			)
			( pin "R1D49.5"
				( objectStatus "@baseboard_fab2_lib.baseboard_fab2(sch_1):page200_i50:\5\" )
			)
			( pin "R1D49.6"
				( objectStatus "@baseboard_fab2_lib.baseboard_fab2(sch_1):page200_i50:\6\" )
			)
			( pin "R9P26.1"
				( objectStatus "@baseboard_fab2_lib.baseboard_fab2(sch_1):page200_i51:a" )
			)
			( pin "R9P26.2"
				( objectStatus "@baseboard_fab2_lib.baseboard_fab2(sch_1):page200_i51:b" )
			)
			( pin "R1D47.1"
				( objectStatus "@baseboard_fab2_lib.baseboard_fab2(sch_1):page200_i52:a" )
			)
			( pin "R1D47.2"
				( objectStatus "@baseboard_fab2_lib.baseboard_fab2(sch_1):page200_i52:b" )
			)
			( pin "EU1E3.5"
				( objectStatus "@baseboard_fab2_lib.baseboard_fab2(sch_1):page200_i54:d" )
			)
			( pin "EU1E3.4"
				( objectStatus "@baseboard_fab2_lib.baseboard_fab2(sch_1):page200_i54:g" )
			)
			( pin "EU1E3.1"
				( objectStatus "@baseboard_fab2_lib.baseboard_fab2(sch_1):page200_i54:s1" )
			)
			( pin "EU1E3.2"
				( objectStatus "@baseboard_fab2_lib.baseboard_fab2(sch_1):page200_i54:s2" )
			)
			( pin "EU1E3.3"
				( objectStatus "@baseboard_fab2_lib.baseboard_fab2(sch_1):page200_i54:s3" )
			)
			( pin "R1E1.1"
				( objectStatus "@baseboard_fab2_lib.baseboard_fab2(sch_1):page200_i56:a" )
			)
			( pin "R1E1.2"
				( objectStatus "@baseboard_fab2_lib.baseboard_fab2(sch_1):page200_i56:b" )
			)
			( pin "EU9R1.5"
				( objectStatus "@baseboard_fab2_lib.baseboard_fab2(sch_1):page200_i57:d" )
			)
			( pin "EU9R1.4"
				( objectStatus "@baseboard_fab2_lib.baseboard_fab2(sch_1):page200_i57:g" )
			)
			( pin "EU9R1.1"
				( objectStatus "@baseboard_fab2_lib.baseboard_fab2(sch_1):page200_i57:s1" )
			)
			( pin "EU9R1.2"
				( objectStatus "@baseboard_fab2_lib.baseboard_fab2(sch_1):page200_i57:s2" )
			)
			( pin "EU9R1.3"
				( objectStatus "@baseboard_fab2_lib.baseboard_fab2(sch_1):page200_i57:s3" )
			)
			( pin "R9R4.1"
				( objectStatus "@baseboard_fab2_lib.baseboard_fab2(sch_1):page200_i58:a" )
			)
			( pin "R9R4.2"
				( objectStatus "@baseboard_fab2_lib.baseboard_fab2(sch_1):page200_i58:b" )
			)
			( pin "EU1E1.5"
				( objectStatus "@baseboard_fab2_lib.baseboard_fab2(sch_1):page200_i59:d" )
			)
			( pin "EU1E1.4"
				( objectStatus "@baseboard_fab2_lib.baseboard_fab2(sch_1):page200_i59:g" )
			)
			( pin "EU1E1.1"
				( objectStatus "@baseboard_fab2_lib.baseboard_fab2(sch_1):page200_i59:s1" )
			)
			( pin "EU1E1.2"
				( objectStatus "@baseboard_fab2_lib.baseboard_fab2(sch_1):page200_i59:s2" )
			)
			( pin "EU1E1.3"
				( objectStatus "@baseboard_fab2_lib.baseboard_fab2(sch_1):page200_i59:s3" )
			)
			( pin "R1D48.1"
				( objectStatus "@baseboard_fab2_lib.baseboard_fab2(sch_1):page200_i60:a" )
			)
			( pin "R1D48.2"
				( objectStatus "@baseboard_fab2_lib.baseboard_fab2(sch_1):page200_i60:b" )
			)
			( pin "R9P19.1"
				( objectStatus "@baseboard_fab2_lib.baseboard_fab2(sch_1):page200_i70:a" )
			)
			( pin "R9P19.2"
				( objectStatus "@baseboard_fab2_lib.baseboard_fab2(sch_1):page200_i70:b" )
			)
			( pin "R9P21.1"
				( objectStatus "@baseboard_fab2_lib.baseboard_fab2(sch_1):page200_i71:a" )
			)
			( pin "R9P21.2"
				( objectStatus "@baseboard_fab2_lib.baseboard_fab2(sch_1):page200_i71:b" )
			)
			( pin "R9P20.1"
				( objectStatus "@baseboard_fab2_lib.baseboard_fab2(sch_1):page200_i86:a" )
			)
			( pin "R9P20.2"
				( objectStatus "@baseboard_fab2_lib.baseboard_fab2(sch_1):page200_i86:b" )
			)
			( pin "U1D1.2"
				( objectStatus "@baseboard_fab2_lib.baseboard_fab2(sch_1):page200_i103:a" )
			)
			( pin "U1D1.1"
				( objectStatus "@baseboard_fab2_lib.baseboard_fab2(sch_1):page200_i103:oe" )
			)
			( pin "U1D1.4"
				( objectStatus "@baseboard_fab2_lib.baseboard_fab2(sch_1):page200_i103:y" )
			)
			( pin "R9P11.1"
				( objectStatus "@baseboard_fab2_lib.baseboard_fab2(sch_1):page200_i108:a" )
			)
			( pin "R9P11.2"
				( objectStatus "@baseboard_fab2_lib.baseboard_fab2(sch_1):page200_i108:b" )
			)
			( pin "R9P6.1"
				( objectStatus "@baseboard_fab2_lib.baseboard_fab2(sch_1):page200_i149:a" )
			)
			( pin "R9P6.2"
				( objectStatus "@baseboard_fab2_lib.baseboard_fab2(sch_1):page200_i149:b" )
			)
			( pin "R1D51.1"
				( objectStatus "@baseboard_fab2_lib.baseboard_fab2(sch_1):page200_i154:a" )
			)
			( pin "R1D51.2"
				( objectStatus "@baseboard_fab2_lib.baseboard_fab2(sch_1):page200_i154:b" )
			)
			( pin "C1E2.1"
				( objectStatus "@baseboard_fab2_lib.baseboard_fab2(sch_1):page200_i155:a" )
			)
			( pin "C1E2.2"
				( objectStatus "@baseboard_fab2_lib.baseboard_fab2(sch_1):page200_i155:b" )
			)
			( pin "R1D22.1"
				( objectStatus "@baseboard_fab2_lib.baseboard_fab2(sch_1):page200_i158:a" )
			)
			( pin "R1D22.2"
				( objectStatus "@baseboard_fab2_lib.baseboard_fab2(sch_1):page200_i158:b" )
			)
			( pin "U9P1.5"
				( objectStatus "@baseboard_fab2_lib.baseboard_fab2(sch_1):page200_i163:gnd" )
			)
			( pin "U9P1.4"
				( objectStatus "@baseboard_fab2_lib.baseboard_fab2(sch_1):page200_i163:inap" )
			)
			( pin "U9P1.3"
				( objectStatus "@baseboard_fab2_lib.baseboard_fab2(sch_1):page200_i163:inbn" )
			)
			( pin "U9P1.6"
				( objectStatus "@baseboard_fab2_lib.baseboard_fab2(sch_1):page200_i163:outa" )
			)
			( pin "U9P1.1"
				( objectStatus "@baseboard_fab2_lib.baseboard_fab2(sch_1):page200_i163:outb" )
			)
			( pin "U9P1.2"
				( objectStatus "@baseboard_fab2_lib.baseboard_fab2(sch_1):page200_i163:vdd" )
			)
			( pin "U1D2.5"
				( objectStatus "@baseboard_fab2_lib.baseboard_fab2(sch_1):page200_i170:gnd" )
			)
			( pin "U1D2.4"
				( objectStatus "@baseboard_fab2_lib.baseboard_fab2(sch_1):page200_i170:inap" )
			)
			( pin "U1D2.3"
				( objectStatus "@baseboard_fab2_lib.baseboard_fab2(sch_1):page200_i170:inbn" )
			)
			( pin "U1D2.6"
				( objectStatus "@baseboard_fab2_lib.baseboard_fab2(sch_1):page200_i170:outa" )
			)
			( pin "U1D2.1"
				( objectStatus "@baseboard_fab2_lib.baseboard_fab2(sch_1):page200_i170:outb" )
			)
			( pin "U1D2.2"
				( objectStatus "@baseboard_fab2_lib.baseboard_fab2(sch_1):page200_i170:vdd" )
			)
			( pin "R1D12.1"
				( objectStatus "@baseboard_fab2_lib.baseboard_fab2(sch_1):page200_i174:a" )
			)
			( pin "R1D12.2"
				( objectStatus "@baseboard_fab2_lib.baseboard_fab2(sch_1):page200_i174:b" )
			)
			( pin "R1D19.1"
				( objectStatus "@baseboard_fab2_lib.baseboard_fab2(sch_1):page200_i175:a" )
			)
			( pin "R1D19.2"
				( objectStatus "@baseboard_fab2_lib.baseboard_fab2(sch_1):page200_i175:b" )
			)
			( pin "C9P6.1"
				( objectStatus "@baseboard_fab2_lib.baseboard_fab2(sch_1):page200_i185:a" )
			)
			( pin "C9P6.2"
				( objectStatus "@baseboard_fab2_lib.baseboard_fab2(sch_1):page200_i185:b" )
			)
			( pin "C1D9.1"
				( objectStatus "@baseboard_fab2_lib.baseboard_fab2(sch_1):page200_i187:a" )
			)
			( pin "C1D9.2"
				( objectStatus "@baseboard_fab2_lib.baseboard_fab2(sch_1):page200_i187:b" )
			)
			( pin "R1D18.1"
				( objectStatus "@baseboard_fab2_lib.baseboard_fab2(sch_1):page199_i87:a" )
			)
			( pin "R1D18.2"
				( objectStatus "@baseboard_fab2_lib.baseboard_fab2(sch_1):page199_i87:b" )
			)
			( pin "R1D23.1"
				( objectStatus "@baseboard_fab2_lib.baseboard_fab2(sch_1):page200_i191:a" )
			)
			( pin "R1D23.2"
				( objectStatus "@baseboard_fab2_lib.baseboard_fab2(sch_1):page200_i191:b" )
			)
			( pin "R9P10.1"
				( objectStatus "@baseboard_fab2_lib.baseboard_fab2(sch_1):page200_i192:a" )
			)
			( pin "R9P10.2"
				( objectStatus "@baseboard_fab2_lib.baseboard_fab2(sch_1):page200_i192:b" )
			)
			( pin "Q9P1.6"
				( objectStatus "@baseboard_fab2_lib.baseboard_fab2(sch_1):page200_i196:drain(0)" )
			)
			( pin "Q9P1.2"
				( objectStatus "@baseboard_fab2_lib.baseboard_fab2(sch_1):page200_i196:gate(0)" )
			)
			( pin "Q9P1.1"
				( objectStatus "@baseboard_fab2_lib.baseboard_fab2(sch_1):page200_i196:source(0)" )
			)
			( pin "Q9P1.3"
				( objectStatus "@baseboard_fab2_lib.baseboard_fab2(sch_1):page200_i199:drain(0)" )
			)
			( pin "Q9P1.5"
				( objectStatus "@baseboard_fab2_lib.baseboard_fab2(sch_1):page200_i199:gate(0)" )
			)
			( pin "Q9P1.4"
				( objectStatus "@baseboard_fab2_lib.baseboard_fab2(sch_1):page200_i199:source(0)" )
			)
			( pin "U9P2.5"
				( objectStatus "@baseboard_fab2_lib.baseboard_fab2(sch_1):page200_i200:gnd" )
			)
			( pin "U9P2.4"
				( objectStatus "@baseboard_fab2_lib.baseboard_fab2(sch_1):page200_i200:inap" )
			)
			( pin "U9P2.3"
				( objectStatus "@baseboard_fab2_lib.baseboard_fab2(sch_1):page200_i200:inbn" )
			)
			( pin "U9P2.6"
				( objectStatus "@baseboard_fab2_lib.baseboard_fab2(sch_1):page200_i200:outa" )
			)
			( pin "U9P2.1"
				( objectStatus "@baseboard_fab2_lib.baseboard_fab2(sch_1):page200_i200:outb" )
			)
			( pin "U9P2.2"
				( objectStatus "@baseboard_fab2_lib.baseboard_fab2(sch_1):page200_i200:vdd" )
			)
			( pin "C9P11.1"
				( objectStatus "@baseboard_fab2_lib.baseboard_fab2(sch_1):page200_i201:a" )
			)
			( pin "C9P11.2"
				( objectStatus "@baseboard_fab2_lib.baseboard_fab2(sch_1):page200_i201:b" )
			)
			( pin "Q1D2.3"
				( objectStatus "@baseboard_fab2_lib.baseboard_fab2(sch_1):page200_i203:drn" )
			)
			( pin "Q1D2.1"
				( objectStatus "@baseboard_fab2_lib.baseboard_fab2(sch_1):page200_i203:gate" )
			)
			( pin "Q1D2.2"
				( objectStatus "@baseboard_fab2_lib.baseboard_fab2(sch_1):page200_i203:src" )
			)
			( pin "R1D21.1"
				( objectStatus "@baseboard_fab2_lib.baseboard_fab2(sch_1):page200_i204:a" )
			)
			( pin "R1D21.2"
				( objectStatus "@baseboard_fab2_lib.baseboard_fab2(sch_1):page200_i204:b" )
			)
			( pin "R9P4.1"
				( objectStatus "@baseboard_fab2_lib.baseboard_fab2(sch_1):page200_i210:a" )
			)
			( pin "R9P4.2"
				( objectStatus "@baseboard_fab2_lib.baseboard_fab2(sch_1):page200_i210:b" )
			)
			( pin "CR9P2.2"
				( objectStatus "@baseboard_fab2_lib.baseboard_fab2(sch_1):page200_i213:a" )
			)
			( pin "CR9P2.1"
				( objectStatus "@baseboard_fab2_lib.baseboard_fab2(sch_1):page200_i213:c" )
			)
			( pin "CR9P1.2"
				( objectStatus "@baseboard_fab2_lib.baseboard_fab2(sch_1):page200_i214:a" )
			)
			( pin "CR9P1.1"
				( objectStatus "@baseboard_fab2_lib.baseboard_fab2(sch_1):page200_i214:c" )
			)
			( pin "R9P5.1"
				( objectStatus "@baseboard_fab2_lib.baseboard_fab2(sch_1):page200_i215:a" )
			)
			( pin "R9P5.2"
				( objectStatus "@baseboard_fab2_lib.baseboard_fab2(sch_1):page200_i215:b" )
			)
			( pin "R9P12.1"
				( objectStatus "@baseboard_fab2_lib.baseboard_fab2(sch_1):page200_i218:a" )
			)
			( pin "R9P12.2"
				( objectStatus "@baseboard_fab2_lib.baseboard_fab2(sch_1):page200_i218:b" )
			)
			( pin "CR1F5.2"
				( objectStatus "@baseboard_fab2_lib.baseboard_fab2(sch_1):page200_i220:a" )
			)
			( pin "CR1F5.1"
				( objectStatus "@baseboard_fab2_lib.baseboard_fab2(sch_1):page200_i220:c" )
			)
			( pin "R9P33.1"
				( objectStatus "@baseboard_fab2_lib.baseboard_fab2(sch_1):page200_i222:a" )
			)
			( pin "R9P33.2"
				( objectStatus "@baseboard_fab2_lib.baseboard_fab2(sch_1):page200_i222:b" )
			)
			( pin "R1D7.1"
				( objectStatus "@baseboard_fab2_lib.baseboard_fab2(sch_1):page206_i155:a" )
			)
			( pin "R1D7.2"
				( objectStatus "@baseboard_fab2_lib.baseboard_fab2(sch_1):page206_i155:b" )
			)
			( pin "R3L13.1"
				( objectStatus "@baseboard_fab2_lib.baseboard_fab2(sch_1):page218_i70:a" )
			)
			( pin "R3L13.2"
				( objectStatus "@baseboard_fab2_lib.baseboard_fab2(sch_1):page218_i70:b" )
			)
			( pin "R4D31.1"
				( objectStatus "@baseboard_fab2_lib.baseboard_fab2(sch_1):page201_i22:a" )
			)
			( pin "R4D31.2"
				( objectStatus "@baseboard_fab2_lib.baseboard_fab2(sch_1):page201_i22:b" )
			)
			( pin "R4D58.1"
				( objectStatus "@baseboard_fab2_lib.baseboard_fab2(sch_1):page201_i25:a" )
			)
			( pin "R4D58.2"
				( objectStatus "@baseboard_fab2_lib.baseboard_fab2(sch_1):page201_i25:b" )
			)
			( pin "R4D67.1"
				( objectStatus "@baseboard_fab2_lib.baseboard_fab2(sch_1):page201_i26:a" )
			)
			( pin "R4D67.2"
				( objectStatus "@baseboard_fab2_lib.baseboard_fab2(sch_1):page201_i26:b" )
			)
			( pin "R4E5.1"
				( objectStatus "@baseboard_fab2_lib.baseboard_fab2(sch_1):page201_i27:a" )
			)
			( pin "R4E5.2"
				( objectStatus "@baseboard_fab2_lib.baseboard_fab2(sch_1):page201_i27:b" )
			)
			( pin "C4D25.1"
				( objectStatus "@baseboard_fab2_lib.baseboard_fab2(sch_1):page201_i30:a" )
			)
			( pin "C4D25.2"
				( objectStatus "@baseboard_fab2_lib.baseboard_fab2(sch_1):page201_i30:b" )
			)
			( pin "C4D26.1"
				( objectStatus "@baseboard_fab2_lib.baseboard_fab2(sch_1):page201_i32:a" )
			)
			( pin "C4D26.2"
				( objectStatus "@baseboard_fab2_lib.baseboard_fab2(sch_1):page201_i32:b" )
			)
			( pin "C4D15.1"
				( objectStatus "@baseboard_fab2_lib.baseboard_fab2(sch_1):page201_i37:a" )
			)
			( pin "C4D15.2"
				( objectStatus "@baseboard_fab2_lib.baseboard_fab2(sch_1):page201_i37:b" )
			)
			( pin "C4D19.1"
				( objectStatus "@baseboard_fab2_lib.baseboard_fab2(sch_1):page201_i39:a" )
			)
			( pin "C4D19.2"
				( objectStatus "@baseboard_fab2_lib.baseboard_fab2(sch_1):page201_i39:b" )
			)
			( pin "R4D26.1"
				( objectStatus "@baseboard_fab2_lib.baseboard_fab2(sch_1):page201_i40:a" )
			)
			( pin "R4D26.2"
				( objectStatus "@baseboard_fab2_lib.baseboard_fab2(sch_1):page201_i40:b" )
			)
			( pin "R3P17.1"
				( objectStatus "@baseboard_fab2_lib.baseboard_fab2(sch_1):page211_i99:a" )
			)
			( pin "R3P17.2"
				( objectStatus "@baseboard_fab2_lib.baseboard_fab2(sch_1):page211_i99:b" )
			)
			( pin "R4D27.1"
				( objectStatus "@baseboard_fab2_lib.baseboard_fab2(sch_1):page201_i54:a" )
			)
			( pin "R4D27.2"
				( objectStatus "@baseboard_fab2_lib.baseboard_fab2(sch_1):page201_i54:b" )
			)
			( pin "R4D32.1"
				( objectStatus "@baseboard_fab2_lib.baseboard_fab2(sch_1):page201_i55:a" )
			)
			( pin "R4D32.2"
				( objectStatus "@baseboard_fab2_lib.baseboard_fab2(sch_1):page201_i55:b" )
			)
			( pin "R4E6.1"
				( objectStatus "@baseboard_fab2_lib.baseboard_fab2(sch_1):page201_i56:a" )
			)
			( pin "R4E6.2"
				( objectStatus "@baseboard_fab2_lib.baseboard_fab2(sch_1):page201_i56:b" )
			)
			( pin "C1C8.1"
				( objectStatus "@baseboard_fab2_lib.baseboard_fab2(sch_1):page206_i156:a" )
			)
			( pin "C1C8.2"
				( objectStatus "@baseboard_fab2_lib.baseboard_fab2(sch_1):page206_i156:b" )
			)
			( pin "C4D29.1"
				( objectStatus "@baseboard_fab2_lib.baseboard_fab2(sch_1):page201_i64:a" )
			)
			( pin "C4D29.2"
				( objectStatus "@baseboard_fab2_lib.baseboard_fab2(sch_1):page201_i64:b" )
			)
			( pin "C4D17.1"
				( objectStatus "@baseboard_fab2_lib.baseboard_fab2(sch_1):page201_i66:a" )
			)
			( pin "C4D17.2"
				( objectStatus "@baseboard_fab2_lib.baseboard_fab2(sch_1):page201_i66:b" )
			)
			( pin "C4D18.1"
				( objectStatus "@baseboard_fab2_lib.baseboard_fab2(sch_1):page201_i68:a" )
			)
			( pin "C4D18.2"
				( objectStatus "@baseboard_fab2_lib.baseboard_fab2(sch_1):page201_i68:b" )
			)
			( pin "C4D45.1"
				( objectStatus "@baseboard_fab2_lib.baseboard_fab2(sch_1):page201_i70:a" )
			)
			( pin "C4D45.2"
				( objectStatus "@baseboard_fab2_lib.baseboard_fab2(sch_1):page201_i70:b" )
			)
			( pin "R4D66.1"
				( objectStatus "@baseboard_fab2_lib.baseboard_fab2(sch_1):page201_i98:a" )
			)
			( pin "R4D66.2"
				( objectStatus "@baseboard_fab2_lib.baseboard_fab2(sch_1):page201_i98:b" )
			)
			( pin "R6P32.1"
				( objectStatus "@baseboard_fab2_lib.baseboard_fab2(sch_1):page201_i102:a" )
			)
			( pin "R6P32.2"
				( objectStatus "@baseboard_fab2_lib.baseboard_fab2(sch_1):page201_i102:b" )
			)
			( pin "R6P37.1"
				( objectStatus "@baseboard_fab2_lib.baseboard_fab2(sch_1):page201_i103:a" )
			)
			( pin "R6P37.2"
				( objectStatus "@baseboard_fab2_lib.baseboard_fab2(sch_1):page201_i103:b" )
			)
			( pin "R4E8.1"
				( objectStatus "@baseboard_fab2_lib.baseboard_fab2(sch_1):page201_i109:a" )
			)
			( pin "R4E8.2"
				( objectStatus "@baseboard_fab2_lib.baseboard_fab2(sch_1):page201_i109:b" )
			)
			( pin "R4D39.1"
				( objectStatus "@baseboard_fab2_lib.baseboard_fab2(sch_1):page201_i110:a" )
			)
			( pin "R4D39.2"
				( objectStatus "@baseboard_fab2_lib.baseboard_fab2(sch_1):page201_i110:b" )
			)
			( pin "R4E3.1"
				( objectStatus "@baseboard_fab2_lib.baseboard_fab2(sch_1):page201_i111:a" )
			)
			( pin "R4E3.2"
				( objectStatus "@baseboard_fab2_lib.baseboard_fab2(sch_1):page201_i111:b" )
			)
			( pin "R4E20.1"
				( objectStatus "@baseboard_fab2_lib.baseboard_fab2(sch_1):page201_i116:a" )
			)
			( pin "R4E20.2"
				( objectStatus "@baseboard_fab2_lib.baseboard_fab2(sch_1):page201_i116:b" )
			)
			( pin "R6P27.1"
				( objectStatus "@baseboard_fab2_lib.baseboard_fab2(sch_1):page201_i120:a" )
			)
			( pin "R6P27.2"
				( objectStatus "@baseboard_fab2_lib.baseboard_fab2(sch_1):page201_i120:b" )
			)
			( pin "R6P28.1"
				( objectStatus "@baseboard_fab2_lib.baseboard_fab2(sch_1):page201_i121:a" )
			)
			( pin "R6P28.2"
				( objectStatus "@baseboard_fab2_lib.baseboard_fab2(sch_1):page201_i121:b" )
			)
			( pin "R4D63.1"
				( objectStatus "@baseboard_fab2_lib.baseboard_fab2(sch_1):page201_i124:a" )
			)
			( pin "R4D63.2"
				( objectStatus "@baseboard_fab2_lib.baseboard_fab2(sch_1):page201_i124:b" )
			)
			( pin "C4D42.1"
				( objectStatus "@baseboard_fab2_lib.baseboard_fab2(sch_1):page201_i125:a" )
			)
			( pin "C4D42.2"
				( objectStatus "@baseboard_fab2_lib.baseboard_fab2(sch_1):page201_i125:b" )
			)
			( pin "R4D65.1"
				( objectStatus "@baseboard_fab2_lib.baseboard_fab2(sch_1):page201_i127:a" )
			)
			( pin "R4D65.2"
				( objectStatus "@baseboard_fab2_lib.baseboard_fab2(sch_1):page201_i127:b" )
			)
			( pin "R6P45.1"
				( objectStatus "@baseboard_fab2_lib.baseboard_fab2(sch_1):page201_i128:a" )
			)
			( pin "R6P45.2"
				( objectStatus "@baseboard_fab2_lib.baseboard_fab2(sch_1):page201_i128:b" )
			)
			( pin "R6P18.1"
				( objectStatus "@baseboard_fab2_lib.baseboard_fab2(sch_1):page201_i131:a" )
			)
			( pin "R6P18.2"
				( objectStatus "@baseboard_fab2_lib.baseboard_fab2(sch_1):page201_i131:b" )
			)
			( pin "R6P16.1"
				( objectStatus "@baseboard_fab2_lib.baseboard_fab2(sch_1):page201_i132:a" )
			)
			( pin "R6P16.2"
				( objectStatus "@baseboard_fab2_lib.baseboard_fab2(sch_1):page201_i132:b" )
			)
			( pin "EU4D4.23"
				( objectStatus "@baseboard_fab2_lib.baseboard_fab2(sch_1):page201_i155:airef1" )
			)
			( pin "EU4D4.25"
				( objectStatus "@baseboard_fab2_lib.baseboard_fab2(sch_1):page201_i155:airef2" )
			)
			( pin "EU4D4.27"
				( objectStatus "@baseboard_fab2_lib.baseboard_fab2(sch_1):page201_i155:airef3" )
			)
			( pin "EU4D4.29"
				( objectStatus "@baseboard_fab2_lib.baseboard_fab2(sch_1):page201_i155:airef4" )
			)
			( pin "EU4D4.31"
				( objectStatus "@baseboard_fab2_lib.baseboard_fab2(sch_1):page201_i155:airef5" )
			)
			( pin "EU4D4.33"
				( objectStatus "@baseboard_fab2_lib.baseboard_fab2(sch_1):page201_i155:airef6" )
			)
			( pin "EU4D4.24"
				( objectStatus "@baseboard_fab2_lib.baseboard_fab2(sch_1):page201_i155:aisen1" )
			)
			( pin "EU4D4.26"
				( objectStatus "@baseboard_fab2_lib.baseboard_fab2(sch_1):page201_i155:aisen2" )
			)
			( pin "EU4D4.28"
				( objectStatus "@baseboard_fab2_lib.baseboard_fab2(sch_1):page201_i155:aisen3" )
			)
			( pin "EU4D4.30"
				( objectStatus "@baseboard_fab2_lib.baseboard_fab2(sch_1):page201_i155:aisen4" )
			)
			( pin "EU4D4.32"
				( objectStatus "@baseboard_fab2_lib.baseboard_fab2(sch_1):page201_i155:aisen5" )
			)
			( pin "EU4D4.34"
				( objectStatus "@baseboard_fab2_lib.baseboard_fab2(sch_1):page201_i155:aisen6" )
			)
			( pin "EU4D4.7"
				( objectStatus "@baseboard_fab2_lib.baseboard_fab2(sch_1):page201_i155:apwm1" )
			)
			( pin "EU4D4.6"
				( objectStatus "@baseboard_fab2_lib.baseboard_fab2(sch_1):page201_i155:apwm2" )
			)
			( pin "EU4D4.5"
				( objectStatus "@baseboard_fab2_lib.baseboard_fab2(sch_1):page201_i155:apwm3" )
			)
			( pin "EU4D4.4"
				( objectStatus "@baseboard_fab2_lib.baseboard_fab2(sch_1):page201_i155:apwm4" )
			)
			( pin "EU4D4.3"
				( objectStatus "@baseboard_fab2_lib.baseboard_fab2(sch_1):page201_i155:apwm5" )
			)
			( pin "EU4D4.2"
				( objectStatus "@baseboard_fab2_lib.baseboard_fab2(sch_1):page201_i155:apwm6" )
			)
			( pin "EU4D4.43"
				( objectStatus "@baseboard_fab2_lib.baseboard_fab2(sch_1):page201_i155:atsen" )
			)
			( pin "EU4D4.22"
				( objectStatus "@baseboard_fab2_lib.baseboard_fab2(sch_1):page201_i155:avref" )
			)
			( pin "EU4D4.12"
				( objectStatus "@baseboard_fab2_lib.baseboard_fab2(sch_1):page201_i155:avren" )
			)
			( pin "EU4D4.11"
				( objectStatus "@baseboard_fab2_lib.baseboard_fab2(sch_1):page201_i155:avrrdy" )
			)
			( pin "EU4D4.21"
				( objectStatus "@baseboard_fab2_lib.baseboard_fab2(sch_1):page201_i155:avsen" )
			)
			( pin "EU4D4.37"
				( objectStatus "@baseboard_fab2_lib.baseboard_fab2(sch_1):page201_i155:biref1" )
			)
			( pin "EU4D4.38"
				( objectStatus "@baseboard_fab2_lib.baseboard_fab2(sch_1):page201_i155:bisen1" )
			)
			( pin "EU4D4.1"
				( objectStatus "@baseboard_fab2_lib.baseboard_fab2(sch_1):page201_i155:bpwm1" )
			)
			( pin "EU4D4.42"
				( objectStatus "@baseboard_fab2_lib.baseboard_fab2(sch_1):page201_i155:btsen" )
			)
			( pin "EU4D4.36"
				( objectStatus "@baseboard_fab2_lib.baseboard_fab2(sch_1):page201_i155:bvref" )
			)
			( pin "EU4D4.35"
				( objectStatus "@baseboard_fab2_lib.baseboard_fab2(sch_1):page201_i155:bvsen" )
			)
			( pin "EU4D4.46"
				( objectStatus "@baseboard_fab2_lib.baseboard_fab2(sch_1):page201_i155:iinsen" )
			)
			( pin "EU4D4.15"
				( objectStatus "@baseboard_fab2_lib.baseboard_fab2(sch_1):page201_i155:mp0" )
			)
			( pin "EU4D4.16"
				( objectStatus "@baseboard_fab2_lib.baseboard_fab2(sch_1):page201_i155:mp1" )
			)
			( pin "EU4D4.20"
				( objectStatus "@baseboard_fab2_lib.baseboard_fab2(sch_1):page201_i155:mp2" )
			)
			( pin "EU4D4.39"
				( objectStatus "@baseboard_fab2_lib.baseboard_fab2(sch_1):page201_i155:mp3" )
			)
			( pin "EU4D4.40"
				( objectStatus "@baseboard_fab2_lib.baseboard_fab2(sch_1):page201_i155:mp4" )
			)
			( pin "EU4D4.14"
				( objectStatus "@baseboard_fab2_lib.baseboard_fab2(sch_1):page201_i155:pinalrt_n" )
			)
			( pin "EU4D4.10"
				( objectStatus "@baseboard_fab2_lib.baseboard_fab2(sch_1):page201_i155:reset_n" )
			)
			( pin "EU4D4.9"
				( objectStatus "@baseboard_fab2_lib.baseboard_fab2(sch_1):page201_i155:scl" )
			)
			( pin "EU4D4.8"
				( objectStatus "@baseboard_fab2_lib.baseboard_fab2(sch_1):page201_i155:sda" )
			)
			( pin "EU4D4.49"
				( objectStatus "@baseboard_fab2_lib.baseboard_fab2(sch_1):page201_i155:thpad" )
			)
			( pin "EU4D4.19"
				( objectStatus "@baseboard_fab2_lib.baseboard_fab2(sch_1):page201_i155:valrt_n" )
			)
			( pin "EU4D4.17"
				( objectStatus "@baseboard_fab2_lib.baseboard_fab2(sch_1):page201_i155:vclk" )
			)
			( pin "EU4D4.48"
				( objectStatus "@baseboard_fab2_lib.baseboard_fab2(sch_1):page201_i155:vd12" )
			)
			( pin "EU4D4.47"
				( objectStatus "@baseboard_fab2_lib.baseboard_fab2(sch_1):page201_i155:vdd" )
			)
			( pin "EU4D4.18"
				( objectStatus "@baseboard_fab2_lib.baseboard_fab2(sch_1):page201_i155:vdio" )
			)
			( pin "EU4D4.45"
				( objectStatus "@baseboard_fab2_lib.baseboard_fab2(sch_1):page201_i155:vinsen" )
			)
			( pin "EU4D4.13"
				( objectStatus "@baseboard_fab2_lib.baseboard_fab2(sch_1):page201_i155:vrhot_n" )
			)
			( pin "EU4D4.44"
				( objectStatus "@baseboard_fab2_lib.baseboard_fab2(sch_1):page201_i155:xaddr1" )
			)
			( pin "EU4D4.41"
				( objectStatus "@baseboard_fab2_lib.baseboard_fab2(sch_1):page201_i155:xaddr2" )
			)
			( pin "L4D3.2"
				( objectStatus "@baseboard_fab2_lib.baseboard_fab2(sch_1):page202_i110:f" )
			)
			( pin "L4D3.1"
				( objectStatus "@baseboard_fab2_lib.baseboard_fab2(sch_1):page202_i110:s" )
			)
			( pin "C6R7.1"
				( objectStatus "@baseboard_fab2_lib.baseboard_fab2(sch_1):page202_i9:a" )
			)
			( pin "C6R7.2"
				( objectStatus "@baseboard_fab2_lib.baseboard_fab2(sch_1):page202_i9:b" )
			)
			( pin "C4E5.1"
				( objectStatus "@baseboard_fab2_lib.baseboard_fab2(sch_1):page202_i18:a" )
			)
			( pin "C4E5.2"
				( objectStatus "@baseboard_fab2_lib.baseboard_fab2(sch_1):page202_i18:b" )
			)
			( pin "C7A26.1"
				( objectStatus "@baseboard_fab2_lib.baseboard_fab2(sch_1):page219_i152:\1\" )
			)
			( pin "C7A26.2"
				( objectStatus "@baseboard_fab2_lib.baseboard_fab2(sch_1):page219_i152:\2\" )
			)
			( pin "C4E17.1"
				( objectStatus "@baseboard_fab2_lib.baseboard_fab2(sch_1):page202_i22:a" )
			)
			( pin "C4E17.2"
				( objectStatus "@baseboard_fab2_lib.baseboard_fab2(sch_1):page202_i22:b" )
			)
			( pin "C4E27.1"
				( objectStatus "@baseboard_fab2_lib.baseboard_fab2(sch_1):page202_i24:a" )
			)
			( pin "C4E27.2"
				( objectStatus "@baseboard_fab2_lib.baseboard_fab2(sch_1):page202_i24:b" )
			)
			( pin "C4E28.1"
				( objectStatus "@baseboard_fab2_lib.baseboard_fab2(sch_1):page214_i175:\1\" )
			)
			( pin "C4E28.2"
				( objectStatus "@baseboard_fab2_lib.baseboard_fab2(sch_1):page214_i175:\2\" )
			)
			( pin "C4E11.1"
				( objectStatus "@baseboard_fab2_lib.baseboard_fab2(sch_1):page202_i27:a" )
			)
			( pin "C4E11.2"
				( objectStatus "@baseboard_fab2_lib.baseboard_fab2(sch_1):page202_i27:b" )
			)
			( pin "L4D2.2"
				( objectStatus "@baseboard_fab2_lib.baseboard_fab2(sch_1):page203_i130:f" )
			)
			( pin "L4D2.1"
				( objectStatus "@baseboard_fab2_lib.baseboard_fab2(sch_1):page203_i130:s" )
			)
			( pin "C4D50.1"
				( objectStatus "@baseboard_fab2_lib.baseboard_fab2(sch_1):page202_i32:a" )
			)
			( pin "C4D50.2"
				( objectStatus "@baseboard_fab2_lib.baseboard_fab2(sch_1):page202_i32:b" )
			)
			( pin "R9R2.1"
				( objectStatus "@baseboard_fab2_lib.baseboard_fab2(sch_1):page207_i106:a" )
			)
			( pin "R9R2.2"
				( objectStatus "@baseboard_fab2_lib.baseboard_fab2(sch_1):page207_i106:b" )
			)
			( pin "C4E10.1"
				( objectStatus "@baseboard_fab2_lib.baseboard_fab2(sch_1):page202_i34:a" )
			)
			( pin "C4E10.2"
				( objectStatus "@baseboard_fab2_lib.baseboard_fab2(sch_1):page202_i34:b" )
			)
			( pin "C4E20.1"
				( objectStatus "@baseboard_fab2_lib.baseboard_fab2(sch_1):page202_i35:a" )
			)
			( pin "C4E20.2"
				( objectStatus "@baseboard_fab2_lib.baseboard_fab2(sch_1):page202_i35:b" )
			)
			( pin "C4E19.1"
				( objectStatus "@baseboard_fab2_lib.baseboard_fab2(sch_1):page202_i36:a" )
			)
			( pin "C4E19.2"
				( objectStatus "@baseboard_fab2_lib.baseboard_fab2(sch_1):page202_i36:b" )
			)
			( pin "C6R11.1"
				( objectStatus "@baseboard_fab2_lib.baseboard_fab2(sch_1):page202_i37:a" )
			)
			( pin "C6R11.2"
				( objectStatus "@baseboard_fab2_lib.baseboard_fab2(sch_1):page202_i37:b" )
			)
			( pin "C6P13.1"
				( objectStatus "@baseboard_fab2_lib.baseboard_fab2(sch_1):page202_i38:a" )
			)
			( pin "C6P13.2"
				( objectStatus "@baseboard_fab2_lib.baseboard_fab2(sch_1):page202_i38:b" )
			)
			( pin "R6N3.1"
				( objectStatus "@baseboard_fab2_lib.baseboard_fab2(sch_1):page205_i81:a" )
			)
			( pin "R6N3.2"
				( objectStatus "@baseboard_fab2_lib.baseboard_fab2(sch_1):page205_i81:b" )
			)
			( pin "C6R13.1"
				( objectStatus "@baseboard_fab2_lib.baseboard_fab2(sch_1):page202_i42:a" )
			)
			( pin "C6R13.2"
				( objectStatus "@baseboard_fab2_lib.baseboard_fab2(sch_1):page202_i42:b" )
			)
			( pin "C4E26.1"
				( objectStatus "@baseboard_fab2_lib.baseboard_fab2(sch_1):page202_i45:a" )
			)
			( pin "C4E26.2"
				( objectStatus "@baseboard_fab2_lib.baseboard_fab2(sch_1):page202_i45:b" )
			)
			( pin "C4D49.1"
				( objectStatus "@baseboard_fab2_lib.baseboard_fab2(sch_1):page202_i46:a" )
			)
			( pin "C4D49.2"
				( objectStatus "@baseboard_fab2_lib.baseboard_fab2(sch_1):page202_i46:b" )
			)
			( pin "C4D48.1"
				( objectStatus "@baseboard_fab2_lib.baseboard_fab2(sch_1):page202_i47:a" )
			)
			( pin "C4D48.2"
				( objectStatus "@baseboard_fab2_lib.baseboard_fab2(sch_1):page202_i47:b" )
			)
			( pin "C6R4.1"
				( objectStatus "@baseboard_fab2_lib.baseboard_fab2(sch_1):page202_i48:a" )
			)
			( pin "C6R4.2"
				( objectStatus "@baseboard_fab2_lib.baseboard_fab2(sch_1):page202_i48:b" )
			)
			( pin "C6P22.1"
				( objectStatus "@baseboard_fab2_lib.baseboard_fab2(sch_1):page202_i49:a" )
			)
			( pin "C6P22.2"
				( objectStatus "@baseboard_fab2_lib.baseboard_fab2(sch_1):page202_i49:b" )
			)
			( pin "C6N8.1"
				( objectStatus "@baseboard_fab2_lib.baseboard_fab2(sch_1):page202_i51:a" )
			)
			( pin "C6N8.2"
				( objectStatus "@baseboard_fab2_lib.baseboard_fab2(sch_1):page202_i51:b" )
			)
			( pin "C4E3.1"
				( objectStatus "@baseboard_fab2_lib.baseboard_fab2(sch_1):page202_i61:a" )
			)
			( pin "C4E3.2"
				( objectStatus "@baseboard_fab2_lib.baseboard_fab2(sch_1):page202_i61:b" )
			)
			( pin "C6P16.1"
				( objectStatus "@baseboard_fab2_lib.baseboard_fab2(sch_1):page202_i62:a" )
			)
			( pin "C6P16.2"
				( objectStatus "@baseboard_fab2_lib.baseboard_fab2(sch_1):page202_i62:b" )
			)
			( pin "EU4E1.33"
				( objectStatus "@baseboard_fab2_lib.baseboard_fab2(sch_1):page202_i63:boost" )
			)
			( pin "EU4E1.35"
				( objectStatus "@baseboard_fab2_lib.baseboard_fab2(sch_1):page202_i63:en" )
			)
			( pin "EU4E1.6"
				( objectStatus "@baseboard_fab2_lib.baseboard_fab2(sch_1):page202_i63:gl(0)" )
			)
			( pin "EU4E1.41"
				( objectStatus "@baseboard_fab2_lib.baseboard_fab2(sch_1):page202_i63:gl(1)" )
			)
			( pin "EU4E1.38"
				( objectStatus "@baseboard_fab2_lib.baseboard_fab2(sch_1):page202_i63:iout" )
			)
			( pin "EU4E1.2"
				( objectStatus "@baseboard_fab2_lib.baseboard_fab2(sch_1):page202_i63:lgnd" )
			)
			( pin "EU4E1.31"
				( objectStatus "@baseboard_fab2_lib.baseboard_fab2(sch_1):page202_i63:nc" )
			)
			( pin "EU4E1.37"
				( objectStatus "@baseboard_fab2_lib.baseboard_fab2(sch_1):page202_i63:ocset" )
			)
			( pin "EU4E1.5"
				( objectStatus "@baseboard_fab2_lib.baseboard_fab2(sch_1):page202_i63:pgnd(0)" )
			)
			( pin "EU4E1.7"
				( objectStatus "@baseboard_fab2_lib.baseboard_fab2(sch_1):page202_i63:pgnd(1)" )
			)
			( pin "EU4E1.40"
				( objectStatus "@baseboard_fab2_lib.baseboard_fab2(sch_1):page202_i63:pgnd(2)" )
			)
			( pin "EU4E1.32"
				( objectStatus "@baseboard_fab2_lib.baseboard_fab2(sch_1):page202_i63:phase" )
			)
			( pin "EU4E1.34"
				( objectStatus "@baseboard_fab2_lib.baseboard_fab2(sch_1):page202_i63:pwm" )
			)
			( pin "EU4E1.39"
				( objectStatus "@baseboard_fab2_lib.baseboard_fab2(sch_1):page202_i63:refin" )
			)
			( pin "EU4E1.10"
				( objectStatus "@baseboard_fab2_lib.baseboard_fab2(sch_1):page202_i63:sw" )
			)
			( pin "EU4E1.36"
				( objectStatus "@baseboard_fab2_lib.baseboard_fab2(sch_1):page202_i63:tout_flt" )
			)
			( pin "EU4E1.3"
				( objectStatus "@baseboard_fab2_lib.baseboard_fab2(sch_1):page202_i63:vcc" )
			)
			( pin "EU4E1.4"
				( objectStatus "@baseboard_fab2_lib.baseboard_fab2(sch_1):page202_i63:vdrv" )
			)
			( pin "EU4E1.25"
				( objectStatus "@baseboard_fab2_lib.baseboard_fab2(sch_1):page202_i63:vin(0)" )
			)
			( pin "EU4E1.30"
				( objectStatus "@baseboard_fab2_lib.baseboard_fab2(sch_1):page202_i63:vin(1)" )
			)
			( pin "EU4E1.1"
				( objectStatus "@baseboard_fab2_lib.baseboard_fab2(sch_1):page202_i63:vos" )
			)
			( pin "EU4D6.33"
				( objectStatus "@baseboard_fab2_lib.baseboard_fab2(sch_1):page202_i64:boost" )
			)
			( pin "EU4D6.35"
				( objectStatus "@baseboard_fab2_lib.baseboard_fab2(sch_1):page202_i64:en" )
			)
			( pin "EU4D6.6"
				( objectStatus "@baseboard_fab2_lib.baseboard_fab2(sch_1):page202_i64:gl(0)" )
			)
			( pin "EU4D6.41"
				( objectStatus "@baseboard_fab2_lib.baseboard_fab2(sch_1):page202_i64:gl(1)" )
			)
			( pin "EU4D6.38"
				( objectStatus "@baseboard_fab2_lib.baseboard_fab2(sch_1):page202_i64:iout" )
			)
			( pin "EU4D6.2"
				( objectStatus "@baseboard_fab2_lib.baseboard_fab2(sch_1):page202_i64:lgnd" )
			)
			( pin "EU4D6.31"
				( objectStatus "@baseboard_fab2_lib.baseboard_fab2(sch_1):page202_i64:nc" )
			)
			( pin "EU4D6.37"
				( objectStatus "@baseboard_fab2_lib.baseboard_fab2(sch_1):page202_i64:ocset" )
			)
			( pin "EU4D6.5"
				( objectStatus "@baseboard_fab2_lib.baseboard_fab2(sch_1):page202_i64:pgnd(0)" )
			)
			( pin "EU4D6.7"
				( objectStatus "@baseboard_fab2_lib.baseboard_fab2(sch_1):page202_i64:pgnd(1)" )
			)
			( pin "EU4D6.40"
				( objectStatus "@baseboard_fab2_lib.baseboard_fab2(sch_1):page202_i64:pgnd(2)" )
			)
			( pin "EU4D6.32"
				( objectStatus "@baseboard_fab2_lib.baseboard_fab2(sch_1):page202_i64:phase" )
			)
			( pin "EU4D6.34"
				( objectStatus "@baseboard_fab2_lib.baseboard_fab2(sch_1):page202_i64:pwm" )
			)
			( pin "EU4D6.39"
				( objectStatus "@baseboard_fab2_lib.baseboard_fab2(sch_1):page202_i64:refin" )
			)
			( pin "EU4D6.10"
				( objectStatus "@baseboard_fab2_lib.baseboard_fab2(sch_1):page202_i64:sw" )
			)
			( pin "EU4D6.36"
				( objectStatus "@baseboard_fab2_lib.baseboard_fab2(sch_1):page202_i64:tout_flt" )
			)
			( pin "EU4D6.3"
				( objectStatus "@baseboard_fab2_lib.baseboard_fab2(sch_1):page202_i64:vcc" )
			)
			( pin "EU4D6.4"
				( objectStatus "@baseboard_fab2_lib.baseboard_fab2(sch_1):page202_i64:vdrv" )
			)
			( pin "EU4D6.25"
				( objectStatus "@baseboard_fab2_lib.baseboard_fab2(sch_1):page202_i64:vin(0)" )
			)
			( pin "EU4D6.30"
				( objectStatus "@baseboard_fab2_lib.baseboard_fab2(sch_1):page202_i64:vin(1)" )
			)
			( pin "EU4D6.1"
				( objectStatus "@baseboard_fab2_lib.baseboard_fab2(sch_1):page202_i64:vos" )
			)
			( pin "R4E22.1"
				( objectStatus "@baseboard_fab2_lib.baseboard_fab2(sch_1):page202_i65:a" )
			)
			( pin "R4E22.2"
				( objectStatus "@baseboard_fab2_lib.baseboard_fab2(sch_1):page202_i65:b" )
			)
			( pin "R4E19.1"
				( objectStatus "@baseboard_fab2_lib.baseboard_fab2(sch_1):page202_i67:a" )
			)
			( pin "R4E19.2"
				( objectStatus "@baseboard_fab2_lib.baseboard_fab2(sch_1):page202_i67:b" )
			)
			( pin "C6P24.1"
				( objectStatus "@baseboard_fab2_lib.baseboard_fab2(sch_1):page203_i1:a" )
			)
			( pin "C6P24.2"
				( objectStatus "@baseboard_fab2_lib.baseboard_fab2(sch_1):page203_i1:b" )
			)
			( pin "C6R6.1"
				( objectStatus "@baseboard_fab2_lib.baseboard_fab2(sch_1):page203_i2:a" )
			)
			( pin "C6R6.2"
				( objectStatus "@baseboard_fab2_lib.baseboard_fab2(sch_1):page203_i2:b" )
			)
			( pin "C4D9.1"
				( objectStatus "@baseboard_fab2_lib.baseboard_fab2(sch_1):page203_i3:a" )
			)
			( pin "C4D9.2"
				( objectStatus "@baseboard_fab2_lib.baseboard_fab2(sch_1):page203_i3:b" )
			)
			( pin "L1D3.2"
				( objectStatus "@baseboard_fab2_lib.baseboard_fab2(sch_1):page207_i108:f" )
			)
			( pin "L1D3.1"
				( objectStatus "@baseboard_fab2_lib.baseboard_fab2(sch_1):page207_i108:s" )
			)
			( pin "C6R3.1"
				( objectStatus "@baseboard_fab2_lib.baseboard_fab2(sch_1):page203_i16:a" )
			)
			( pin "C6R3.2"
				( objectStatus "@baseboard_fab2_lib.baseboard_fab2(sch_1):page203_i16:b" )
			)
			( pin "C6R9.1"
				( objectStatus "@baseboard_fab2_lib.baseboard_fab2(sch_1):page203_i18:a" )
			)
			( pin "C6R9.2"
				( objectStatus "@baseboard_fab2_lib.baseboard_fab2(sch_1):page203_i18:b" )
			)
			( pin "L4C3.2"
				( objectStatus "@baseboard_fab2_lib.baseboard_fab2(sch_1):page204_i104:f" )
			)
			( pin "L4C3.1"
				( objectStatus "@baseboard_fab2_lib.baseboard_fab2(sch_1):page204_i104:s" )
			)
			( pin "C6P3.1"
				( objectStatus "@baseboard_fab2_lib.baseboard_fab2(sch_1):page203_i25:a" )
			)
			( pin "C6P3.2"
				( objectStatus "@baseboard_fab2_lib.baseboard_fab2(sch_1):page203_i25:b" )
			)
			( pin "C6P23.1"
				( objectStatus "@baseboard_fab2_lib.baseboard_fab2(sch_1):page203_i28:a" )
			)
			( pin "C6P23.2"
				( objectStatus "@baseboard_fab2_lib.baseboard_fab2(sch_1):page203_i28:b" )
			)
			( pin "C6P14.1"
				( objectStatus "@baseboard_fab2_lib.baseboard_fab2(sch_1):page203_i29:a" )
			)
			( pin "C6P14.2"
				( objectStatus "@baseboard_fab2_lib.baseboard_fab2(sch_1):page203_i29:b" )
			)
			( pin "C6P18.1"
				( objectStatus "@baseboard_fab2_lib.baseboard_fab2(sch_1):page203_i30:a" )
			)
			( pin "C6P18.2"
				( objectStatus "@baseboard_fab2_lib.baseboard_fab2(sch_1):page203_i30:b" )
			)
			( pin "C6P8.1"
				( objectStatus "@baseboard_fab2_lib.baseboard_fab2(sch_1):page203_i32:a" )
			)
			( pin "C6P8.2"
				( objectStatus "@baseboard_fab2_lib.baseboard_fab2(sch_1):page203_i32:b" )
			)
			( pin "C6N9.1"
				( objectStatus "@baseboard_fab2_lib.baseboard_fab2(sch_1):page203_i34:a" )
			)
			( pin "C6N9.2"
				( objectStatus "@baseboard_fab2_lib.baseboard_fab2(sch_1):page203_i34:b" )
			)
			( pin "R6R6.1"
				( objectStatus "@baseboard_fab2_lib.baseboard_fab2(sch_1):page202_i108:a" )
			)
			( pin "R6R6.2"
				( objectStatus "@baseboard_fab2_lib.baseboard_fab2(sch_1):page202_i108:b" )
			)
			( pin "C4D13.1"
				( objectStatus "@baseboard_fab2_lib.baseboard_fab2(sch_1):page203_i40:a" )
			)
			( pin "C4D13.2"
				( objectStatus "@baseboard_fab2_lib.baseboard_fab2(sch_1):page203_i40:b" )
			)
			( pin "C4E6.1"
				( objectStatus "@baseboard_fab2_lib.baseboard_fab2(sch_1):page202_i112:\1\" )
			)
			( pin "C4E6.2"
				( objectStatus "@baseboard_fab2_lib.baseboard_fab2(sch_1):page202_i112:\2\" )
			)
			( pin "C4D28.1"
				( objectStatus "@baseboard_fab2_lib.baseboard_fab2(sch_1):page203_i42:a" )
			)
			( pin "C4D28.2"
				( objectStatus "@baseboard_fab2_lib.baseboard_fab2(sch_1):page203_i42:b" )
			)
			( pin "C4D16.1"
				( objectStatus "@baseboard_fab2_lib.baseboard_fab2(sch_1):page203_i45:a" )
			)
			( pin "C4D16.2"
				( objectStatus "@baseboard_fab2_lib.baseboard_fab2(sch_1):page203_i45:b" )
			)
			( pin "C4D35.1"
				( objectStatus "@baseboard_fab2_lib.baseboard_fab2(sch_1):page203_i46:a" )
			)
			( pin "C4D35.2"
				( objectStatus "@baseboard_fab2_lib.baseboard_fab2(sch_1):page203_i46:b" )
			)
			( pin "C4D30.1"
				( objectStatus "@baseboard_fab2_lib.baseboard_fab2(sch_1):page203_i47:a" )
			)
			( pin "C4D30.2"
				( objectStatus "@baseboard_fab2_lib.baseboard_fab2(sch_1):page203_i47:b" )
			)
			( pin "C4D5.1"
				( objectStatus "@baseboard_fab2_lib.baseboard_fab2(sch_1):page203_i48:a" )
			)
			( pin "C4D5.2"
				( objectStatus "@baseboard_fab2_lib.baseboard_fab2(sch_1):page203_i48:b" )
			)
			( pin "C4E25.1"
				( objectStatus "@baseboard_fab2_lib.baseboard_fab2(sch_1):page202_i111:\1\" )
			)
			( pin "C4E25.2"
				( objectStatus "@baseboard_fab2_lib.baseboard_fab2(sch_1):page202_i111:\2\" )
			)
			( pin "R6R2.1"
				( objectStatus "@baseboard_fab2_lib.baseboard_fab2(sch_1):page202_i107:a" )
			)
			( pin "R6R2.2"
				( objectStatus "@baseboard_fab2_lib.baseboard_fab2(sch_1):page202_i107:b" )
			)
			( pin "C4D7.1"
				( objectStatus "@baseboard_fab2_lib.baseboard_fab2(sch_1):page203_i51:a" )
			)
			( pin "C4D7.2"
				( objectStatus "@baseboard_fab2_lib.baseboard_fab2(sch_1):page203_i51:b" )
			)
			( pin "C4D11.1"
				( objectStatus "@baseboard_fab2_lib.baseboard_fab2(sch_1):page203_i52:a" )
			)
			( pin "C4D11.2"
				( objectStatus "@baseboard_fab2_lib.baseboard_fab2(sch_1):page203_i52:b" )
			)
			( pin "C4D10.1"
				( objectStatus "@baseboard_fab2_lib.baseboard_fab2(sch_1):page203_i53:a" )
			)
			( pin "C4D10.2"
				( objectStatus "@baseboard_fab2_lib.baseboard_fab2(sch_1):page203_i53:b" )
			)
			( pin "C6P19.1"
				( objectStatus "@baseboard_fab2_lib.baseboard_fab2(sch_1):page203_i54:a" )
			)
			( pin "C6P19.2"
				( objectStatus "@baseboard_fab2_lib.baseboard_fab2(sch_1):page203_i54:b" )
			)
			( pin "C6P20.1"
				( objectStatus "@baseboard_fab2_lib.baseboard_fab2(sch_1):page203_i57:a" )
			)
			( pin "C6P20.2"
				( objectStatus "@baseboard_fab2_lib.baseboard_fab2(sch_1):page203_i57:b" )
			)
			( pin "C6P15.1"
				( objectStatus "@baseboard_fab2_lib.baseboard_fab2(sch_1):page203_i58:a" )
			)
			( pin "C6P15.2"
				( objectStatus "@baseboard_fab2_lib.baseboard_fab2(sch_1):page203_i58:b" )
			)
			( pin "C6P7.1"
				( objectStatus "@baseboard_fab2_lib.baseboard_fab2(sch_1):page203_i59:a" )
			)
			( pin "C6P7.2"
				( objectStatus "@baseboard_fab2_lib.baseboard_fab2(sch_1):page203_i59:b" )
			)
			( pin "C6P21.1"
				( objectStatus "@baseboard_fab2_lib.baseboard_fab2(sch_1):page203_i66:a" )
			)
			( pin "C6P21.2"
				( objectStatus "@baseboard_fab2_lib.baseboard_fab2(sch_1):page203_i66:b" )
			)
			( pin "R4E13.1"
				( objectStatus "@baseboard_fab2_lib.baseboard_fab2(sch_1):page203_i67:a" )
			)
			( pin "R4E13.2"
				( objectStatus "@baseboard_fab2_lib.baseboard_fab2(sch_1):page203_i67:b" )
			)
			( pin "C4D34.1"
				( objectStatus "@baseboard_fab2_lib.baseboard_fab2(sch_1):page203_i68:a" )
			)
			( pin "C4D34.2"
				( objectStatus "@baseboard_fab2_lib.baseboard_fab2(sch_1):page203_i68:b" )
			)
			( pin "C4D4.1"
				( objectStatus "@baseboard_fab2_lib.baseboard_fab2(sch_1):page203_i69:a" )
			)
			( pin "C4D4.2"
				( objectStatus "@baseboard_fab2_lib.baseboard_fab2(sch_1):page203_i69:b" )
			)
			( pin "EU4D3.33"
				( objectStatus "@baseboard_fab2_lib.baseboard_fab2(sch_1):page203_i70:boost" )
			)
			( pin "EU4D3.35"
				( objectStatus "@baseboard_fab2_lib.baseboard_fab2(sch_1):page203_i70:en" )
			)
			( pin "EU4D3.6"
				( objectStatus "@baseboard_fab2_lib.baseboard_fab2(sch_1):page203_i70:gl(0)" )
			)
			( pin "EU4D3.41"
				( objectStatus "@baseboard_fab2_lib.baseboard_fab2(sch_1):page203_i70:gl(1)" )
			)
			( pin "EU4D3.38"
				( objectStatus "@baseboard_fab2_lib.baseboard_fab2(sch_1):page203_i70:iout" )
			)
			( pin "EU4D3.2"
				( objectStatus "@baseboard_fab2_lib.baseboard_fab2(sch_1):page203_i70:lgnd" )
			)
			( pin "EU4D3.31"
				( objectStatus "@baseboard_fab2_lib.baseboard_fab2(sch_1):page203_i70:nc" )
			)
			( pin "EU4D3.37"
				( objectStatus "@baseboard_fab2_lib.baseboard_fab2(sch_1):page203_i70:ocset" )
			)
			( pin "EU4D3.5"
				( objectStatus "@baseboard_fab2_lib.baseboard_fab2(sch_1):page203_i70:pgnd(0)" )
			)
			( pin "EU4D3.7"
				( objectStatus "@baseboard_fab2_lib.baseboard_fab2(sch_1):page203_i70:pgnd(1)" )
			)
			( pin "EU4D3.40"
				( objectStatus "@baseboard_fab2_lib.baseboard_fab2(sch_1):page203_i70:pgnd(2)" )
			)
			( pin "EU4D3.32"
				( objectStatus "@baseboard_fab2_lib.baseboard_fab2(sch_1):page203_i70:phase" )
			)
			( pin "EU4D3.34"
				( objectStatus "@baseboard_fab2_lib.baseboard_fab2(sch_1):page203_i70:pwm" )
			)
			( pin "EU4D3.39"
				( objectStatus "@baseboard_fab2_lib.baseboard_fab2(sch_1):page203_i70:refin" )
			)
			( pin "EU4D3.10"
				( objectStatus "@baseboard_fab2_lib.baseboard_fab2(sch_1):page203_i70:sw" )
			)
			( pin "EU4D3.36"
				( objectStatus "@baseboard_fab2_lib.baseboard_fab2(sch_1):page203_i70:tout_flt" )
			)
			( pin "EU4D3.3"
				( objectStatus "@baseboard_fab2_lib.baseboard_fab2(sch_1):page203_i70:vcc" )
			)
			( pin "EU4D3.4"
				( objectStatus "@baseboard_fab2_lib.baseboard_fab2(sch_1):page203_i70:vdrv" )
			)
			( pin "EU4D3.25"
				( objectStatus "@baseboard_fab2_lib.baseboard_fab2(sch_1):page203_i70:vin(0)" )
			)
			( pin "EU4D3.30"
				( objectStatus "@baseboard_fab2_lib.baseboard_fab2(sch_1):page203_i70:vin(1)" )
			)
			( pin "EU4D3.1"
				( objectStatus "@baseboard_fab2_lib.baseboard_fab2(sch_1):page203_i70:vos" )
			)
			( pin "EU4D1.33"
				( objectStatus "@baseboard_fab2_lib.baseboard_fab2(sch_1):page203_i71:boost" )
			)
			( pin "EU4D1.35"
				( objectStatus "@baseboard_fab2_lib.baseboard_fab2(sch_1):page203_i71:en" )
			)
			( pin "EU4D1.6"
				( objectStatus "@baseboard_fab2_lib.baseboard_fab2(sch_1):page203_i71:gl(0)" )
			)
			( pin "EU4D1.41"
				( objectStatus "@baseboard_fab2_lib.baseboard_fab2(sch_1):page203_i71:gl(1)" )
			)
			( pin "EU4D1.38"
				( objectStatus "@baseboard_fab2_lib.baseboard_fab2(sch_1):page203_i71:iout" )
			)
			( pin "EU4D1.2"
				( objectStatus "@baseboard_fab2_lib.baseboard_fab2(sch_1):page203_i71:lgnd" )
			)
			( pin "EU4D1.31"
				( objectStatus "@baseboard_fab2_lib.baseboard_fab2(sch_1):page203_i71:nc" )
			)
			( pin "EU4D1.37"
				( objectStatus "@baseboard_fab2_lib.baseboard_fab2(sch_1):page203_i71:ocset" )
			)
			( pin "EU4D1.5"
				( objectStatus "@baseboard_fab2_lib.baseboard_fab2(sch_1):page203_i71:pgnd(0)" )
			)
			( pin "EU4D1.7"
				( objectStatus "@baseboard_fab2_lib.baseboard_fab2(sch_1):page203_i71:pgnd(1)" )
			)
			( pin "EU4D1.40"
				( objectStatus "@baseboard_fab2_lib.baseboard_fab2(sch_1):page203_i71:pgnd(2)" )
			)
			( pin "EU4D1.32"
				( objectStatus "@baseboard_fab2_lib.baseboard_fab2(sch_1):page203_i71:phase" )
			)
			( pin "EU4D1.34"
				( objectStatus "@baseboard_fab2_lib.baseboard_fab2(sch_1):page203_i71:pwm" )
			)
			( pin "EU4D1.39"
				( objectStatus "@baseboard_fab2_lib.baseboard_fab2(sch_1):page203_i71:refin" )
			)
			( pin "EU4D1.10"
				( objectStatus "@baseboard_fab2_lib.baseboard_fab2(sch_1):page203_i71:sw" )
			)
			( pin "EU4D1.36"
				( objectStatus "@baseboard_fab2_lib.baseboard_fab2(sch_1):page203_i71:tout_flt" )
			)
			( pin "EU4D1.3"
				( objectStatus "@baseboard_fab2_lib.baseboard_fab2(sch_1):page203_i71:vcc" )
			)
			( pin "EU4D1.4"
				( objectStatus "@baseboard_fab2_lib.baseboard_fab2(sch_1):page203_i71:vdrv" )
			)
			( pin "EU4D1.25"
				( objectStatus "@baseboard_fab2_lib.baseboard_fab2(sch_1):page203_i71:vin(0)" )
			)
			( pin "EU4D1.30"
				( objectStatus "@baseboard_fab2_lib.baseboard_fab2(sch_1):page203_i71:vin(1)" )
			)
			( pin "EU4D1.1"
				( objectStatus "@baseboard_fab2_lib.baseboard_fab2(sch_1):page203_i71:vos" )
			)
			( pin "R4D72.1"
				( objectStatus "@baseboard_fab2_lib.baseboard_fab2(sch_1):page203_i89:a" )
			)
			( pin "R4D72.2"
				( objectStatus "@baseboard_fab2_lib.baseboard_fab2(sch_1):page203_i89:b" )
			)
			( pin "R4D71.1"
				( objectStatus "@baseboard_fab2_lib.baseboard_fab2(sch_1):page203_i91:a" )
			)
			( pin "R4D71.2"
				( objectStatus "@baseboard_fab2_lib.baseboard_fab2(sch_1):page203_i91:b" )
			)
			( pin "L1E1.2"
				( objectStatus "@baseboard_fab2_lib.baseboard_fab2(sch_1):page207_i107:f" )
			)
			( pin "L1E1.1"
				( objectStatus "@baseboard_fab2_lib.baseboard_fab2(sch_1):page207_i107:s" )
			)
			( pin "C4D12.1"
				( objectStatus "@baseboard_fab2_lib.baseboard_fab2(sch_1):page204_i9:a" )
			)
			( pin "C4D12.2"
				( objectStatus "@baseboard_fab2_lib.baseboard_fab2(sch_1):page204_i9:b" )
			)
			( pin "C4D47.1"
				( objectStatus "@baseboard_fab2_lib.baseboard_fab2(sch_1):page204_i18:a" )
			)
			( pin "C4D47.2"
				( objectStatus "@baseboard_fab2_lib.baseboard_fab2(sch_1):page204_i18:b" )
			)
			( pin "C4D14.1"
				( objectStatus "@baseboard_fab2_lib.baseboard_fab2(sch_1):page203_i132:\1\" )
			)
			( pin "C4D14.2"
				( objectStatus "@baseboard_fab2_lib.baseboard_fab2(sch_1):page203_i132:\2\" )
			)
			( pin "C4C17.1"
				( objectStatus "@baseboard_fab2_lib.baseboard_fab2(sch_1):page204_i22:a" )
			)
			( pin "C4C17.2"
				( objectStatus "@baseboard_fab2_lib.baseboard_fab2(sch_1):page204_i22:b" )
			)
			( pin "R9R11.1"
				( objectStatus "@baseboard_fab2_lib.baseboard_fab2(sch_1):page207_i105:a" )
			)
			( pin "R9R11.2"
				( objectStatus "@baseboard_fab2_lib.baseboard_fab2(sch_1):page207_i105:b" )
			)
			( pin "C4D46.1"
				( objectStatus "@baseboard_fab2_lib.baseboard_fab2(sch_1):page204_i34:a" )
			)
			( pin "C4D46.2"
				( objectStatus "@baseboard_fab2_lib.baseboard_fab2(sch_1):page204_i34:b" )
			)
			( pin "C4C19.1"
				( objectStatus "@baseboard_fab2_lib.baseboard_fab2(sch_1):page204_i35:a" )
			)
			( pin "C4C19.2"
				( objectStatus "@baseboard_fab2_lib.baseboard_fab2(sch_1):page204_i35:b" )
			)
			( pin "C4C18.1"
				( objectStatus "@baseboard_fab2_lib.baseboard_fab2(sch_1):page204_i36:a" )
			)
			( pin "C4C18.2"
				( objectStatus "@baseboard_fab2_lib.baseboard_fab2(sch_1):page204_i36:b" )
			)
			( pin "C6N10.1"
				( objectStatus "@baseboard_fab2_lib.baseboard_fab2(sch_1):page204_i37:a" )
			)
			( pin "C6N10.2"
				( objectStatus "@baseboard_fab2_lib.baseboard_fab2(sch_1):page204_i37:b" )
			)
			( pin "C6P17.1"
				( objectStatus "@baseboard_fab2_lib.baseboard_fab2(sch_1):page204_i38:a" )
			)
			( pin "C6P17.2"
				( objectStatus "@baseboard_fab2_lib.baseboard_fab2(sch_1):page204_i38:b" )
			)
			( pin "C6N11.1"
				( objectStatus "@baseboard_fab2_lib.baseboard_fab2(sch_1):page204_i42:a" )
			)
			( pin "C6N11.2"
				( objectStatus "@baseboard_fab2_lib.baseboard_fab2(sch_1):page204_i42:b" )
			)
			( pin "L1B2.2"
				( objectStatus "@baseboard_fab2_lib.baseboard_fab2(sch_1):page209_i81:f" )
			)
			( pin "L1B2.1"
				( objectStatus "@baseboard_fab2_lib.baseboard_fab2(sch_1):page209_i81:s" )
			)
			( pin "C4D2.1"
				( objectStatus "@baseboard_fab2_lib.baseboard_fab2(sch_1):page204_i48:a" )
			)
			( pin "C4D2.2"
				( objectStatus "@baseboard_fab2_lib.baseboard_fab2(sch_1):page204_i48:b" )
			)
			( pin "C4E16.1"
				( objectStatus "@baseboard_fab2_lib.baseboard_fab2(sch_1):page204_i50:a" )
			)
			( pin "C4E16.2"
				( objectStatus "@baseboard_fab2_lib.baseboard_fab2(sch_1):page204_i50:b" )
			)
			( pin "R8W5.1"
				( objectStatus "@baseboard_fab2_lib.baseboard_fab2(sch_1):page138_i194:a" )
			)
			( pin "R8W5.2"
				( objectStatus "@baseboard_fab2_lib.baseboard_fab2(sch_1):page138_i194:b" )
			)
			( pin "R8W4.1"
				( objectStatus "@baseboard_fab2_lib.baseboard_fab2(sch_1):page138_i195:a" )
			)
			( pin "R8W4.2"
				( objectStatus "@baseboard_fab2_lib.baseboard_fab2(sch_1):page138_i195:b" )
			)
			( pin "R4E14.1"
				( objectStatus "@baseboard_fab2_lib.baseboard_fab2(sch_1):page204_i60:a" )
			)
			( pin "R4E14.2"
				( objectStatus "@baseboard_fab2_lib.baseboard_fab2(sch_1):page204_i60:b" )
			)
			( pin "R4E16.1"
				( objectStatus "@baseboard_fab2_lib.baseboard_fab2(sch_1):page204_i61:a" )
			)
			( pin "R4E16.2"
				( objectStatus "@baseboard_fab2_lib.baseboard_fab2(sch_1):page204_i61:b" )
			)
			( pin "R4E17.1"
				( objectStatus "@baseboard_fab2_lib.baseboard_fab2(sch_1):page204_i62:a" )
			)
			( pin "R4E17.2"
				( objectStatus "@baseboard_fab2_lib.baseboard_fab2(sch_1):page204_i62:b" )
			)
			( pin "R4E15.1"
				( objectStatus "@baseboard_fab2_lib.baseboard_fab2(sch_1):page204_i63:a" )
			)
			( pin "R4E15.2"
				( objectStatus "@baseboard_fab2_lib.baseboard_fab2(sch_1):page204_i63:b" )
			)
			( pin "R4E18.1"
				( objectStatus "@baseboard_fab2_lib.baseboard_fab2(sch_1):page204_i64:a" )
			)
			( pin "R4E18.2"
				( objectStatus "@baseboard_fab2_lib.baseboard_fab2(sch_1):page204_i64:b" )
			)
			( pin "C4C12.1"
				( objectStatus "@baseboard_fab2_lib.baseboard_fab2(sch_1):page204_i67:a" )
			)
			( pin "C4C12.2"
				( objectStatus "@baseboard_fab2_lib.baseboard_fab2(sch_1):page204_i67:b" )
			)
			( pin "C6R2.1"
				( objectStatus "@baseboard_fab2_lib.baseboard_fab2(sch_1):page204_i70:a" )
			)
			( pin "C6R2.2"
				( objectStatus "@baseboard_fab2_lib.baseboard_fab2(sch_1):page204_i70:b" )
			)
			( pin "EU4C2.33"
				( objectStatus "@baseboard_fab2_lib.baseboard_fab2(sch_1):page204_i71:boost" )
			)
			( pin "EU4C2.35"
				( objectStatus "@baseboard_fab2_lib.baseboard_fab2(sch_1):page204_i71:en" )
			)
			( pin "EU4C2.6"
				( objectStatus "@baseboard_fab2_lib.baseboard_fab2(sch_1):page204_i71:gl(0)" )
			)
			( pin "EU4C2.41"
				( objectStatus "@baseboard_fab2_lib.baseboard_fab2(sch_1):page204_i71:gl(1)" )
			)
			( pin "EU4C2.38"
				( objectStatus "@baseboard_fab2_lib.baseboard_fab2(sch_1):page204_i71:iout" )
			)
			( pin "EU4C2.2"
				( objectStatus "@baseboard_fab2_lib.baseboard_fab2(sch_1):page204_i71:lgnd" )
			)
			( pin "EU4C2.31"
				( objectStatus "@baseboard_fab2_lib.baseboard_fab2(sch_1):page204_i71:nc" )
			)
			( pin "EU4C2.37"
				( objectStatus "@baseboard_fab2_lib.baseboard_fab2(sch_1):page204_i71:ocset" )
			)
			( pin "EU4C2.5"
				( objectStatus "@baseboard_fab2_lib.baseboard_fab2(sch_1):page204_i71:pgnd(0)" )
			)
			( pin "EU4C2.7"
				( objectStatus "@baseboard_fab2_lib.baseboard_fab2(sch_1):page204_i71:pgnd(1)" )
			)
			( pin "EU4C2.40"
				( objectStatus "@baseboard_fab2_lib.baseboard_fab2(sch_1):page204_i71:pgnd(2)" )
			)
			( pin "EU4C2.32"
				( objectStatus "@baseboard_fab2_lib.baseboard_fab2(sch_1):page204_i71:phase" )
			)
			( pin "EU4C2.34"
				( objectStatus "@baseboard_fab2_lib.baseboard_fab2(sch_1):page204_i71:pwm" )
			)
			( pin "EU4C2.39"
				( objectStatus "@baseboard_fab2_lib.baseboard_fab2(sch_1):page204_i71:refin" )
			)
			( pin "EU4C2.10"
				( objectStatus "@baseboard_fab2_lib.baseboard_fab2(sch_1):page204_i71:sw" )
			)
			( pin "EU4C2.36"
				( objectStatus "@baseboard_fab2_lib.baseboard_fab2(sch_1):page204_i71:tout_flt" )
			)
			( pin "EU4C2.3"
				( objectStatus "@baseboard_fab2_lib.baseboard_fab2(sch_1):page204_i71:vcc" )
			)
			( pin "EU4C2.4"
				( objectStatus "@baseboard_fab2_lib.baseboard_fab2(sch_1):page204_i71:vdrv" )
			)
			( pin "EU4C2.25"
				( objectStatus "@baseboard_fab2_lib.baseboard_fab2(sch_1):page204_i71:vin(0)" )
			)
			( pin "EU4C2.30"
				( objectStatus "@baseboard_fab2_lib.baseboard_fab2(sch_1):page204_i71:vin(1)" )
			)
			( pin "EU4C2.1"
				( objectStatus "@baseboard_fab2_lib.baseboard_fab2(sch_1):page204_i71:vos" )
			)
			( pin "R4D68.1"
				( objectStatus "@baseboard_fab2_lib.baseboard_fab2(sch_1):page204_i83:a" )
			)
			( pin "R4D68.2"
				( objectStatus "@baseboard_fab2_lib.baseboard_fab2(sch_1):page204_i83:b" )
			)
			( pin "C6N7.1"
				( objectStatus "@baseboard_fab2_lib.baseboard_fab2(sch_1):page205_i5:a" )
			)
			( pin "C6N7.2"
				( objectStatus "@baseboard_fab2_lib.baseboard_fab2(sch_1):page205_i5:b" )
			)
			( pin "L1C1.2"
				( objectStatus "@baseboard_fab2_lib.baseboard_fab2(sch_1):page210_i72:f" )
			)
			( pin "L1C1.1"
				( objectStatus "@baseboard_fab2_lib.baseboard_fab2(sch_1):page210_i72:s" )
			)
			( pin "C6N1.1"
				( objectStatus "@baseboard_fab2_lib.baseboard_fab2(sch_1):page205_i12:a" )
			)
			( pin "C6N1.2"
				( objectStatus "@baseboard_fab2_lib.baseboard_fab2(sch_1):page205_i12:b" )
			)
			( pin "C6N4.1"
				( objectStatus "@baseboard_fab2_lib.baseboard_fab2(sch_1):page205_i14:a" )
			)
			( pin "C6N4.2"
				( objectStatus "@baseboard_fab2_lib.baseboard_fab2(sch_1):page205_i14:b" )
			)
			( pin "C4C5.1"
				( objectStatus "@baseboard_fab2_lib.baseboard_fab2(sch_1):page205_i16:a" )
			)
			( pin "C4C5.2"
				( objectStatus "@baseboard_fab2_lib.baseboard_fab2(sch_1):page205_i16:b" )
			)
			( pin "C4C14.1"
				( objectStatus "@baseboard_fab2_lib.baseboard_fab2(sch_1):page204_i113:\1\" )
			)
			( pin "C4C14.2"
				( objectStatus "@baseboard_fab2_lib.baseboard_fab2(sch_1):page204_i113:\2\" )
			)
			( pin "R6P47.1"
				( objectStatus "@baseboard_fab2_lib.baseboard_fab2(sch_1):page204_i103:a" )
			)
			( pin "R6P47.2"
				( objectStatus "@baseboard_fab2_lib.baseboard_fab2(sch_1):page204_i103:b" )
			)
			( pin "C4C6.1"
				( objectStatus "@baseboard_fab2_lib.baseboard_fab2(sch_1):page205_i20:a" )
			)
			( pin "C4C6.2"
				( objectStatus "@baseboard_fab2_lib.baseboard_fab2(sch_1):page205_i20:b" )
			)
			( pin "R4C5.1"
				( objectStatus "@baseboard_fab2_lib.baseboard_fab2(sch_1):page205_i24:a" )
			)
			( pin "R4C5.2"
				( objectStatus "@baseboard_fab2_lib.baseboard_fab2(sch_1):page205_i24:b" )
			)
			( pin "C4C8.1"
				( objectStatus "@baseboard_fab2_lib.baseboard_fab2(sch_1):page205_i25:a" )
			)
			( pin "C4C8.2"
				( objectStatus "@baseboard_fab2_lib.baseboard_fab2(sch_1):page205_i25:b" )
			)
			( pin "R4C4.1"
				( objectStatus "@baseboard_fab2_lib.baseboard_fab2(sch_1):page205_i26:a" )
			)
			( pin "R4C4.2"
				( objectStatus "@baseboard_fab2_lib.baseboard_fab2(sch_1):page205_i26:b" )
			)
			( pin "R4C1.1"
				( objectStatus "@baseboard_fab2_lib.baseboard_fab2(sch_1):page205_i29:a" )
			)
			( pin "R4C1.2"
				( objectStatus "@baseboard_fab2_lib.baseboard_fab2(sch_1):page205_i29:b" )
			)
			( pin "R4C2.1"
				( objectStatus "@baseboard_fab2_lib.baseboard_fab2(sch_1):page205_i30:a" )
			)
			( pin "R4C2.2"
				( objectStatus "@baseboard_fab2_lib.baseboard_fab2(sch_1):page205_i30:b" )
			)
			( pin "C4C10.1"
				( objectStatus "@baseboard_fab2_lib.baseboard_fab2(sch_1):page205_i31:a" )
			)
			( pin "C4C10.2"
				( objectStatus "@baseboard_fab2_lib.baseboard_fab2(sch_1):page205_i31:b" )
			)
			( pin "C4C9.1"
				( objectStatus "@baseboard_fab2_lib.baseboard_fab2(sch_1):page205_i32:a" )
			)
			( pin "C4C9.2"
				( objectStatus "@baseboard_fab2_lib.baseboard_fab2(sch_1):page205_i32:b" )
			)
			( pin "C6N2.1"
				( objectStatus "@baseboard_fab2_lib.baseboard_fab2(sch_1):page205_i33:a" )
			)
			( pin "C6N2.2"
				( objectStatus "@baseboard_fab2_lib.baseboard_fab2(sch_1):page205_i33:b" )
			)
			( pin "C6N3.1"
				( objectStatus "@baseboard_fab2_lib.baseboard_fab2(sch_1):page205_i34:a" )
			)
			( pin "C6N3.2"
				( objectStatus "@baseboard_fab2_lib.baseboard_fab2(sch_1):page205_i34:b" )
			)
			( pin "C6N6.1"
				( objectStatus "@baseboard_fab2_lib.baseboard_fab2(sch_1):page205_i35:a" )
			)
			( pin "C6N6.2"
				( objectStatus "@baseboard_fab2_lib.baseboard_fab2(sch_1):page205_i35:b" )
			)
			( pin "R4C3.1"
				( objectStatus "@baseboard_fab2_lib.baseboard_fab2(sch_1):page205_i37:a" )
			)
			( pin "R4C3.2"
				( objectStatus "@baseboard_fab2_lib.baseboard_fab2(sch_1):page205_i37:b" )
			)
			( pin "C4C11.1"
				( objectStatus "@baseboard_fab2_lib.baseboard_fab2(sch_1):page205_i43:a" )
			)
			( pin "C4C11.2"
				( objectStatus "@baseboard_fab2_lib.baseboard_fab2(sch_1):page205_i43:b" )
			)
			( pin "R6N4.1"
				( objectStatus "@baseboard_fab2_lib.baseboard_fab2(sch_1):page205_i45:a" )
			)
			( pin "R6N4.2"
				( objectStatus "@baseboard_fab2_lib.baseboard_fab2(sch_1):page205_i45:b" )
			)
			( pin "EU4C1.33"
				( objectStatus "@baseboard_fab2_lib.baseboard_fab2(sch_1):page205_i46:boost" )
			)
			( pin "EU4C1.35"
				( objectStatus "@baseboard_fab2_lib.baseboard_fab2(sch_1):page205_i46:en" )
			)
			( pin "EU4C1.6"
				( objectStatus "@baseboard_fab2_lib.baseboard_fab2(sch_1):page205_i46:gl(0)" )
			)
			( pin "EU4C1.41"
				( objectStatus "@baseboard_fab2_lib.baseboard_fab2(sch_1):page205_i46:gl(1)" )
			)
			( pin "EU4C1.38"
				( objectStatus "@baseboard_fab2_lib.baseboard_fab2(sch_1):page205_i46:iout" )
			)
			( pin "EU4C1.2"
				( objectStatus "@baseboard_fab2_lib.baseboard_fab2(sch_1):page205_i46:lgnd" )
			)
			( pin "EU4C1.31"
				( objectStatus "@baseboard_fab2_lib.baseboard_fab2(sch_1):page205_i46:nc" )
			)
			( pin "EU4C1.37"
				( objectStatus "@baseboard_fab2_lib.baseboard_fab2(sch_1):page205_i46:ocset" )
			)
			( pin "EU4C1.5"
				( objectStatus "@baseboard_fab2_lib.baseboard_fab2(sch_1):page205_i46:pgnd(0)" )
			)
			( pin "EU4C1.7"
				( objectStatus "@baseboard_fab2_lib.baseboard_fab2(sch_1):page205_i46:pgnd(1)" )
			)
			( pin "EU4C1.40"
				( objectStatus "@baseboard_fab2_lib.baseboard_fab2(sch_1):page205_i46:pgnd(2)" )
			)
			( pin "EU4C1.32"
				( objectStatus "@baseboard_fab2_lib.baseboard_fab2(sch_1):page205_i46:phase" )
			)
			( pin "EU4C1.34"
				( objectStatus "@baseboard_fab2_lib.baseboard_fab2(sch_1):page205_i46:pwm" )
			)
			( pin "EU4C1.39"
				( objectStatus "@baseboard_fab2_lib.baseboard_fab2(sch_1):page205_i46:refin" )
			)
			( pin "EU4C1.10"
				( objectStatus "@baseboard_fab2_lib.baseboard_fab2(sch_1):page205_i46:sw" )
			)
			( pin "EU4C1.36"
				( objectStatus "@baseboard_fab2_lib.baseboard_fab2(sch_1):page205_i46:tout_flt" )
			)
			( pin "EU4C1.3"
				( objectStatus "@baseboard_fab2_lib.baseboard_fab2(sch_1):page205_i46:vcc" )
			)
			( pin "EU4C1.4"
				( objectStatus "@baseboard_fab2_lib.baseboard_fab2(sch_1):page205_i46:vdrv" )
			)
			( pin "EU4C1.25"
				( objectStatus "@baseboard_fab2_lib.baseboard_fab2(sch_1):page205_i46:vin(0)" )
			)
			( pin "EU4C1.30"
				( objectStatus "@baseboard_fab2_lib.baseboard_fab2(sch_1):page205_i46:vin(1)" )
			)
			( pin "EU4C1.1"
				( objectStatus "@baseboard_fab2_lib.baseboard_fab2(sch_1):page205_i46:vos" )
			)
			( pin "R4C13.1"
				( objectStatus "@baseboard_fab2_lib.baseboard_fab2(sch_1):page205_i62:a" )
			)
			( pin "R4C13.2"
				( objectStatus "@baseboard_fab2_lib.baseboard_fab2(sch_1):page205_i62:b" )
			)
			( pin "R9P1.1"
				( objectStatus "@baseboard_fab2_lib.baseboard_fab2(sch_1):page206_i4:a" )
			)
			( pin "R9P1.2"
				( objectStatus "@baseboard_fab2_lib.baseboard_fab2(sch_1):page206_i4:b" )
			)
			( pin "R1D6.1"
				( objectStatus "@baseboard_fab2_lib.baseboard_fab2(sch_1):page206_i6:a" )
			)
			( pin "R1D6.2"
				( objectStatus "@baseboard_fab2_lib.baseboard_fab2(sch_1):page206_i6:b" )
			)
			( pin "C4W4.1"
				( objectStatus "@baseboard_fab2_lib.baseboard_fab2(sch_1):page235_i246:a" )
			)
			( pin "C4W4.2"
				( objectStatus "@baseboard_fab2_lib.baseboard_fab2(sch_1):page235_i246:b" )
			)
			( pin "C1C13.1"
				( objectStatus "@baseboard_fab2_lib.baseboard_fab2(sch_1):page206_i29:a" )
			)
			( pin "C1C13.2"
				( objectStatus "@baseboard_fab2_lib.baseboard_fab2(sch_1):page206_i29:b" )
			)
			( pin "C1C14.1"
				( objectStatus "@baseboard_fab2_lib.baseboard_fab2(sch_1):page206_i31:a" )
			)
			( pin "C1C14.2"
				( objectStatus "@baseboard_fab2_lib.baseboard_fab2(sch_1):page206_i31:b" )
			)
			( pin "R1D53.1"
				( objectStatus "@baseboard_fab2_lib.baseboard_fab2(sch_1):page206_i33:a" )
			)
			( pin "R1D53.2"
				( objectStatus "@baseboard_fab2_lib.baseboard_fab2(sch_1):page206_i33:b" )
			)
			( pin "R1C18.1"
				( objectStatus "@baseboard_fab2_lib.baseboard_fab2(sch_1):page206_i34:a" )
			)
			( pin "R1C18.2"
				( objectStatus "@baseboard_fab2_lib.baseboard_fab2(sch_1):page206_i34:b" )
			)
			( pin "R1C28.1"
				( objectStatus "@baseboard_fab2_lib.baseboard_fab2(sch_1):page206_i35:a" )
			)
			( pin "R1C28.2"
				( objectStatus "@baseboard_fab2_lib.baseboard_fab2(sch_1):page206_i35:b" )
			)
			( pin "R1D8.1"
				( objectStatus "@baseboard_fab2_lib.baseboard_fab2(sch_1):page206_i36:a" )
			)
			( pin "R1D8.2"
				( objectStatus "@baseboard_fab2_lib.baseboard_fab2(sch_1):page206_i36:b" )
			)
			( pin "R1D3.1"
				( objectStatus "@baseboard_fab2_lib.baseboard_fab2(sch_1):page206_i37:a" )
			)
			( pin "R1D3.2"
				( objectStatus "@baseboard_fab2_lib.baseboard_fab2(sch_1):page206_i37:b" )
			)
			( pin "R1D2.1"
				( objectStatus "@baseboard_fab2_lib.baseboard_fab2(sch_1):page206_i38:a" )
			)
			( pin "R1D2.2"
				( objectStatus "@baseboard_fab2_lib.baseboard_fab2(sch_1):page206_i38:b" )
			)
			( pin "C1C7.1"
				( objectStatus "@baseboard_fab2_lib.baseboard_fab2(sch_1):page206_i41:a" )
			)
			( pin "C1C7.2"
				( objectStatus "@baseboard_fab2_lib.baseboard_fab2(sch_1):page206_i41:b" )
			)
			( pin "C1C9.1"
				( objectStatus "@baseboard_fab2_lib.baseboard_fab2(sch_1):page206_i42:a" )
			)
			( pin "C1C9.2"
				( objectStatus "@baseboard_fab2_lib.baseboard_fab2(sch_1):page206_i42:b" )
			)
			( pin "R1C14.1"
				( objectStatus "@baseboard_fab2_lib.baseboard_fab2(sch_1):page206_i46:a" )
			)
			( pin "R1C14.2"
				( objectStatus "@baseboard_fab2_lib.baseboard_fab2(sch_1):page206_i46:b" )
			)
			( pin "R1C13.1"
				( objectStatus "@baseboard_fab2_lib.baseboard_fab2(sch_1):page206_i49:a" )
			)
			( pin "R1C13.2"
				( objectStatus "@baseboard_fab2_lib.baseboard_fab2(sch_1):page206_i49:b" )
			)
			( pin "R9P2.1"
				( objectStatus "@baseboard_fab2_lib.baseboard_fab2(sch_1):page206_i53:a" )
			)
			( pin "R9P2.2"
				( objectStatus "@baseboard_fab2_lib.baseboard_fab2(sch_1):page206_i53:b" )
			)
			( pin "R1D9.1"
				( objectStatus "@baseboard_fab2_lib.baseboard_fab2(sch_1):page206_i54:a" )
			)
			( pin "R1D9.2"
				( objectStatus "@baseboard_fab2_lib.baseboard_fab2(sch_1):page206_i54:b" )
			)
			( pin "R1C16.1"
				( objectStatus "@baseboard_fab2_lib.baseboard_fab2(sch_1):page206_i56:a" )
			)
			( pin "R1C16.2"
				( objectStatus "@baseboard_fab2_lib.baseboard_fab2(sch_1):page206_i56:b" )
			)
			( pin "C1C16.1"
				( objectStatus "@baseboard_fab2_lib.baseboard_fab2(sch_1):page206_i68:a" )
			)
			( pin "C1C16.2"
				( objectStatus "@baseboard_fab2_lib.baseboard_fab2(sch_1):page206_i68:b" )
			)
			( pin "C1C10.1"
				( objectStatus "@baseboard_fab2_lib.baseboard_fab2(sch_1):page206_i69:a" )
			)
			( pin "C1C10.2"
				( objectStatus "@baseboard_fab2_lib.baseboard_fab2(sch_1):page206_i69:b" )
			)
			( pin "C1C11.1"
				( objectStatus "@baseboard_fab2_lib.baseboard_fab2(sch_1):page206_i71:a" )
			)
			( pin "C1C11.2"
				( objectStatus "@baseboard_fab2_lib.baseboard_fab2(sch_1):page206_i71:b" )
			)
			( pin "C3P2.1"
				( objectStatus "@baseboard_fab2_lib.baseboard_fab2(sch_1):page211_i103:a" )
			)
			( pin "C3P2.2"
				( objectStatus "@baseboard_fab2_lib.baseboard_fab2(sch_1):page211_i103:b" )
			)
			( pin "R1C21.1"
				( objectStatus "@baseboard_fab2_lib.baseboard_fab2(sch_1):page206_i77:a" )
			)
			( pin "R1C21.2"
				( objectStatus "@baseboard_fab2_lib.baseboard_fab2(sch_1):page206_i77:b" )
			)
			( pin "C1D1.1"
				( objectStatus "@baseboard_fab2_lib.baseboard_fab2(sch_1):page206_i78:a" )
			)
			( pin "C1D1.2"
				( objectStatus "@baseboard_fab2_lib.baseboard_fab2(sch_1):page206_i78:b" )
			)
			( pin "R1D4.1"
				( objectStatus "@baseboard_fab2_lib.baseboard_fab2(sch_1):page206_i79:a" )
			)
			( pin "R1D4.2"
				( objectStatus "@baseboard_fab2_lib.baseboard_fab2(sch_1):page206_i79:b" )
			)
			( pin "R9N7.1"
				( objectStatus "@baseboard_fab2_lib.baseboard_fab2(sch_1):page206_i111:a" )
			)
			( pin "R9N7.2"
				( objectStatus "@baseboard_fab2_lib.baseboard_fab2(sch_1):page206_i111:b" )
			)
			( pin "R9N8.1"
				( objectStatus "@baseboard_fab2_lib.baseboard_fab2(sch_1):page206_i112:a" )
			)
			( pin "R9N8.2"
				( objectStatus "@baseboard_fab2_lib.baseboard_fab2(sch_1):page206_i112:b" )
			)
			( pin "R1C30.1"
				( objectStatus "@baseboard_fab2_lib.baseboard_fab2(sch_1):page206_i113:a" )
			)
			( pin "R1C30.2"
				( objectStatus "@baseboard_fab2_lib.baseboard_fab2(sch_1):page206_i113:b" )
			)
			( pin "C1C23.1"
				( objectStatus "@baseboard_fab2_lib.baseboard_fab2(sch_1):page206_i114:a" )
			)
			( pin "C1C23.2"
				( objectStatus "@baseboard_fab2_lib.baseboard_fab2(sch_1):page206_i114:b" )
			)
			( pin "R1D1.1"
				( objectStatus "@baseboard_fab2_lib.baseboard_fab2(sch_1):page206_i116:a" )
			)
			( pin "R1D1.2"
				( objectStatus "@baseboard_fab2_lib.baseboard_fab2(sch_1):page206_i116:b" )
			)
			( pin "R9P3.1"
				( objectStatus "@baseboard_fab2_lib.baseboard_fab2(sch_1):page206_i117:a" )
			)
			( pin "R9P3.2"
				( objectStatus "@baseboard_fab2_lib.baseboard_fab2(sch_1):page206_i117:b" )
			)
			( pin "R9N16.1"
				( objectStatus "@baseboard_fab2_lib.baseboard_fab2(sch_1):page206_i119:a" )
			)
			( pin "R9N16.2"
				( objectStatus "@baseboard_fab2_lib.baseboard_fab2(sch_1):page206_i119:b" )
			)
			( pin "R9N14.1"
				( objectStatus "@baseboard_fab2_lib.baseboard_fab2(sch_1):page206_i120:a" )
			)
			( pin "R9N14.2"
				( objectStatus "@baseboard_fab2_lib.baseboard_fab2(sch_1):page206_i120:b" )
			)
			( pin "EU1C2.23"
				( objectStatus "@baseboard_fab2_lib.baseboard_fab2(sch_1):page206_i130:airef1" )
			)
			( pin "EU1C2.25"
				( objectStatus "@baseboard_fab2_lib.baseboard_fab2(sch_1):page206_i130:airef2" )
			)
			( pin "EU1C2.27"
				( objectStatus "@baseboard_fab2_lib.baseboard_fab2(sch_1):page206_i130:airef3" )
			)
			( pin "EU1C2.29"
				( objectStatus "@baseboard_fab2_lib.baseboard_fab2(sch_1):page206_i130:airef4" )
			)
			( pin "EU1C2.31"
				( objectStatus "@baseboard_fab2_lib.baseboard_fab2(sch_1):page206_i130:airef5" )
			)
			( pin "EU1C2.33"
				( objectStatus "@baseboard_fab2_lib.baseboard_fab2(sch_1):page206_i130:airef6" )
			)
			( pin "EU1C2.24"
				( objectStatus "@baseboard_fab2_lib.baseboard_fab2(sch_1):page206_i130:aisen1" )
			)
			( pin "EU1C2.26"
				( objectStatus "@baseboard_fab2_lib.baseboard_fab2(sch_1):page206_i130:aisen2" )
			)
			( pin "EU1C2.28"
				( objectStatus "@baseboard_fab2_lib.baseboard_fab2(sch_1):page206_i130:aisen3" )
			)
			( pin "EU1C2.30"
				( objectStatus "@baseboard_fab2_lib.baseboard_fab2(sch_1):page206_i130:aisen4" )
			)
			( pin "EU1C2.32"
				( objectStatus "@baseboard_fab2_lib.baseboard_fab2(sch_1):page206_i130:aisen5" )
			)
			( pin "EU1C2.34"
				( objectStatus "@baseboard_fab2_lib.baseboard_fab2(sch_1):page206_i130:aisen6" )
			)
			( pin "EU1C2.7"
				( objectStatus "@baseboard_fab2_lib.baseboard_fab2(sch_1):page206_i130:apwm1" )
			)
			( pin "EU1C2.6"
				( objectStatus "@baseboard_fab2_lib.baseboard_fab2(sch_1):page206_i130:apwm2" )
			)
			( pin "EU1C2.5"
				( objectStatus "@baseboard_fab2_lib.baseboard_fab2(sch_1):page206_i130:apwm3" )
			)
			( pin "EU1C2.4"
				( objectStatus "@baseboard_fab2_lib.baseboard_fab2(sch_1):page206_i130:apwm4" )
			)
			( pin "EU1C2.3"
				( objectStatus "@baseboard_fab2_lib.baseboard_fab2(sch_1):page206_i130:apwm5" )
			)
			( pin "EU1C2.2"
				( objectStatus "@baseboard_fab2_lib.baseboard_fab2(sch_1):page206_i130:apwm6" )
			)
			( pin "EU1C2.43"
				( objectStatus "@baseboard_fab2_lib.baseboard_fab2(sch_1):page206_i130:atsen" )
			)
			( pin "EU1C2.22"
				( objectStatus "@baseboard_fab2_lib.baseboard_fab2(sch_1):page206_i130:avref" )
			)
			( pin "EU1C2.12"
				( objectStatus "@baseboard_fab2_lib.baseboard_fab2(sch_1):page206_i130:avren" )
			)
			( pin "EU1C2.11"
				( objectStatus "@baseboard_fab2_lib.baseboard_fab2(sch_1):page206_i130:avrrdy" )
			)
			( pin "EU1C2.21"
				( objectStatus "@baseboard_fab2_lib.baseboard_fab2(sch_1):page206_i130:avsen" )
			)
			( pin "EU1C2.37"
				( objectStatus "@baseboard_fab2_lib.baseboard_fab2(sch_1):page206_i130:biref1" )
			)
			( pin "EU1C2.38"
				( objectStatus "@baseboard_fab2_lib.baseboard_fab2(sch_1):page206_i130:bisen1" )
			)
			( pin "EU1C2.1"
				( objectStatus "@baseboard_fab2_lib.baseboard_fab2(sch_1):page206_i130:bpwm1" )
			)
			( pin "EU1C2.42"
				( objectStatus "@baseboard_fab2_lib.baseboard_fab2(sch_1):page206_i130:btsen" )
			)
			( pin "EU1C2.36"
				( objectStatus "@baseboard_fab2_lib.baseboard_fab2(sch_1):page206_i130:bvref" )
			)
			( pin "EU1C2.35"
				( objectStatus "@baseboard_fab2_lib.baseboard_fab2(sch_1):page206_i130:bvsen" )
			)
			( pin "EU1C2.46"
				( objectStatus "@baseboard_fab2_lib.baseboard_fab2(sch_1):page206_i130:iinsen" )
			)
			( pin "EU1C2.15"
				( objectStatus "@baseboard_fab2_lib.baseboard_fab2(sch_1):page206_i130:mp0" )
			)
			( pin "EU1C2.16"
				( objectStatus "@baseboard_fab2_lib.baseboard_fab2(sch_1):page206_i130:mp1" )
			)
			( pin "EU1C2.20"
				( objectStatus "@baseboard_fab2_lib.baseboard_fab2(sch_1):page206_i130:mp2" )
			)
			( pin "EU1C2.39"
				( objectStatus "@baseboard_fab2_lib.baseboard_fab2(sch_1):page206_i130:mp3" )
			)
			( pin "EU1C2.40"
				( objectStatus "@baseboard_fab2_lib.baseboard_fab2(sch_1):page206_i130:mp4" )
			)
			( pin "EU1C2.14"
				( objectStatus "@baseboard_fab2_lib.baseboard_fab2(sch_1):page206_i130:pinalrt_n" )
			)
			( pin "EU1C2.10"
				( objectStatus "@baseboard_fab2_lib.baseboard_fab2(sch_1):page206_i130:reset_n" )
			)
			( pin "EU1C2.9"
				( objectStatus "@baseboard_fab2_lib.baseboard_fab2(sch_1):page206_i130:scl" )
			)
			( pin "EU1C2.8"
				( objectStatus "@baseboard_fab2_lib.baseboard_fab2(sch_1):page206_i130:sda" )
			)
			( pin "EU1C2.49"
				( objectStatus "@baseboard_fab2_lib.baseboard_fab2(sch_1):page206_i130:thpad" )
			)
			( pin "EU1C2.19"
				( objectStatus "@baseboard_fab2_lib.baseboard_fab2(sch_1):page206_i130:valrt_n" )
			)
			( pin "EU1C2.17"
				( objectStatus "@baseboard_fab2_lib.baseboard_fab2(sch_1):page206_i130:vclk" )
			)
			( pin "EU1C2.48"
				( objectStatus "@baseboard_fab2_lib.baseboard_fab2(sch_1):page206_i130:vd12" )
			)
			( pin "EU1C2.47"
				( objectStatus "@baseboard_fab2_lib.baseboard_fab2(sch_1):page206_i130:vdd" )
			)
			( pin "EU1C2.18"
				( objectStatus "@baseboard_fab2_lib.baseboard_fab2(sch_1):page206_i130:vdio" )
			)
			( pin "EU1C2.45"
				( objectStatus "@baseboard_fab2_lib.baseboard_fab2(sch_1):page206_i130:vinsen" )
			)
			( pin "EU1C2.13"
				( objectStatus "@baseboard_fab2_lib.baseboard_fab2(sch_1):page206_i130:vrhot_n" )
			)
			( pin "EU1C2.44"
				( objectStatus "@baseboard_fab2_lib.baseboard_fab2(sch_1):page206_i130:xaddr1" )
			)
			( pin "EU1C2.41"
				( objectStatus "@baseboard_fab2_lib.baseboard_fab2(sch_1):page206_i130:xaddr2" )
			)
			( pin "C9R8.1"
				( objectStatus "@baseboard_fab2_lib.baseboard_fab2(sch_1):page207_i8:a" )
			)
			( pin "C9R8.2"
				( objectStatus "@baseboard_fab2_lib.baseboard_fab2(sch_1):page207_i8:b" )
			)
			( pin "C1E3.1"
				( objectStatus "@baseboard_fab2_lib.baseboard_fab2(sch_1):page207_i18:a" )
			)
			( pin "C1E3.2"
				( objectStatus "@baseboard_fab2_lib.baseboard_fab2(sch_1):page207_i18:b" )
			)
			( pin "EU1E2.33"
				( objectStatus "@baseboard_fab2_lib.baseboard_fab2(sch_1):page207_i20:boost" )
			)
			( pin "EU1E2.35"
				( objectStatus "@baseboard_fab2_lib.baseboard_fab2(sch_1):page207_i20:en" )
			)
			( pin "EU1E2.6"
				( objectStatus "@baseboard_fab2_lib.baseboard_fab2(sch_1):page207_i20:gl(0)" )
			)
			( pin "EU1E2.41"
				( objectStatus "@baseboard_fab2_lib.baseboard_fab2(sch_1):page207_i20:gl(1)" )
			)
			( pin "EU1E2.38"
				( objectStatus "@baseboard_fab2_lib.baseboard_fab2(sch_1):page207_i20:iout" )
			)
			( pin "EU1E2.2"
				( objectStatus "@baseboard_fab2_lib.baseboard_fab2(sch_1):page207_i20:lgnd" )
			)
			( pin "EU1E2.31"
				( objectStatus "@baseboard_fab2_lib.baseboard_fab2(sch_1):page207_i20:nc" )
			)
			( pin "EU1E2.37"
				( objectStatus "@baseboard_fab2_lib.baseboard_fab2(sch_1):page207_i20:ocset" )
			)
			( pin "EU1E2.5"
				( objectStatus "@baseboard_fab2_lib.baseboard_fab2(sch_1):page207_i20:pgnd(0)" )
			)
			( pin "EU1E2.7"
				( objectStatus "@baseboard_fab2_lib.baseboard_fab2(sch_1):page207_i20:pgnd(1)" )
			)
			( pin "EU1E2.40"
				( objectStatus "@baseboard_fab2_lib.baseboard_fab2(sch_1):page207_i20:pgnd(2)" )
			)
			( pin "EU1E2.32"
				( objectStatus "@baseboard_fab2_lib.baseboard_fab2(sch_1):page207_i20:phase" )
			)
			( pin "EU1E2.34"
				( objectStatus "@baseboard_fab2_lib.baseboard_fab2(sch_1):page207_i20:pwm" )
			)
			( pin "EU1E2.39"
				( objectStatus "@baseboard_fab2_lib.baseboard_fab2(sch_1):page207_i20:refin" )
			)
			( pin "EU1E2.10"
				( objectStatus "@baseboard_fab2_lib.baseboard_fab2(sch_1):page207_i20:sw" )
			)
			( pin "EU1E2.36"
				( objectStatus "@baseboard_fab2_lib.baseboard_fab2(sch_1):page207_i20:tout_flt" )
			)
			( pin "EU1E2.3"
				( objectStatus "@baseboard_fab2_lib.baseboard_fab2(sch_1):page207_i20:vcc" )
			)
			( pin "EU1E2.4"
				( objectStatus "@baseboard_fab2_lib.baseboard_fab2(sch_1):page207_i20:vdrv" )
			)
			( pin "EU1E2.25"
				( objectStatus "@baseboard_fab2_lib.baseboard_fab2(sch_1):page207_i20:vin(0)" )
			)
			( pin "EU1E2.30"
				( objectStatus "@baseboard_fab2_lib.baseboard_fab2(sch_1):page207_i20:vin(1)" )
			)
			( pin "EU1E2.1"
				( objectStatus "@baseboard_fab2_lib.baseboard_fab2(sch_1):page207_i20:vos" )
			)
			( pin "R9P8.1"
				( objectStatus "@baseboard_fab2_lib.baseboard_fab2(sch_1):page208_i115:a" )
			)
			( pin "R9P8.2"
				( objectStatus "@baseboard_fab2_lib.baseboard_fab2(sch_1):page208_i115:b" )
			)
			( pin "C1E7.1"
				( objectStatus "@baseboard_fab2_lib.baseboard_fab2(sch_1):page207_i28:a" )
			)
			( pin "C1E7.2"
				( objectStatus "@baseboard_fab2_lib.baseboard_fab2(sch_1):page207_i28:b" )
			)
			( pin "C1G4.1"
				( objectStatus "@baseboard_fab2_lib.baseboard_fab2(sch_1):page224_i155:\1\" )
			)
			( pin "C1G4.2"
				( objectStatus "@baseboard_fab2_lib.baseboard_fab2(sch_1):page224_i155:\2\" )
			)
			( pin "C1E11.1"
				( objectStatus "@baseboard_fab2_lib.baseboard_fab2(sch_1):page207_i30:a" )
			)
			( pin "C1E11.2"
				( objectStatus "@baseboard_fab2_lib.baseboard_fab2(sch_1):page207_i30:b" )
			)
			( pin "C1E8.1"
				( objectStatus "@baseboard_fab2_lib.baseboard_fab2(sch_1):page207_i32:a" )
			)
			( pin "C1E8.2"
				( objectStatus "@baseboard_fab2_lib.baseboard_fab2(sch_1):page207_i32:b" )
			)
			( pin "C1E14.1"
				( objectStatus "@baseboard_fab2_lib.baseboard_fab2(sch_1):page207_i33:a" )
			)
			( pin "C1E14.2"
				( objectStatus "@baseboard_fab2_lib.baseboard_fab2(sch_1):page207_i33:b" )
			)
			( pin "C1E13.1"
				( objectStatus "@baseboard_fab2_lib.baseboard_fab2(sch_1):page207_i34:a" )
			)
			( pin "C1E13.2"
				( objectStatus "@baseboard_fab2_lib.baseboard_fab2(sch_1):page207_i34:b" )
			)
			( pin "C1E25.1"
				( objectStatus "@baseboard_fab2_lib.baseboard_fab2(sch_1):page207_i36:a" )
			)
			( pin "C1E25.2"
				( objectStatus "@baseboard_fab2_lib.baseboard_fab2(sch_1):page207_i36:b" )
			)
			( pin "C1F21.1"
				( objectStatus "@baseboard_fab2_lib.baseboard_fab2(sch_1):page224_i154:\1\" )
			)
			( pin "C1F21.2"
				( objectStatus "@baseboard_fab2_lib.baseboard_fab2(sch_1):page224_i154:\2\" )
			)
			( pin "C1D36.1"
				( objectStatus "@baseboard_fab2_lib.baseboard_fab2(sch_1):page207_i38:a" )
			)
			( pin "C1D36.2"
				( objectStatus "@baseboard_fab2_lib.baseboard_fab2(sch_1):page207_i38:b" )
			)
			( pin "R9P22.1"
				( objectStatus "@baseboard_fab2_lib.baseboard_fab2(sch_1):page208_i114:a" )
			)
			( pin "R9P22.2"
				( objectStatus "@baseboard_fab2_lib.baseboard_fab2(sch_1):page208_i114:b" )
			)
			( pin "C1E24.1"
				( objectStatus "@baseboard_fab2_lib.baseboard_fab2(sch_1):page207_i40:a" )
			)
			( pin "C1E24.2"
				( objectStatus "@baseboard_fab2_lib.baseboard_fab2(sch_1):page207_i40:b" )
			)
			( pin "C1D34.1"
				( objectStatus "@baseboard_fab2_lib.baseboard_fab2(sch_1):page207_i41:a" )
			)
			( pin "C1D34.2"
				( objectStatus "@baseboard_fab2_lib.baseboard_fab2(sch_1):page207_i41:b" )
			)
			( pin "C1D35.1"
				( objectStatus "@baseboard_fab2_lib.baseboard_fab2(sch_1):page207_i42:a" )
			)
			( pin "C1D35.2"
				( objectStatus "@baseboard_fab2_lib.baseboard_fab2(sch_1):page207_i42:b" )
			)
			( pin "C9R7.1"
				( objectStatus "@baseboard_fab2_lib.baseboard_fab2(sch_1):page207_i43:a" )
			)
			( pin "C9R7.2"
				( objectStatus "@baseboard_fab2_lib.baseboard_fab2(sch_1):page207_i43:b" )
			)
			( pin "C9R10.1"
				( objectStatus "@baseboard_fab2_lib.baseboard_fab2(sch_1):page207_i44:a" )
			)
			( pin "C9R10.2"
				( objectStatus "@baseboard_fab2_lib.baseboard_fab2(sch_1):page207_i44:b" )
			)
			( pin "C9R11.1"
				( objectStatus "@baseboard_fab2_lib.baseboard_fab2(sch_1):page207_i48:a" )
			)
			( pin "C9R11.2"
				( objectStatus "@baseboard_fab2_lib.baseboard_fab2(sch_1):page207_i48:b" )
			)
			( pin "C9P22.1"
				( objectStatus "@baseboard_fab2_lib.baseboard_fab2(sch_1):page207_i50:a" )
			)
			( pin "C9P22.2"
				( objectStatus "@baseboard_fab2_lib.baseboard_fab2(sch_1):page207_i50:b" )
			)
			( pin "C9P25.1"
				( objectStatus "@baseboard_fab2_lib.baseboard_fab2(sch_1):page207_i51:a" )
			)
			( pin "C9P25.2"
				( objectStatus "@baseboard_fab2_lib.baseboard_fab2(sch_1):page207_i51:b" )
			)
			( pin "C9P26.1"
				( objectStatus "@baseboard_fab2_lib.baseboard_fab2(sch_1):page207_i54:a" )
			)
			( pin "C9P26.2"
				( objectStatus "@baseboard_fab2_lib.baseboard_fab2(sch_1):page207_i54:b" )
			)
			( pin "C1E9.1"
				( objectStatus "@baseboard_fab2_lib.baseboard_fab2(sch_1):page207_i58:a" )
			)
			( pin "C1E9.2"
				( objectStatus "@baseboard_fab2_lib.baseboard_fab2(sch_1):page207_i58:b" )
			)
			( pin "C9P3.1"
				( objectStatus "@baseboard_fab2_lib.baseboard_fab2(sch_1):page207_i59:a" )
			)
			( pin "C9P3.2"
				( objectStatus "@baseboard_fab2_lib.baseboard_fab2(sch_1):page207_i59:b" )
			)
			( pin "R1E13.1"
				( objectStatus "@baseboard_fab2_lib.baseboard_fab2(sch_1):page207_i67:a" )
			)
			( pin "R1E13.2"
				( objectStatus "@baseboard_fab2_lib.baseboard_fab2(sch_1):page207_i67:b" )
			)
			( pin "R1E14.1"
				( objectStatus "@baseboard_fab2_lib.baseboard_fab2(sch_1):page207_i68:a" )
			)
			( pin "R1E14.2"
				( objectStatus "@baseboard_fab2_lib.baseboard_fab2(sch_1):page207_i68:b" )
			)
			( pin "R1E3.1"
				( objectStatus "@baseboard_fab2_lib.baseboard_fab2(sch_1):page208_i7:a" )
			)
			( pin "R1E3.2"
				( objectStatus "@baseboard_fab2_lib.baseboard_fab2(sch_1):page208_i7:b" )
			)
			( pin "C1D14.1"
				( objectStatus "@baseboard_fab2_lib.baseboard_fab2(sch_1):page208_i9:a" )
			)
			( pin "C1D14.2"
				( objectStatus "@baseboard_fab2_lib.baseboard_fab2(sch_1):page208_i9:b" )
			)
			( pin "J1F2.1"
				( objectStatus "@baseboard_fab2_lib.baseboard_fab2(sch_1):page161_i139:\1\" )
			)
			( pin "J1F2.2"
				( objectStatus "@baseboard_fab2_lib.baseboard_fab2(sch_1):page161_i139:\2\" )
			)
			( pin "J1F2.3"
				( objectStatus "@baseboard_fab2_lib.baseboard_fab2(sch_1):page161_i139:\3\" )
			)
			( pin "J1F2.4"
				( objectStatus "@baseboard_fab2_lib.baseboard_fab2(sch_1):page161_i139:\4\" )
			)
			( pin "J1F2.NP1"
				( objectStatus "@baseboard_fab2_lib.baseboard_fab2(sch_1):page161_i139:np1" )
			)
			( pin "C9P8.1"
				( objectStatus "@baseboard_fab2_lib.baseboard_fab2(sch_1):page208_i12:a" )
			)
			( pin "C9P8.2"
				( objectStatus "@baseboard_fab2_lib.baseboard_fab2(sch_1):page208_i12:b" )
			)
			( pin "C9P5.1"
				( objectStatus "@baseboard_fab2_lib.baseboard_fab2(sch_1):page208_i14:a" )
			)
			( pin "C9P5.2"
				( objectStatus "@baseboard_fab2_lib.baseboard_fab2(sch_1):page208_i14:b" )
			)
			( pin "L1C2.2"
				( objectStatus "@baseboard_fab2_lib.baseboard_fab2(sch_1):page209_i80:f" )
			)
			( pin "L1C2.1"
				( objectStatus "@baseboard_fab2_lib.baseboard_fab2(sch_1):page209_i80:s" )
			)
			( pin "C1D3.1"
				( objectStatus "@baseboard_fab2_lib.baseboard_fab2(sch_1):page208_i22:a" )
			)
			( pin "C1D3.2"
				( objectStatus "@baseboard_fab2_lib.baseboard_fab2(sch_1):page208_i22:b" )
			)
			( pin "C9N24.1"
				( objectStatus "@baseboard_fab2_lib.baseboard_fab2(sch_1):page208_i24:a" )
			)
			( pin "C9N24.2"
				( objectStatus "@baseboard_fab2_lib.baseboard_fab2(sch_1):page208_i24:b" )
			)
			( pin "C9R9.1"
				( objectStatus "@baseboard_fab2_lib.baseboard_fab2(sch_1):page208_i25:a" )
			)
			( pin "C9R9.2"
				( objectStatus "@baseboard_fab2_lib.baseboard_fab2(sch_1):page208_i25:b" )
			)
			( pin "C9R3.1"
				( objectStatus "@baseboard_fab2_lib.baseboard_fab2(sch_1):page208_i26:a" )
			)
			( pin "C9R3.2"
				( objectStatus "@baseboard_fab2_lib.baseboard_fab2(sch_1):page208_i26:b" )
			)
			( pin "EU1D3.33"
				( objectStatus "@baseboard_fab2_lib.baseboard_fab2(sch_1):page208_i27:boost" )
			)
			( pin "EU1D3.35"
				( objectStatus "@baseboard_fab2_lib.baseboard_fab2(sch_1):page208_i27:en" )
			)
			( pin "EU1D3.6"
				( objectStatus "@baseboard_fab2_lib.baseboard_fab2(sch_1):page208_i27:gl(0)" )
			)
			( pin "EU1D3.41"
				( objectStatus "@baseboard_fab2_lib.baseboard_fab2(sch_1):page208_i27:gl(1)" )
			)
			( pin "EU1D3.38"
				( objectStatus "@baseboard_fab2_lib.baseboard_fab2(sch_1):page208_i27:iout" )
			)
			( pin "EU1D3.2"
				( objectStatus "@baseboard_fab2_lib.baseboard_fab2(sch_1):page208_i27:lgnd" )
			)
			( pin "EU1D3.31"
				( objectStatus "@baseboard_fab2_lib.baseboard_fab2(sch_1):page208_i27:nc" )
			)
			( pin "EU1D3.37"
				( objectStatus "@baseboard_fab2_lib.baseboard_fab2(sch_1):page208_i27:ocset" )
			)
			( pin "EU1D3.5"
				( objectStatus "@baseboard_fab2_lib.baseboard_fab2(sch_1):page208_i27:pgnd(0)" )
			)
			( pin "EU1D3.7"
				( objectStatus "@baseboard_fab2_lib.baseboard_fab2(sch_1):page208_i27:pgnd(1)" )
			)
			( pin "EU1D3.40"
				( objectStatus "@baseboard_fab2_lib.baseboard_fab2(sch_1):page208_i27:pgnd(2)" )
			)
			( pin "EU1D3.32"
				( objectStatus "@baseboard_fab2_lib.baseboard_fab2(sch_1):page208_i27:phase" )
			)
			( pin "EU1D3.34"
				( objectStatus "@baseboard_fab2_lib.baseboard_fab2(sch_1):page208_i27:pwm" )
			)
			( pin "EU1D3.39"
				( objectStatus "@baseboard_fab2_lib.baseboard_fab2(sch_1):page208_i27:refin" )
			)
			( pin "EU1D3.10"
				( objectStatus "@baseboard_fab2_lib.baseboard_fab2(sch_1):page208_i27:sw" )
			)
			( pin "EU1D3.36"
				( objectStatus "@baseboard_fab2_lib.baseboard_fab2(sch_1):page208_i27:tout_flt" )
			)
			( pin "EU1D3.3"
				( objectStatus "@baseboard_fab2_lib.baseboard_fab2(sch_1):page208_i27:vcc" )
			)
			( pin "EU1D3.4"
				( objectStatus "@baseboard_fab2_lib.baseboard_fab2(sch_1):page208_i27:vdrv" )
			)
			( pin "EU1D3.25"
				( objectStatus "@baseboard_fab2_lib.baseboard_fab2(sch_1):page208_i27:vin(0)" )
			)
			( pin "EU1D3.30"
				( objectStatus "@baseboard_fab2_lib.baseboard_fab2(sch_1):page208_i27:vin(1)" )
			)
			( pin "EU1D3.1"
				( objectStatus "@baseboard_fab2_lib.baseboard_fab2(sch_1):page208_i27:vos" )
			)
			( pin "C9P23.1"
				( objectStatus "@baseboard_fab2_lib.baseboard_fab2(sch_1):page208_i28:a" )
			)
			( pin "C9P23.2"
				( objectStatus "@baseboard_fab2_lib.baseboard_fab2(sch_1):page208_i28:b" )
			)
			( pin "C9P18.1"
				( objectStatus "@baseboard_fab2_lib.baseboard_fab2(sch_1):page208_i30:a" )
			)
			( pin "C9P18.2"
				( objectStatus "@baseboard_fab2_lib.baseboard_fab2(sch_1):page208_i30:b" )
			)
			( pin "R3U9.1"
				( objectStatus "@baseboard_fab2_lib.baseboard_fab2(sch_1):page216_i146:a" )
			)
			( pin "R3U9.2"
				( objectStatus "@baseboard_fab2_lib.baseboard_fab2(sch_1):page216_i146:b" )
			)
			( pin "C1D16.1"
				( objectStatus "@baseboard_fab2_lib.baseboard_fab2(sch_1):page208_i38:a" )
			)
			( pin "C1D16.2"
				( objectStatus "@baseboard_fab2_lib.baseboard_fab2(sch_1):page208_i38:b" )
			)
			( pin "C1E6.1"
				( objectStatus "@baseboard_fab2_lib.baseboard_fab2(sch_1):page207_i110:\1\" )
			)
			( pin "C1E6.2"
				( objectStatus "@baseboard_fab2_lib.baseboard_fab2(sch_1):page207_i110:\2\" )
			)
			( pin "C1D20.1"
				( objectStatus "@baseboard_fab2_lib.baseboard_fab2(sch_1):page208_i40:a" )
			)
			( pin "C1D20.2"
				( objectStatus "@baseboard_fab2_lib.baseboard_fab2(sch_1):page208_i40:b" )
			)
			( pin "C1D17.1"
				( objectStatus "@baseboard_fab2_lib.baseboard_fab2(sch_1):page208_i43:a" )
			)
			( pin "C1D17.2"
				( objectStatus "@baseboard_fab2_lib.baseboard_fab2(sch_1):page208_i43:b" )
			)
			( pin "C1D28.1"
				( objectStatus "@baseboard_fab2_lib.baseboard_fab2(sch_1):page208_i44:a" )
			)
			( pin "C1D28.2"
				( objectStatus "@baseboard_fab2_lib.baseboard_fab2(sch_1):page208_i44:b" )
			)
			( pin "C1D23.1"
				( objectStatus "@baseboard_fab2_lib.baseboard_fab2(sch_1):page208_i45:a" )
			)
			( pin "C1D23.2"
				( objectStatus "@baseboard_fab2_lib.baseboard_fab2(sch_1):page208_i45:b" )
			)
			( pin "C1D6.1"
				( objectStatus "@baseboard_fab2_lib.baseboard_fab2(sch_1):page208_i46:a" )
			)
			( pin "C1D6.2"
				( objectStatus "@baseboard_fab2_lib.baseboard_fab2(sch_1):page208_i46:b" )
			)
			( pin "C1E23.1"
				( objectStatus "@baseboard_fab2_lib.baseboard_fab2(sch_1):page207_i109:\1\" )
			)
			( pin "C1E23.2"
				( objectStatus "@baseboard_fab2_lib.baseboard_fab2(sch_1):page207_i109:\2\" )
			)
			( pin "C1D10.1"
				( objectStatus "@baseboard_fab2_lib.baseboard_fab2(sch_1):page208_i48:a" )
			)
			( pin "C1D10.2"
				( objectStatus "@baseboard_fab2_lib.baseboard_fab2(sch_1):page208_i48:b" )
			)
			( pin "R9P32.1"
				( objectStatus "@baseboard_fab2_lib.baseboard_fab2(sch_1):page209_i79:a" )
			)
			( pin "R9P32.2"
				( objectStatus "@baseboard_fab2_lib.baseboard_fab2(sch_1):page209_i79:b" )
			)
			( pin "C1D7.1"
				( objectStatus "@baseboard_fab2_lib.baseboard_fab2(sch_1):page208_i50:a" )
			)
			( pin "C1D7.2"
				( objectStatus "@baseboard_fab2_lib.baseboard_fab2(sch_1):page208_i50:b" )
			)
			( pin "C1D13.1"
				( objectStatus "@baseboard_fab2_lib.baseboard_fab2(sch_1):page208_i51:a" )
			)
			( pin "C1D13.2"
				( objectStatus "@baseboard_fab2_lib.baseboard_fab2(sch_1):page208_i51:b" )
			)
			( pin "C1D12.1"
				( objectStatus "@baseboard_fab2_lib.baseboard_fab2(sch_1):page208_i52:a" )
			)
			( pin "C1D12.2"
				( objectStatus "@baseboard_fab2_lib.baseboard_fab2(sch_1):page208_i52:b" )
			)
			( pin "C9P4.1"
				( objectStatus "@baseboard_fab2_lib.baseboard_fab2(sch_1):page208_i53:a" )
			)
			( pin "C9P4.2"
				( objectStatus "@baseboard_fab2_lib.baseboard_fab2(sch_1):page208_i53:b" )
			)
			( pin "C9P7.1"
				( objectStatus "@baseboard_fab2_lib.baseboard_fab2(sch_1):page208_i54:a" )
			)
			( pin "C9P7.2"
				( objectStatus "@baseboard_fab2_lib.baseboard_fab2(sch_1):page208_i54:b" )
			)
			( pin "C9P9.1"
				( objectStatus "@baseboard_fab2_lib.baseboard_fab2(sch_1):page208_i55:a" )
			)
			( pin "C9P9.2"
				( objectStatus "@baseboard_fab2_lib.baseboard_fab2(sch_1):page208_i55:b" )
			)
			( pin "C9P24.1"
				( objectStatus "@baseboard_fab2_lib.baseboard_fab2(sch_1):page208_i58:a" )
			)
			( pin "C9P24.2"
				( objectStatus "@baseboard_fab2_lib.baseboard_fab2(sch_1):page208_i58:b" )
			)
			( pin "C9P1.1"
				( objectStatus "@baseboard_fab2_lib.baseboard_fab2(sch_1):page208_i59:a" )
			)
			( pin "C9P1.2"
				( objectStatus "@baseboard_fab2_lib.baseboard_fab2(sch_1):page208_i59:b" )
			)
			( pin "C9P2.1"
				( objectStatus "@baseboard_fab2_lib.baseboard_fab2(sch_1):page208_i60:a" )
			)
			( pin "C9P2.2"
				( objectStatus "@baseboard_fab2_lib.baseboard_fab2(sch_1):page208_i60:b" )
			)
			( pin "C9P10.1"
				( objectStatus "@baseboard_fab2_lib.baseboard_fab2(sch_1):page208_i66:a" )
			)
			( pin "C9P10.2"
				( objectStatus "@baseboard_fab2_lib.baseboard_fab2(sch_1):page208_i66:b" )
			)
			( pin "C9R2.1"
				( objectStatus "@baseboard_fab2_lib.baseboard_fab2(sch_1):page208_i67:a" )
			)
			( pin "C9R2.2"
				( objectStatus "@baseboard_fab2_lib.baseboard_fab2(sch_1):page208_i67:b" )
			)
			( pin "EU1D1.33"
				( objectStatus "@baseboard_fab2_lib.baseboard_fab2(sch_1):page208_i71:boost" )
			)
			( pin "EU1D1.35"
				( objectStatus "@baseboard_fab2_lib.baseboard_fab2(sch_1):page208_i71:en" )
			)
			( pin "EU1D1.6"
				( objectStatus "@baseboard_fab2_lib.baseboard_fab2(sch_1):page208_i71:gl(0)" )
			)
			( pin "EU1D1.41"
				( objectStatus "@baseboard_fab2_lib.baseboard_fab2(sch_1):page208_i71:gl(1)" )
			)
			( pin "EU1D1.38"
				( objectStatus "@baseboard_fab2_lib.baseboard_fab2(sch_1):page208_i71:iout" )
			)
			( pin "EU1D1.2"
				( objectStatus "@baseboard_fab2_lib.baseboard_fab2(sch_1):page208_i71:lgnd" )
			)
			( pin "EU1D1.31"
				( objectStatus "@baseboard_fab2_lib.baseboard_fab2(sch_1):page208_i71:nc" )
			)
			( pin "EU1D1.37"
				( objectStatus "@baseboard_fab2_lib.baseboard_fab2(sch_1):page208_i71:ocset" )
			)
			( pin "EU1D1.5"
				( objectStatus "@baseboard_fab2_lib.baseboard_fab2(sch_1):page208_i71:pgnd(0)" )
			)
			( pin "EU1D1.7"
				( objectStatus "@baseboard_fab2_lib.baseboard_fab2(sch_1):page208_i71:pgnd(1)" )
			)
			( pin "EU1D1.40"
				( objectStatus "@baseboard_fab2_lib.baseboard_fab2(sch_1):page208_i71:pgnd(2)" )
			)
			( pin "EU1D1.32"
				( objectStatus "@baseboard_fab2_lib.baseboard_fab2(sch_1):page208_i71:phase" )
			)
			( pin "EU1D1.34"
				( objectStatus "@baseboard_fab2_lib.baseboard_fab2(sch_1):page208_i71:pwm" )
			)
			( pin "EU1D1.39"
				( objectStatus "@baseboard_fab2_lib.baseboard_fab2(sch_1):page208_i71:refin" )
			)
			( pin "EU1D1.10"
				( objectStatus "@baseboard_fab2_lib.baseboard_fab2(sch_1):page208_i71:sw" )
			)
			( pin "EU1D1.36"
				( objectStatus "@baseboard_fab2_lib.baseboard_fab2(sch_1):page208_i71:tout_flt" )
			)
			( pin "EU1D1.3"
				( objectStatus "@baseboard_fab2_lib.baseboard_fab2(sch_1):page208_i71:vcc" )
			)
			( pin "EU1D1.4"
				( objectStatus "@baseboard_fab2_lib.baseboard_fab2(sch_1):page208_i71:vdrv" )
			)
			( pin "EU1D1.25"
				( objectStatus "@baseboard_fab2_lib.baseboard_fab2(sch_1):page208_i71:vin(0)" )
			)
			( pin "EU1D1.30"
				( objectStatus "@baseboard_fab2_lib.baseboard_fab2(sch_1):page208_i71:vin(1)" )
			)
			( pin "EU1D1.1"
				( objectStatus "@baseboard_fab2_lib.baseboard_fab2(sch_1):page208_i71:vos" )
			)
			( pin "R1D54.1"
				( objectStatus "@baseboard_fab2_lib.baseboard_fab2(sch_1):page208_i75:a" )
			)
			( pin "R1D54.2"
				( objectStatus "@baseboard_fab2_lib.baseboard_fab2(sch_1):page208_i75:b" )
			)
			( pin "R1D55.1"
				( objectStatus "@baseboard_fab2_lib.baseboard_fab2(sch_1):page208_i76:a" )
			)
			( pin "R1D55.2"
				( objectStatus "@baseboard_fab2_lib.baseboard_fab2(sch_1):page208_i76:b" )
			)
			( pin "R1E5.1"
				( objectStatus "@baseboard_fab2_lib.baseboard_fab2(sch_1):page209_i3:a" )
			)
			( pin "R1E5.2"
				( objectStatus "@baseboard_fab2_lib.baseboard_fab2(sch_1):page209_i3:b" )
			)
			( pin "C9N27.1"
				( objectStatus "@baseboard_fab2_lib.baseboard_fab2(sch_1):page209_i5:a" )
			)
			( pin "C9N27.2"
				( objectStatus "@baseboard_fab2_lib.baseboard_fab2(sch_1):page209_i5:b" )
			)
			( pin "C9N26.1"
				( objectStatus "@baseboard_fab2_lib.baseboard_fab2(sch_1):page209_i7:a" )
			)
			( pin "C9N26.2"
				( objectStatus "@baseboard_fab2_lib.baseboard_fab2(sch_1):page209_i7:b" )
			)
			( pin "C9N25.1"
				( objectStatus "@baseboard_fab2_lib.baseboard_fab2(sch_1):page209_i8:a" )
			)
			( pin "C9N25.2"
				( objectStatus "@baseboard_fab2_lib.baseboard_fab2(sch_1):page209_i8:b" )
			)
			( pin "R1E8.1"
				( objectStatus "@baseboard_fab2_lib.baseboard_fab2(sch_1):page209_i9:a" )
			)
			( pin "R1E8.2"
				( objectStatus "@baseboard_fab2_lib.baseboard_fab2(sch_1):page209_i9:b" )
			)
			( pin "R1E7.1"
				( objectStatus "@baseboard_fab2_lib.baseboard_fab2(sch_1):page209_i10:a" )
			)
			( pin "R1E7.2"
				( objectStatus "@baseboard_fab2_lib.baseboard_fab2(sch_1):page209_i10:b" )
			)
			( pin "R1E6.1"
				( objectStatus "@baseboard_fab2_lib.baseboard_fab2(sch_1):page209_i11:a" )
			)
			( pin "R1E6.2"
				( objectStatus "@baseboard_fab2_lib.baseboard_fab2(sch_1):page209_i11:b" )
			)
			( pin "R1E4.1"
				( objectStatus "@baseboard_fab2_lib.baseboard_fab2(sch_1):page209_i15:a" )
			)
			( pin "R1E4.2"
				( objectStatus "@baseboard_fab2_lib.baseboard_fab2(sch_1):page209_i15:b" )
			)
			( pin "C1C26.1"
				( objectStatus "@baseboard_fab2_lib.baseboard_fab2(sch_1):page209_i16:a" )
			)
			( pin "C1C26.2"
				( objectStatus "@baseboard_fab2_lib.baseboard_fab2(sch_1):page209_i16:b" )
			)
			( pin "C1C25.1"
				( objectStatus "@baseboard_fab2_lib.baseboard_fab2(sch_1):page209_i17:a" )
			)
			( pin "C1C25.2"
				( objectStatus "@baseboard_fab2_lib.baseboard_fab2(sch_1):page209_i17:b" )
			)
			( pin "C1D32.1"
				( objectStatus "@baseboard_fab2_lib.baseboard_fab2(sch_1):page209_i18:a" )
			)
			( pin "C1D32.2"
				( objectStatus "@baseboard_fab2_lib.baseboard_fab2(sch_1):page209_i18:b" )
			)
			( pin "C1C24.1"
				( objectStatus "@baseboard_fab2_lib.baseboard_fab2(sch_1):page209_i20:a" )
			)
			( pin "C1C24.2"
				( objectStatus "@baseboard_fab2_lib.baseboard_fab2(sch_1):page209_i20:b" )
			)
			( pin "C1A11.1"
				( objectStatus "@baseboard_fab2_lib.baseboard_fab2(sch_1):page227_i147:\1\" )
			)
			( pin "C1A11.2"
				( objectStatus "@baseboard_fab2_lib.baseboard_fab2(sch_1):page227_i147:\2\" )
			)
			( pin "C1D33.1"
				( objectStatus "@baseboard_fab2_lib.baseboard_fab2(sch_1):page209_i22:a" )
			)
			( pin "C1D33.2"
				( objectStatus "@baseboard_fab2_lib.baseboard_fab2(sch_1):page209_i22:b" )
			)
			( pin "R9N3.1"
				( objectStatus "@baseboard_fab2_lib.baseboard_fab2(sch_1):page210_i71:a" )
			)
			( pin "R9N3.2"
				( objectStatus "@baseboard_fab2_lib.baseboard_fab2(sch_1):page210_i71:b" )
			)
			( pin "R3P7.1"
				( objectStatus "@baseboard_fab2_lib.baseboard_fab2(sch_1):page133_i370:a" )
			)
			( pin "R3P7.2"
				( objectStatus "@baseboard_fab2_lib.baseboard_fab2(sch_1):page133_i370:b" )
			)
			( pin "L7F2.2"
				( objectStatus "@baseboard_fab2_lib.baseboard_fab2(sch_1):page217_i261:f" )
			)
			( pin "L7F2.1"
				( objectStatus "@baseboard_fab2_lib.baseboard_fab2(sch_1):page217_i261:s" )
			)
			( pin "C1C1.1"
				( objectStatus "@baseboard_fab2_lib.baseboard_fab2(sch_1):page209_i35:a" )
			)
			( pin "C1C1.2"
				( objectStatus "@baseboard_fab2_lib.baseboard_fab2(sch_1):page209_i35:b" )
			)
			( pin "C1E18.1"
				( objectStatus "@baseboard_fab2_lib.baseboard_fab2(sch_1):page209_i37:a" )
			)
			( pin "C1E18.2"
				( objectStatus "@baseboard_fab2_lib.baseboard_fab2(sch_1):page209_i37:b" )
			)
			( pin "C1C2.1"
				( objectStatus "@baseboard_fab2_lib.baseboard_fab2(sch_1):page209_i38:a" )
			)
			( pin "C1C2.2"
				( objectStatus "@baseboard_fab2_lib.baseboard_fab2(sch_1):page209_i38:b" )
			)
			( pin "L7A1.2"
				( objectStatus "@baseboard_fab2_lib.baseboard_fab2(sch_1):page219_i157:f" )
			)
			( pin "L7A1.1"
				( objectStatus "@baseboard_fab2_lib.baseboard_fab2(sch_1):page219_i157:s" )
			)
			( pin "C1D24.1"
				( objectStatus "@baseboard_fab2_lib.baseboard_fab2(sch_1):page209_i42:a" )
			)
			( pin "C1D24.2"
				( objectStatus "@baseboard_fab2_lib.baseboard_fab2(sch_1):page209_i42:b" )
			)
			( pin "C9P20.1"
				( objectStatus "@baseboard_fab2_lib.baseboard_fab2(sch_1):page209_i55:a" )
			)
			( pin "C9P20.2"
				( objectStatus "@baseboard_fab2_lib.baseboard_fab2(sch_1):page209_i55:b" )
			)
			( pin "EU1C3.33"
				( objectStatus "@baseboard_fab2_lib.baseboard_fab2(sch_1):page209_i56:boost" )
			)
			( pin "EU1C3.35"
				( objectStatus "@baseboard_fab2_lib.baseboard_fab2(sch_1):page209_i56:en" )
			)
			( pin "EU1C3.6"
				( objectStatus "@baseboard_fab2_lib.baseboard_fab2(sch_1):page209_i56:gl(0)" )
			)
			( pin "EU1C3.41"
				( objectStatus "@baseboard_fab2_lib.baseboard_fab2(sch_1):page209_i56:gl(1)" )
			)
			( pin "EU1C3.38"
				( objectStatus "@baseboard_fab2_lib.baseboard_fab2(sch_1):page209_i56:iout" )
			)
			( pin "EU1C3.2"
				( objectStatus "@baseboard_fab2_lib.baseboard_fab2(sch_1):page209_i56:lgnd" )
			)
			( pin "EU1C3.31"
				( objectStatus "@baseboard_fab2_lib.baseboard_fab2(sch_1):page209_i56:nc" )
			)
			( pin "EU1C3.37"
				( objectStatus "@baseboard_fab2_lib.baseboard_fab2(sch_1):page209_i56:ocset" )
			)
			( pin "EU1C3.5"
				( objectStatus "@baseboard_fab2_lib.baseboard_fab2(sch_1):page209_i56:pgnd(0)" )
			)
			( pin "EU1C3.7"
				( objectStatus "@baseboard_fab2_lib.baseboard_fab2(sch_1):page209_i56:pgnd(1)" )
			)
			( pin "EU1C3.40"
				( objectStatus "@baseboard_fab2_lib.baseboard_fab2(sch_1):page209_i56:pgnd(2)" )
			)
			( pin "EU1C3.32"
				( objectStatus "@baseboard_fab2_lib.baseboard_fab2(sch_1):page209_i56:phase" )
			)
			( pin "EU1C3.34"
				( objectStatus "@baseboard_fab2_lib.baseboard_fab2(sch_1):page209_i56:pwm" )
			)
			( pin "EU1C3.39"
				( objectStatus "@baseboard_fab2_lib.baseboard_fab2(sch_1):page209_i56:refin" )
			)
			( pin "EU1C3.10"
				( objectStatus "@baseboard_fab2_lib.baseboard_fab2(sch_1):page209_i56:sw" )
			)
			( pin "EU1C3.36"
				( objectStatus "@baseboard_fab2_lib.baseboard_fab2(sch_1):page209_i56:tout_flt" )
			)
			( pin "EU1C3.3"
				( objectStatus "@baseboard_fab2_lib.baseboard_fab2(sch_1):page209_i56:vcc" )
			)
			( pin "EU1C3.4"
				( objectStatus "@baseboard_fab2_lib.baseboard_fab2(sch_1):page209_i56:vdrv" )
			)
			( pin "EU1C3.25"
				( objectStatus "@baseboard_fab2_lib.baseboard_fab2(sch_1):page209_i56:vin(0)" )
			)
			( pin "EU1C3.30"
				( objectStatus "@baseboard_fab2_lib.baseboard_fab2(sch_1):page209_i56:vin(1)" )
			)
			( pin "EU1C3.1"
				( objectStatus "@baseboard_fab2_lib.baseboard_fab2(sch_1):page209_i56:vos" )
			)
			( pin "R1D52.1"
				( objectStatus "@baseboard_fab2_lib.baseboard_fab2(sch_1):page209_i59:a" )
			)
			( pin "R1D52.2"
				( objectStatus "@baseboard_fab2_lib.baseboard_fab2(sch_1):page209_i59:b" )
			)
			( pin "C1C19.1"
				( objectStatus "@baseboard_fab2_lib.baseboard_fab2(sch_1):page210_i8:a" )
			)
			( pin "C1C19.2"
				( objectStatus "@baseboard_fab2_lib.baseboard_fab2(sch_1):page210_i8:b" )
			)
			( pin "L7A2.2"
				( objectStatus "@baseboard_fab2_lib.baseboard_fab2(sch_1):page236_i178:f" )
			)
			( pin "L7A2.1"
				( objectStatus "@baseboard_fab2_lib.baseboard_fab2(sch_1):page236_i178:s" )
			)
			( pin "C9N11.1"
				( objectStatus "@baseboard_fab2_lib.baseboard_fab2(sch_1):page210_i12:a" )
			)
			( pin "C9N11.2"
				( objectStatus "@baseboard_fab2_lib.baseboard_fab2(sch_1):page210_i12:b" )
			)
			( pin "C9N20.1"
				( objectStatus "@baseboard_fab2_lib.baseboard_fab2(sch_1):page210_i14:a" )
			)
			( pin "C9N20.2"
				( objectStatus "@baseboard_fab2_lib.baseboard_fab2(sch_1):page210_i14:b" )
			)
			( pin "R3N7.1"
				( objectStatus "@baseboard_fab2_lib.baseboard_fab2(sch_1):page212_i140:a" )
			)
			( pin "R3N7.2"
				( objectStatus "@baseboard_fab2_lib.baseboard_fab2(sch_1):page212_i140:b" )
			)
			( pin "C1C4.1"
				( objectStatus "@baseboard_fab2_lib.baseboard_fab2(sch_1):page210_i22:a" )
			)
			( pin "C1C4.2"
				( objectStatus "@baseboard_fab2_lib.baseboard_fab2(sch_1):page210_i22:b" )
			)
			( pin "C1D15.1"
				( objectStatus "@baseboard_fab2_lib.baseboard_fab2(sch_1):page208_i118:\1\" )
			)
			( pin "C1D15.2"
				( objectStatus "@baseboard_fab2_lib.baseboard_fab2(sch_1):page208_i118:\2\" )
			)
			( pin "C1C12.1"
				( objectStatus "@baseboard_fab2_lib.baseboard_fab2(sch_1):page210_i24:a" )
			)
			( pin "C1C12.2"
				( objectStatus "@baseboard_fab2_lib.baseboard_fab2(sch_1):page210_i24:b" )
			)
			( pin "C1C5.1"
				( objectStatus "@baseboard_fab2_lib.baseboard_fab2(sch_1):page210_i26:a" )
			)
			( pin "C1C5.2"
				( objectStatus "@baseboard_fab2_lib.baseboard_fab2(sch_1):page210_i26:b" )
			)
			( pin "C1C17.1"
				( objectStatus "@baseboard_fab2_lib.baseboard_fab2(sch_1):page210_i27:a" )
			)
			( pin "C1C17.2"
				( objectStatus "@baseboard_fab2_lib.baseboard_fab2(sch_1):page210_i27:b" )
			)
			( pin "C1C15.1"
				( objectStatus "@baseboard_fab2_lib.baseboard_fab2(sch_1):page210_i28:a" )
			)
			( pin "C1C15.2"
				( objectStatus "@baseboard_fab2_lib.baseboard_fab2(sch_1):page210_i28:b" )
			)
			( pin "R1C12.1"
				( objectStatus "@baseboard_fab2_lib.baseboard_fab2(sch_1):page210_i29:a" )
			)
			( pin "R1C12.2"
				( objectStatus "@baseboard_fab2_lib.baseboard_fab2(sch_1):page210_i29:b" )
			)
			( pin "R1C7.1"
				( objectStatus "@baseboard_fab2_lib.baseboard_fab2(sch_1):page210_i31:a" )
			)
			( pin "R1C7.2"
				( objectStatus "@baseboard_fab2_lib.baseboard_fab2(sch_1):page210_i31:b" )
			)
			( pin "R1C5.1"
				( objectStatus "@baseboard_fab2_lib.baseboard_fab2(sch_1):page210_i32:a" )
			)
			( pin "R1C5.2"
				( objectStatus "@baseboard_fab2_lib.baseboard_fab2(sch_1):page210_i32:b" )
			)
			( pin "R1C4.1"
				( objectStatus "@baseboard_fab2_lib.baseboard_fab2(sch_1):page210_i33:a" )
			)
			( pin "R1C4.2"
				( objectStatus "@baseboard_fab2_lib.baseboard_fab2(sch_1):page210_i33:b" )
			)
			( pin "R1C6.1"
				( objectStatus "@baseboard_fab2_lib.baseboard_fab2(sch_1):page210_i34:a" )
			)
			( pin "R1C6.2"
				( objectStatus "@baseboard_fab2_lib.baseboard_fab2(sch_1):page210_i34:b" )
			)
			( pin "C9N13.1"
				( objectStatus "@baseboard_fab2_lib.baseboard_fab2(sch_1):page210_i35:a" )
			)
			( pin "C9N13.2"
				( objectStatus "@baseboard_fab2_lib.baseboard_fab2(sch_1):page210_i35:b" )
			)
			( pin "C9N19.1"
				( objectStatus "@baseboard_fab2_lib.baseboard_fab2(sch_1):page210_i36:a" )
			)
			( pin "C9N19.2"
				( objectStatus "@baseboard_fab2_lib.baseboard_fab2(sch_1):page210_i36:b" )
			)
			( pin "C9N21.1"
				( objectStatus "@baseboard_fab2_lib.baseboard_fab2(sch_1):page210_i38:a" )
			)
			( pin "C9N21.2"
				( objectStatus "@baseboard_fab2_lib.baseboard_fab2(sch_1):page210_i38:b" )
			)
			( pin "C9N22.1"
				( objectStatus "@baseboard_fab2_lib.baseboard_fab2(sch_1):page210_i44:a" )
			)
			( pin "C9N22.2"
				( objectStatus "@baseboard_fab2_lib.baseboard_fab2(sch_1):page210_i44:b" )
			)
			( pin "R9N4.1"
				( objectStatus "@baseboard_fab2_lib.baseboard_fab2(sch_1):page210_i45:a" )
			)
			( pin "R9N4.2"
				( objectStatus "@baseboard_fab2_lib.baseboard_fab2(sch_1):page210_i45:b" )
			)
			( pin "EU1C1.33"
				( objectStatus "@baseboard_fab2_lib.baseboard_fab2(sch_1):page210_i51:boost" )
			)
			( pin "EU1C1.35"
				( objectStatus "@baseboard_fab2_lib.baseboard_fab2(sch_1):page210_i51:en" )
			)
			( pin "EU1C1.6"
				( objectStatus "@baseboard_fab2_lib.baseboard_fab2(sch_1):page210_i51:gl(0)" )
			)
			( pin "EU1C1.41"
				( objectStatus "@baseboard_fab2_lib.baseboard_fab2(sch_1):page210_i51:gl(1)" )
			)
			( pin "EU1C1.38"
				( objectStatus "@baseboard_fab2_lib.baseboard_fab2(sch_1):page210_i51:iout" )
			)
			( pin "EU1C1.2"
				( objectStatus "@baseboard_fab2_lib.baseboard_fab2(sch_1):page210_i51:lgnd" )
			)
			( pin "EU1C1.31"
				( objectStatus "@baseboard_fab2_lib.baseboard_fab2(sch_1):page210_i51:nc" )
			)
			( pin "EU1C1.37"
				( objectStatus "@baseboard_fab2_lib.baseboard_fab2(sch_1):page210_i51:ocset" )
			)
			( pin "EU1C1.5"
				( objectStatus "@baseboard_fab2_lib.baseboard_fab2(sch_1):page210_i51:pgnd(0)" )
			)
			( pin "EU1C1.7"
				( objectStatus "@baseboard_fab2_lib.baseboard_fab2(sch_1):page210_i51:pgnd(1)" )
			)
			( pin "EU1C1.40"
				( objectStatus "@baseboard_fab2_lib.baseboard_fab2(sch_1):page210_i51:pgnd(2)" )
			)
			( pin "EU1C1.32"
				( objectStatus "@baseboard_fab2_lib.baseboard_fab2(sch_1):page210_i51:phase" )
			)
			( pin "EU1C1.34"
				( objectStatus "@baseboard_fab2_lib.baseboard_fab2(sch_1):page210_i51:pwm" )
			)
			( pin "EU1C1.39"
				( objectStatus "@baseboard_fab2_lib.baseboard_fab2(sch_1):page210_i51:refin" )
			)
			( pin "EU1C1.10"
				( objectStatus "@baseboard_fab2_lib.baseboard_fab2(sch_1):page210_i51:sw" )
			)
			( pin "EU1C1.36"
				( objectStatus "@baseboard_fab2_lib.baseboard_fab2(sch_1):page210_i51:tout_flt" )
			)
			( pin "EU1C1.3"
				( objectStatus "@baseboard_fab2_lib.baseboard_fab2(sch_1):page210_i51:vcc" )
			)
			( pin "EU1C1.4"
				( objectStatus "@baseboard_fab2_lib.baseboard_fab2(sch_1):page210_i51:vdrv" )
			)
			( pin "EU1C1.25"
				( objectStatus "@baseboard_fab2_lib.baseboard_fab2(sch_1):page210_i51:vin(0)" )
			)
			( pin "EU1C1.30"
				( objectStatus "@baseboard_fab2_lib.baseboard_fab2(sch_1):page210_i51:vin(1)" )
			)
			( pin "EU1C1.1"
				( objectStatus "@baseboard_fab2_lib.baseboard_fab2(sch_1):page210_i51:vos" )
			)
			( pin "R1C37.1"
				( objectStatus "@baseboard_fab2_lib.baseboard_fab2(sch_1):page210_i52:a" )
			)
			( pin "R1C37.2"
				( objectStatus "@baseboard_fab2_lib.baseboard_fab2(sch_1):page210_i52:b" )
			)
			( pin "C3P4.1"
				( objectStatus "@baseboard_fab2_lib.baseboard_fab2(sch_1):page211_i11:a" )
			)
			( pin "C3P4.2"
				( objectStatus "@baseboard_fab2_lib.baseboard_fab2(sch_1):page211_i11:b" )
			)
			( pin "C3P5.1"
				( objectStatus "@baseboard_fab2_lib.baseboard_fab2(sch_1):page211_i13:a" )
			)
			( pin "C3P5.2"
				( objectStatus "@baseboard_fab2_lib.baseboard_fab2(sch_1):page211_i13:b" )
			)
			( pin "R3P11.1"
				( objectStatus "@baseboard_fab2_lib.baseboard_fab2(sch_1):page211_i16:a" )
			)
			( pin "R3P11.2"
				( objectStatus "@baseboard_fab2_lib.baseboard_fab2(sch_1):page211_i16:b" )
			)
			( pin "R3T11.1"
				( objectStatus "@baseboard_fab2_lib.baseboard_fab2(sch_1):page215_i70:a" )
			)
			( pin "R3T11.2"
				( objectStatus "@baseboard_fab2_lib.baseboard_fab2(sch_1):page215_i70:b" )
			)
			( pin "C3P3.1"
				( objectStatus "@baseboard_fab2_lib.baseboard_fab2(sch_1):page211_i20:a" )
			)
			( pin "C3P3.2"
				( objectStatus "@baseboard_fab2_lib.baseboard_fab2(sch_1):page211_i20:b" )
			)
			( pin "C3P7.1"
				( objectStatus "@baseboard_fab2_lib.baseboard_fab2(sch_1):page211_i22:a" )
			)
			( pin "C3P7.2"
				( objectStatus "@baseboard_fab2_lib.baseboard_fab2(sch_1):page211_i22:b" )
			)
			( pin "R3P22.1"
				( objectStatus "@baseboard_fab2_lib.baseboard_fab2(sch_1):page211_i24:a" )
			)
			( pin "R3P22.2"
				( objectStatus "@baseboard_fab2_lib.baseboard_fab2(sch_1):page211_i24:b" )
			)
			( pin "R3P13.1"
				( objectStatus "@baseboard_fab2_lib.baseboard_fab2(sch_1):page211_i100:a" )
			)
			( pin "R3P13.2"
				( objectStatus "@baseboard_fab2_lib.baseboard_fab2(sch_1):page211_i100:b" )
			)
			( pin "R3P15.1"
				( objectStatus "@baseboard_fab2_lib.baseboard_fab2(sch_1):page211_i29:a" )
			)
			( pin "R3P15.2"
				( objectStatus "@baseboard_fab2_lib.baseboard_fab2(sch_1):page211_i29:b" )
			)
			( pin "R3P12.1"
				( objectStatus "@baseboard_fab2_lib.baseboard_fab2(sch_1):page211_i31:a" )
			)
			( pin "R3P12.2"
				( objectStatus "@baseboard_fab2_lib.baseboard_fab2(sch_1):page211_i31:b" )
			)
			( pin "R3P16.1"
				( objectStatus "@baseboard_fab2_lib.baseboard_fab2(sch_1):page211_i32:a" )
			)
			( pin "R3P16.2"
				( objectStatus "@baseboard_fab2_lib.baseboard_fab2(sch_1):page211_i32:b" )
			)
			( pin "C4D40.1"
				( objectStatus "@baseboard_fab2_lib.baseboard_fab2(sch_1):page213_i105:a" )
			)
			( pin "C4D40.2"
				( objectStatus "@baseboard_fab2_lib.baseboard_fab2(sch_1):page213_i105:b" )
			)
			( pin "R3N31.1"
				( objectStatus "@baseboard_fab2_lib.baseboard_fab2(sch_1):page211_i52:a" )
			)
			( pin "R3N31.2"
				( objectStatus "@baseboard_fab2_lib.baseboard_fab2(sch_1):page211_i52:b" )
			)
			( pin "R3P25.1"
				( objectStatus "@baseboard_fab2_lib.baseboard_fab2(sch_1):page211_i56:a" )
			)
			( pin "R3P25.2"
				( objectStatus "@baseboard_fab2_lib.baseboard_fab2(sch_1):page211_i56:b" )
			)
			( pin "R3P20.1"
				( objectStatus "@baseboard_fab2_lib.baseboard_fab2(sch_1):page211_i58:a" )
			)
			( pin "R3P20.2"
				( objectStatus "@baseboard_fab2_lib.baseboard_fab2(sch_1):page211_i58:b" )
			)
			( pin "R3N23.1"
				( objectStatus "@baseboard_fab2_lib.baseboard_fab2(sch_1):page211_i60:a" )
			)
			( pin "R3N23.2"
				( objectStatus "@baseboard_fab2_lib.baseboard_fab2(sch_1):page211_i60:b" )
			)
			( pin "R3P1.1"
				( objectStatus "@baseboard_fab2_lib.baseboard_fab2(sch_1):page211_i61:a" )
			)
			( pin "R3P1.2"
				( objectStatus "@baseboard_fab2_lib.baseboard_fab2(sch_1):page211_i61:b" )
			)
			( pin "R3P18.1"
				( objectStatus "@baseboard_fab2_lib.baseboard_fab2(sch_1):page211_i64:a" )
			)
			( pin "R3P18.2"
				( objectStatus "@baseboard_fab2_lib.baseboard_fab2(sch_1):page211_i64:b" )
			)
			( pin "R7G10.1"
				( objectStatus "@baseboard_fab2_lib.baseboard_fab2(sch_1):page215_i73:a" )
			)
			( pin "R7G10.2"
				( objectStatus "@baseboard_fab2_lib.baseboard_fab2(sch_1):page215_i73:b" )
			)
			( pin "C3P6.1"
				( objectStatus "@baseboard_fab2_lib.baseboard_fab2(sch_1):page211_i71:a" )
			)
			( pin "C3P6.2"
				( objectStatus "@baseboard_fab2_lib.baseboard_fab2(sch_1):page211_i71:b" )
			)
			( pin "R3N19.1"
				( objectStatus "@baseboard_fab2_lib.baseboard_fab2(sch_1):page211_i81:a" )
			)
			( pin "R3N19.2"
				( objectStatus "@baseboard_fab2_lib.baseboard_fab2(sch_1):page211_i81:b" )
			)
			( pin "C3N39.1"
				( objectStatus "@baseboard_fab2_lib.baseboard_fab2(sch_1):page211_i83:a" )
			)
			( pin "C3N39.2"
				( objectStatus "@baseboard_fab2_lib.baseboard_fab2(sch_1):page211_i83:b" )
			)
			( pin "R3P26.1"
				( objectStatus "@baseboard_fab2_lib.baseboard_fab2(sch_1):page211_i87:a" )
			)
			( pin "R3P26.2"
				( objectStatus "@baseboard_fab2_lib.baseboard_fab2(sch_1):page211_i87:b" )
			)
			( pin "R3P21.1"
				( objectStatus "@baseboard_fab2_lib.baseboard_fab2(sch_1):page211_i88:a" )
			)
			( pin "R3P21.2"
				( objectStatus "@baseboard_fab2_lib.baseboard_fab2(sch_1):page211_i88:b" )
			)
			( pin "EU3P1.21"
				( objectStatus "@baseboard_fab2_lib.baseboard_fab2(sch_1):page211_i93:airef1" )
			)
			( pin "EU3P1.22"
				( objectStatus "@baseboard_fab2_lib.baseboard_fab2(sch_1):page211_i93:aisen1" )
			)
			( pin "EU3P1.5"
				( objectStatus "@baseboard_fab2_lib.baseboard_fab2(sch_1):page211_i93:apwm1" )
			)
			( pin "EU3P1.35"
				( objectStatus "@baseboard_fab2_lib.baseboard_fab2(sch_1):page211_i93:atsen" )
			)
			( pin "EU3P1.20"
				( objectStatus "@baseboard_fab2_lib.baseboard_fab2(sch_1):page211_i93:avref" )
			)
			( pin "EU3P1.10"
				( objectStatus "@baseboard_fab2_lib.baseboard_fab2(sch_1):page211_i93:avren" )
			)
			( pin "EU3P1.9"
				( objectStatus "@baseboard_fab2_lib.baseboard_fab2(sch_1):page211_i93:avrrdy" )
			)
			( pin "EU3P1.19"
				( objectStatus "@baseboard_fab2_lib.baseboard_fab2(sch_1):page211_i93:avsen" )
			)
			( pin "EU3P1.25"
				( objectStatus "@baseboard_fab2_lib.baseboard_fab2(sch_1):page211_i93:biref1" )
			)
			( pin "EU3P1.26"
				( objectStatus "@baseboard_fab2_lib.baseboard_fab2(sch_1):page211_i93:bisen1" )
			)
			( pin "EU3P1.3"
				( objectStatus "@baseboard_fab2_lib.baseboard_fab2(sch_1):page211_i93:bpwm1" )
			)
			( pin "EU3P1.34"
				( objectStatus "@baseboard_fab2_lib.baseboard_fab2(sch_1):page211_i93:btsen" )
			)
			( pin "EU3P1.30"
				( objectStatus "@baseboard_fab2_lib.baseboard_fab2(sch_1):page211_i93:bvref" )
			)
			( pin "EU3P1.29"
				( objectStatus "@baseboard_fab2_lib.baseboard_fab2(sch_1):page211_i93:bvsen" )
			)
			( pin "EU3P1.1"
				( objectStatus "@baseboard_fab2_lib.baseboard_fab2(sch_1):page211_i93:dnc(0)" )
			)
			( pin "EU3P1.2"
				( objectStatus "@baseboard_fab2_lib.baseboard_fab2(sch_1):page211_i93:dnc(1)" )
			)
			( pin "EU3P1.4"
				( objectStatus "@baseboard_fab2_lib.baseboard_fab2(sch_1):page211_i93:dnc(2)" )
			)
			( pin "EU3P1.24"
				( objectStatus "@baseboard_fab2_lib.baseboard_fab2(sch_1):page211_i93:dnc(3)" )
			)
			( pin "EU3P1.28"
				( objectStatus "@baseboard_fab2_lib.baseboard_fab2(sch_1):page211_i93:dnc(4)" )
			)
			( pin "EU3P1.27"
				( objectStatus "@baseboard_fab2_lib.baseboard_fab2(sch_1):page211_i93:gnd(0)" )
			)
			( pin "EU3P1.23"
				( objectStatus "@baseboard_fab2_lib.baseboard_fab2(sch_1):page211_i93:gnd(1)" )
			)
			( pin "EU3P1.38"
				( objectStatus "@baseboard_fab2_lib.baseboard_fab2(sch_1):page211_i93:iinsen" )
			)
			( pin "EU3P1.13"
				( objectStatus "@baseboard_fab2_lib.baseboard_fab2(sch_1):page211_i93:mp0" )
			)
			( pin "EU3P1.14"
				( objectStatus "@baseboard_fab2_lib.baseboard_fab2(sch_1):page211_i93:mp1" )
			)
			( pin "EU3P1.18"
				( objectStatus "@baseboard_fab2_lib.baseboard_fab2(sch_1):page211_i93:mp2" )
			)
			( pin "EU3P1.31"
				( objectStatus "@baseboard_fab2_lib.baseboard_fab2(sch_1):page211_i93:mp3" )
			)
			( pin "EU3P1.32"
				( objectStatus "@baseboard_fab2_lib.baseboard_fab2(sch_1):page211_i93:mp4" )
			)
			( pin "EU3P1.12"
				( objectStatus "@baseboard_fab2_lib.baseboard_fab2(sch_1):page211_i93:pinalrt_n" )
			)
			( pin "EU3P1.8"
				( objectStatus "@baseboard_fab2_lib.baseboard_fab2(sch_1):page211_i93:reset_n" )
			)
			( pin "EU3P1.7"
				( objectStatus "@baseboard_fab2_lib.baseboard_fab2(sch_1):page211_i93:scl" )
			)
			( pin "EU3P1.6"
				( objectStatus "@baseboard_fab2_lib.baseboard_fab2(sch_1):page211_i93:sda" )
			)
			( pin "EU3P1.41"
				( objectStatus "@baseboard_fab2_lib.baseboard_fab2(sch_1):page211_i93:thpad" )
			)
			( pin "EU3P1.17"
				( objectStatus "@baseboard_fab2_lib.baseboard_fab2(sch_1):page211_i93:valrt_n" )
			)
			( pin "EU3P1.15"
				( objectStatus "@baseboard_fab2_lib.baseboard_fab2(sch_1):page211_i93:vclk" )
			)
			( pin "EU3P1.40"
				( objectStatus "@baseboard_fab2_lib.baseboard_fab2(sch_1):page211_i93:vd12" )
			)
			( pin "EU3P1.39"
				( objectStatus "@baseboard_fab2_lib.baseboard_fab2(sch_1):page211_i93:vdd" )
			)
			( pin "EU3P1.16"
				( objectStatus "@baseboard_fab2_lib.baseboard_fab2(sch_1):page211_i93:vdio" )
			)
			( pin "EU3P1.37"
				( objectStatus "@baseboard_fab2_lib.baseboard_fab2(sch_1):page211_i93:vinsen" )
			)
			( pin "EU3P1.11"
				( objectStatus "@baseboard_fab2_lib.baseboard_fab2(sch_1):page211_i93:vrhot_n" )
			)
			( pin "EU3P1.36"
				( objectStatus "@baseboard_fab2_lib.baseboard_fab2(sch_1):page211_i93:xaddr1" )
			)
			( pin "EU3P1.33"
				( objectStatus "@baseboard_fab2_lib.baseboard_fab2(sch_1):page211_i93:xaddr2" )
			)
			( pin "C4E7.1"
				( objectStatus "@baseboard_fab2_lib.baseboard_fab2(sch_1):page214_i178:a" )
			)
			( pin "C4E7.2"
				( objectStatus "@baseboard_fab2_lib.baseboard_fab2(sch_1):page214_i178:b" )
			)
			( pin "C6R12.1"
				( objectStatus "@baseboard_fab2_lib.baseboard_fab2(sch_1):page214_i177:a" )
			)
			( pin "C6R12.2"
				( objectStatus "@baseboard_fab2_lib.baseboard_fab2(sch_1):page214_i177:b" )
			)
			( pin "C3N35.1"
				( objectStatus "@baseboard_fab2_lib.baseboard_fab2(sch_1):page212_i18:a" )
			)
			( pin "C3N35.2"
				( objectStatus "@baseboard_fab2_lib.baseboard_fab2(sch_1):page212_i18:b" )
			)
			( pin "C7C6.1"
				( objectStatus "@baseboard_fab2_lib.baseboard_fab2(sch_1):page212_i23:a" )
			)
			( pin "C7C6.2"
				( objectStatus "@baseboard_fab2_lib.baseboard_fab2(sch_1):page212_i23:b" )
			)
			( pin "L7A4.2"
				( objectStatus "@baseboard_fab2_lib.baseboard_fab2(sch_1):page236_i179:f" )
			)
			( pin "L7A4.1"
				( objectStatus "@baseboard_fab2_lib.baseboard_fab2(sch_1):page236_i179:s" )
			)
			( pin "R6R5.1"
				( objectStatus "@baseboard_fab2_lib.baseboard_fab2(sch_1):page214_i173:a" )
			)
			( pin "R6R5.2"
				( objectStatus "@baseboard_fab2_lib.baseboard_fab2(sch_1):page214_i173:b" )
			)
			( pin "C7C18.1"
				( objectStatus "@baseboard_fab2_lib.baseboard_fab2(sch_1):page212_i33:a" )
			)
			( pin "C7C18.2"
				( objectStatus "@baseboard_fab2_lib.baseboard_fab2(sch_1):page212_i33:b" )
			)
			( pin "C7G35.1"
				( objectStatus "@baseboard_fab2_lib.baseboard_fab2(sch_1):page216_i149:\1\" )
			)
			( pin "C7G35.2"
				( objectStatus "@baseboard_fab2_lib.baseboard_fab2(sch_1):page216_i149:\2\" )
			)
			( pin "C7C17.1"
				( objectStatus "@baseboard_fab2_lib.baseboard_fab2(sch_1):page212_i36:a" )
			)
			( pin "C7C17.2"
				( objectStatus "@baseboard_fab2_lib.baseboard_fab2(sch_1):page212_i36:b" )
			)
			( pin "C7C14.1"
				( objectStatus "@baseboard_fab2_lib.baseboard_fab2(sch_1):page212_i37:a" )
			)
			( pin "C7C14.2"
				( objectStatus "@baseboard_fab2_lib.baseboard_fab2(sch_1):page212_i37:b" )
			)
			( pin "C7C11.1"
				( objectStatus "@baseboard_fab2_lib.baseboard_fab2(sch_1):page212_i38:a" )
			)
			( pin "C7C11.2"
				( objectStatus "@baseboard_fab2_lib.baseboard_fab2(sch_1):page212_i38:b" )
			)
			( pin "C7C12.1"
				( objectStatus "@baseboard_fab2_lib.baseboard_fab2(sch_1):page212_i39:a" )
			)
			( pin "C7C12.2"
				( objectStatus "@baseboard_fab2_lib.baseboard_fab2(sch_1):page212_i39:b" )
			)
			( pin "C3N36.1"
				( objectStatus "@baseboard_fab2_lib.baseboard_fab2(sch_1):page212_i40:a" )
			)
			( pin "C3N36.2"
				( objectStatus "@baseboard_fab2_lib.baseboard_fab2(sch_1):page212_i40:b" )
			)
			( pin "C3N33.1"
				( objectStatus "@baseboard_fab2_lib.baseboard_fab2(sch_1):page212_i41:a" )
			)
			( pin "C3N33.2"
				( objectStatus "@baseboard_fab2_lib.baseboard_fab2(sch_1):page212_i41:b" )
			)
			( pin "C3N34.1"
				( objectStatus "@baseboard_fab2_lib.baseboard_fab2(sch_1):page212_i43:a" )
			)
			( pin "C3N34.2"
				( objectStatus "@baseboard_fab2_lib.baseboard_fab2(sch_1):page212_i43:b" )
			)
			( pin "R6P10.1"
				( objectStatus "@baseboard_fab2_lib.baseboard_fab2(sch_1):page203_i129:a" )
			)
			( pin "R6P10.2"
				( objectStatus "@baseboard_fab2_lib.baseboard_fab2(sch_1):page203_i129:b" )
			)
			( pin "R6P19.1"
				( objectStatus "@baseboard_fab2_lib.baseboard_fab2(sch_1):page203_i128:a" )
			)
			( pin "R6P19.2"
				( objectStatus "@baseboard_fab2_lib.baseboard_fab2(sch_1):page203_i128:b" )
			)
			( pin "L4E2.2"
				( objectStatus "@baseboard_fab2_lib.baseboard_fab2(sch_1):page214_i174:f" )
			)
			( pin "L4E2.1"
				( objectStatus "@baseboard_fab2_lib.baseboard_fab2(sch_1):page214_i174:s" )
			)
			( pin "C3P1.1"
				( objectStatus "@baseboard_fab2_lib.baseboard_fab2(sch_1):page212_i60:a" )
			)
			( pin "C3P1.2"
				( objectStatus "@baseboard_fab2_lib.baseboard_fab2(sch_1):page212_i60:b" )
			)
			( pin "R3N20.1"
				( objectStatus "@baseboard_fab2_lib.baseboard_fab2(sch_1):page212_i68:a" )
			)
			( pin "R3N20.2"
				( objectStatus "@baseboard_fab2_lib.baseboard_fab2(sch_1):page212_i68:b" )
			)
			( pin "R3N21.1"
				( objectStatus "@baseboard_fab2_lib.baseboard_fab2(sch_1):page212_i74:a" )
			)
			( pin "R3N21.2"
				( objectStatus "@baseboard_fab2_lib.baseboard_fab2(sch_1):page212_i74:b" )
			)
			( pin "C7C10.1"
				( objectStatus "@baseboard_fab2_lib.baseboard_fab2(sch_1):page212_i77:a" )
			)
			( pin "C7C10.2"
				( objectStatus "@baseboard_fab2_lib.baseboard_fab2(sch_1):page212_i77:b" )
			)
			( pin "R7C3.1"
				( objectStatus "@baseboard_fab2_lib.baseboard_fab2(sch_1):page212_i78:a" )
			)
			( pin "R7C3.2"
				( objectStatus "@baseboard_fab2_lib.baseboard_fab2(sch_1):page212_i78:b" )
			)
			( pin "EU7C1.33"
				( objectStatus "@baseboard_fab2_lib.baseboard_fab2(sch_1):page212_i101:boost" )
			)
			( pin "EU7C1.35"
				( objectStatus "@baseboard_fab2_lib.baseboard_fab2(sch_1):page212_i101:en" )
			)
			( pin "EU7C1.6"
				( objectStatus "@baseboard_fab2_lib.baseboard_fab2(sch_1):page212_i101:gl(0)" )
			)
			( pin "EU7C1.41"
				( objectStatus "@baseboard_fab2_lib.baseboard_fab2(sch_1):page212_i101:gl(1)" )
			)
			( pin "EU7C1.38"
				( objectStatus "@baseboard_fab2_lib.baseboard_fab2(sch_1):page212_i101:iout" )
			)
			( pin "EU7C1.2"
				( objectStatus "@baseboard_fab2_lib.baseboard_fab2(sch_1):page212_i101:lgnd" )
			)
			( pin "EU7C1.31"
				( objectStatus "@baseboard_fab2_lib.baseboard_fab2(sch_1):page212_i101:nc" )
			)
			( pin "EU7C1.37"
				( objectStatus "@baseboard_fab2_lib.baseboard_fab2(sch_1):page212_i101:ocset" )
			)
			( pin "EU7C1.5"
				( objectStatus "@baseboard_fab2_lib.baseboard_fab2(sch_1):page212_i101:pgnd(0)" )
			)
			( pin "EU7C1.7"
				( objectStatus "@baseboard_fab2_lib.baseboard_fab2(sch_1):page212_i101:pgnd(1)" )
			)
			( pin "EU7C1.40"
				( objectStatus "@baseboard_fab2_lib.baseboard_fab2(sch_1):page212_i101:pgnd(2)" )
			)
			( pin "EU7C1.32"
				( objectStatus "@baseboard_fab2_lib.baseboard_fab2(sch_1):page212_i101:phase" )
			)
			( pin "EU7C1.34"
				( objectStatus "@baseboard_fab2_lib.baseboard_fab2(sch_1):page212_i101:pwm" )
			)
			( pin "EU7C1.39"
				( objectStatus "@baseboard_fab2_lib.baseboard_fab2(sch_1):page212_i101:refin" )
			)
			( pin "EU7C1.10"
				( objectStatus "@baseboard_fab2_lib.baseboard_fab2(sch_1):page212_i101:sw" )
			)
			( pin "EU7C1.36"
				( objectStatus "@baseboard_fab2_lib.baseboard_fab2(sch_1):page212_i101:tout_flt" )
			)
			( pin "EU7C1.3"
				( objectStatus "@baseboard_fab2_lib.baseboard_fab2(sch_1):page212_i101:vcc" )
			)
			( pin "EU7C1.4"
				( objectStatus "@baseboard_fab2_lib.baseboard_fab2(sch_1):page212_i101:vdrv" )
			)
			( pin "EU7C1.25"
				( objectStatus "@baseboard_fab2_lib.baseboard_fab2(sch_1):page212_i101:vin(0)" )
			)
			( pin "EU7C1.30"
				( objectStatus "@baseboard_fab2_lib.baseboard_fab2(sch_1):page212_i101:vin(1)" )
			)
			( pin "EU7C1.1"
				( objectStatus "@baseboard_fab2_lib.baseboard_fab2(sch_1):page212_i101:vos" )
			)
			( pin "R7C25.1"
				( objectStatus "@baseboard_fab2_lib.baseboard_fab2(sch_1):page212_i103:a" )
			)
			( pin "R7C25.2"
				( objectStatus "@baseboard_fab2_lib.baseboard_fab2(sch_1):page212_i103:b" )
			)
			( pin "SH3P1.1"
				( objectStatus "@baseboard_fab2_lib.baseboard_fab2(sch_1):page212_i104:a" )
			)
			( pin "SH3P1.2"
				( objectStatus "@baseboard_fab2_lib.baseboard_fab2(sch_1):page212_i104:b" )
			)
			( pin "SH3P2.1"
				( objectStatus "@baseboard_fab2_lib.baseboard_fab2(sch_1):page212_i105:a" )
			)
			( pin "SH3P2.2"
				( objectStatus "@baseboard_fab2_lib.baseboard_fab2(sch_1):page212_i105:b" )
			)
			( pin "C4D31.1"
				( objectStatus "@baseboard_fab2_lib.baseboard_fab2(sch_1):page213_i9:a" )
			)
			( pin "C4D31.2"
				( objectStatus "@baseboard_fab2_lib.baseboard_fab2(sch_1):page213_i9:b" )
			)
			( pin "C4D32.1"
				( objectStatus "@baseboard_fab2_lib.baseboard_fab2(sch_1):page213_i11:a" )
			)
			( pin "C4D32.2"
				( objectStatus "@baseboard_fab2_lib.baseboard_fab2(sch_1):page213_i11:b" )
			)
			( pin "R4D46.1"
				( objectStatus "@baseboard_fab2_lib.baseboard_fab2(sch_1):page213_i13:a" )
			)
			( pin "R4D46.2"
				( objectStatus "@baseboard_fab2_lib.baseboard_fab2(sch_1):page213_i13:b" )
			)
			( pin "R6P49.1"
				( objectStatus "@baseboard_fab2_lib.baseboard_fab2(sch_1):page213_i14:a" )
			)
			( pin "R6P49.2"
				( objectStatus "@baseboard_fab2_lib.baseboard_fab2(sch_1):page213_i14:b" )
			)
			( pin "R4D42.1"
				( objectStatus "@baseboard_fab2_lib.baseboard_fab2(sch_1):page213_i15:a" )
			)
			( pin "R4D42.2"
				( objectStatus "@baseboard_fab2_lib.baseboard_fab2(sch_1):page213_i15:b" )
			)
			( pin "R4D56.1"
				( objectStatus "@baseboard_fab2_lib.baseboard_fab2(sch_1):page213_i16:a" )
			)
			( pin "R4D56.2"
				( objectStatus "@baseboard_fab2_lib.baseboard_fab2(sch_1):page213_i16:b" )
			)
			( pin "C4D36.1"
				( objectStatus "@baseboard_fab2_lib.baseboard_fab2(sch_1):page213_i17:a" )
			)
			( pin "C4D36.2"
				( objectStatus "@baseboard_fab2_lib.baseboard_fab2(sch_1):page213_i17:b" )
			)
			( pin "R4D47.1"
				( objectStatus "@baseboard_fab2_lib.baseboard_fab2(sch_1):page213_i25:a" )
			)
			( pin "R4D47.2"
				( objectStatus "@baseboard_fab2_lib.baseboard_fab2(sch_1):page213_i25:b" )
			)
			( pin "R6P35.1"
				( objectStatus "@baseboard_fab2_lib.baseboard_fab2(sch_1):page213_i27:a" )
			)
			( pin "R6P35.2"
				( objectStatus "@baseboard_fab2_lib.baseboard_fab2(sch_1):page213_i27:b" )
			)
			( pin "R6P33.1"
				( objectStatus "@baseboard_fab2_lib.baseboard_fab2(sch_1):page213_i30:a" )
			)
			( pin "R6P33.2"
				( objectStatus "@baseboard_fab2_lib.baseboard_fab2(sch_1):page213_i30:b" )
			)
			( pin "R4D60.1"
				( objectStatus "@baseboard_fab2_lib.baseboard_fab2(sch_1):page213_i31:a" )
			)
			( pin "R4D60.2"
				( objectStatus "@baseboard_fab2_lib.baseboard_fab2(sch_1):page213_i31:b" )
			)
			( pin "R4D57.1"
				( objectStatus "@baseboard_fab2_lib.baseboard_fab2(sch_1):page213_i32:a" )
			)
			( pin "R4D57.2"
				( objectStatus "@baseboard_fab2_lib.baseboard_fab2(sch_1):page213_i32:b" )
			)
			( pin "C8A3.1"
				( objectStatus "@baseboard_fab2_lib.baseboard_fab2(sch_1):page235_i255:a" )
			)
			( pin "C8A3.2"
				( objectStatus "@baseboard_fab2_lib.baseboard_fab2(sch_1):page235_i255:b" )
			)
			( pin "C4D38.1"
				( objectStatus "@baseboard_fab2_lib.baseboard_fab2(sch_1):page213_i35:a" )
			)
			( pin "C4D38.2"
				( objectStatus "@baseboard_fab2_lib.baseboard_fab2(sch_1):page213_i35:b" )
			)
			( pin "R4D54.1"
				( objectStatus "@baseboard_fab2_lib.baseboard_fab2(sch_1):page213_i37:a" )
			)
			( pin "R4D54.2"
				( objectStatus "@baseboard_fab2_lib.baseboard_fab2(sch_1):page213_i37:b" )
			)
			( pin "R1G23.1"
				( objectStatus "@baseboard_fab2_lib.baseboard_fab2(sch_1):page223_i73:a" )
			)
			( pin "R1G23.2"
				( objectStatus "@baseboard_fab2_lib.baseboard_fab2(sch_1):page223_i73:b" )
			)
			( pin "R4D51.1"
				( objectStatus "@baseboard_fab2_lib.baseboard_fab2(sch_1):page213_i46:a" )
			)
			( pin "R4D51.2"
				( objectStatus "@baseboard_fab2_lib.baseboard_fab2(sch_1):page213_i46:b" )
			)
			( pin "R4D49.1"
				( objectStatus "@baseboard_fab2_lib.baseboard_fab2(sch_1):page213_i63:a" )
			)
			( pin "R4D49.2"
				( objectStatus "@baseboard_fab2_lib.baseboard_fab2(sch_1):page213_i63:b" )
			)
			( pin "R7A8.1"
				( objectStatus "@baseboard_fab2_lib.baseboard_fab2(sch_1):page218_i74:a" )
			)
			( pin "R7A8.2"
				( objectStatus "@baseboard_fab2_lib.baseboard_fab2(sch_1):page218_i74:b" )
			)
			( pin "C4D33.1"
				( objectStatus "@baseboard_fab2_lib.baseboard_fab2(sch_1):page213_i73:a" )
			)
			( pin "C4D33.2"
				( objectStatus "@baseboard_fab2_lib.baseboard_fab2(sch_1):page213_i73:b" )
			)
			( pin "C4D44.1"
				( objectStatus "@baseboard_fab2_lib.baseboard_fab2(sch_1):page213_i83:a" )
			)
			( pin "C4D44.2"
				( objectStatus "@baseboard_fab2_lib.baseboard_fab2(sch_1):page213_i83:b" )
			)
			( pin "R4E7.1"
				( objectStatus "@baseboard_fab2_lib.baseboard_fab2(sch_1):page213_i84:a" )
			)
			( pin "R4E7.2"
				( objectStatus "@baseboard_fab2_lib.baseboard_fab2(sch_1):page213_i84:b" )
			)
			( pin "R6P41.1"
				( objectStatus "@baseboard_fab2_lib.baseboard_fab2(sch_1):page213_i90:a" )
			)
			( pin "R6P41.2"
				( objectStatus "@baseboard_fab2_lib.baseboard_fab2(sch_1):page213_i90:b" )
			)
			( pin "R6P40.1"
				( objectStatus "@baseboard_fab2_lib.baseboard_fab2(sch_1):page213_i91:a" )
			)
			( pin "R6P40.2"
				( objectStatus "@baseboard_fab2_lib.baseboard_fab2(sch_1):page213_i91:b" )
			)
			( pin "EU4D5.21"
				( objectStatus "@baseboard_fab2_lib.baseboard_fab2(sch_1):page213_i96:airef1" )
			)
			( pin "EU4D5.22"
				( objectStatus "@baseboard_fab2_lib.baseboard_fab2(sch_1):page213_i96:aisen1" )
			)
			( pin "EU4D5.5"
				( objectStatus "@baseboard_fab2_lib.baseboard_fab2(sch_1):page213_i96:apwm1" )
			)
			( pin "EU4D5.35"
				( objectStatus "@baseboard_fab2_lib.baseboard_fab2(sch_1):page213_i96:atsen" )
			)
			( pin "EU4D5.20"
				( objectStatus "@baseboard_fab2_lib.baseboard_fab2(sch_1):page213_i96:avref" )
			)
			( pin "EU4D5.10"
				( objectStatus "@baseboard_fab2_lib.baseboard_fab2(sch_1):page213_i96:avren" )
			)
			( pin "EU4D5.9"
				( objectStatus "@baseboard_fab2_lib.baseboard_fab2(sch_1):page213_i96:avrrdy" )
			)
			( pin "EU4D5.19"
				( objectStatus "@baseboard_fab2_lib.baseboard_fab2(sch_1):page213_i96:avsen" )
			)
			( pin "EU4D5.25"
				( objectStatus "@baseboard_fab2_lib.baseboard_fab2(sch_1):page213_i96:biref1" )
			)
			( pin "EU4D5.26"
				( objectStatus "@baseboard_fab2_lib.baseboard_fab2(sch_1):page213_i96:bisen1" )
			)
			( pin "EU4D5.3"
				( objectStatus "@baseboard_fab2_lib.baseboard_fab2(sch_1):page213_i96:bpwm1" )
			)
			( pin "EU4D5.34"
				( objectStatus "@baseboard_fab2_lib.baseboard_fab2(sch_1):page213_i96:btsen" )
			)
			( pin "EU4D5.30"
				( objectStatus "@baseboard_fab2_lib.baseboard_fab2(sch_1):page213_i96:bvref" )
			)
			( pin "EU4D5.29"
				( objectStatus "@baseboard_fab2_lib.baseboard_fab2(sch_1):page213_i96:bvsen" )
			)
			( pin "EU4D5.1"
				( objectStatus "@baseboard_fab2_lib.baseboard_fab2(sch_1):page213_i96:dnc(0)" )
			)
			( pin "EU4D5.2"
				( objectStatus "@baseboard_fab2_lib.baseboard_fab2(sch_1):page213_i96:dnc(1)" )
			)
			( pin "EU4D5.4"
				( objectStatus "@baseboard_fab2_lib.baseboard_fab2(sch_1):page213_i96:dnc(2)" )
			)
			( pin "EU4D5.24"
				( objectStatus "@baseboard_fab2_lib.baseboard_fab2(sch_1):page213_i96:dnc(3)" )
			)
			( pin "EU4D5.28"
				( objectStatus "@baseboard_fab2_lib.baseboard_fab2(sch_1):page213_i96:dnc(4)" )
			)
			( pin "EU4D5.27"
				( objectStatus "@baseboard_fab2_lib.baseboard_fab2(sch_1):page213_i96:gnd(0)" )
			)
			( pin "EU4D5.23"
				( objectStatus "@baseboard_fab2_lib.baseboard_fab2(sch_1):page213_i96:gnd(1)" )
			)
			( pin "EU4D5.38"
				( objectStatus "@baseboard_fab2_lib.baseboard_fab2(sch_1):page213_i96:iinsen" )
			)
			( pin "EU4D5.13"
				( objectStatus "@baseboard_fab2_lib.baseboard_fab2(sch_1):page213_i96:mp0" )
			)
			( pin "EU4D5.14"
				( objectStatus "@baseboard_fab2_lib.baseboard_fab2(sch_1):page213_i96:mp1" )
			)
			( pin "EU4D5.18"
				( objectStatus "@baseboard_fab2_lib.baseboard_fab2(sch_1):page213_i96:mp2" )
			)
			( pin "EU4D5.31"
				( objectStatus "@baseboard_fab2_lib.baseboard_fab2(sch_1):page213_i96:mp3" )
			)
			( pin "EU4D5.32"
				( objectStatus "@baseboard_fab2_lib.baseboard_fab2(sch_1):page213_i96:mp4" )
			)
			( pin "EU4D5.12"
				( objectStatus "@baseboard_fab2_lib.baseboard_fab2(sch_1):page213_i96:pinalrt_n" )
			)
			( pin "EU4D5.8"
				( objectStatus "@baseboard_fab2_lib.baseboard_fab2(sch_1):page213_i96:reset_n" )
			)
			( pin "EU4D5.7"
				( objectStatus "@baseboard_fab2_lib.baseboard_fab2(sch_1):page213_i96:scl" )
			)
			( pin "EU4D5.6"
				( objectStatus "@baseboard_fab2_lib.baseboard_fab2(sch_1):page213_i96:sda" )
			)
			( pin "EU4D5.41"
				( objectStatus "@baseboard_fab2_lib.baseboard_fab2(sch_1):page213_i96:thpad" )
			)
			( pin "EU4D5.17"
				( objectStatus "@baseboard_fab2_lib.baseboard_fab2(sch_1):page213_i96:valrt_n" )
			)
			( pin "EU4D5.15"
				( objectStatus "@baseboard_fab2_lib.baseboard_fab2(sch_1):page213_i96:vclk" )
			)
			( pin "EU4D5.40"
				( objectStatus "@baseboard_fab2_lib.baseboard_fab2(sch_1):page213_i96:vd12" )
			)
			( pin "EU4D5.39"
				( objectStatus "@baseboard_fab2_lib.baseboard_fab2(sch_1):page213_i96:vdd" )
			)
			( pin "EU4D5.16"
				( objectStatus "@baseboard_fab2_lib.baseboard_fab2(sch_1):page213_i96:vdio" )
			)
			( pin "EU4D5.37"
				( objectStatus "@baseboard_fab2_lib.baseboard_fab2(sch_1):page213_i96:vinsen" )
			)
			( pin "EU4D5.11"
				( objectStatus "@baseboard_fab2_lib.baseboard_fab2(sch_1):page213_i96:vrhot_n" )
			)
			( pin "EU4D5.36"
				( objectStatus "@baseboard_fab2_lib.baseboard_fab2(sch_1):page213_i96:xaddr1" )
			)
			( pin "EU4D5.33"
				( objectStatus "@baseboard_fab2_lib.baseboard_fab2(sch_1):page213_i96:xaddr2" )
			)
			( pin "C7A13.1"
				( objectStatus "@baseboard_fab2_lib.baseboard_fab2(sch_1):page236_i161:\1\" )
			)
			( pin "C7A13.2"
				( objectStatus "@baseboard_fab2_lib.baseboard_fab2(sch_1):page236_i161:\2\" )
			)
			( pin "C6R5.1"
				( objectStatus "@baseboard_fab2_lib.baseboard_fab2(sch_1):page214_i24:a" )
			)
			( pin "C6R5.2"
				( objectStatus "@baseboard_fab2_lib.baseboard_fab2(sch_1):page214_i24:b" )
			)
			( pin "C22W24.1"
				( objectStatus "@baseboard_fab2_lib.baseboard_fab2(sch_1):page236_i160:\1\" )
			)
			( pin "C22W24.2"
				( objectStatus "@baseboard_fab2_lib.baseboard_fab2(sch_1):page236_i160:\2\" )
			)
			( pin "C22W23.1"
				( objectStatus "@baseboard_fab2_lib.baseboard_fab2(sch_1):page236_i159:\1\" )
			)
			( pin "C22W23.2"
				( objectStatus "@baseboard_fab2_lib.baseboard_fab2(sch_1):page236_i159:\2\" )
			)
			( pin "C7R1.1"
				( objectStatus "@baseboard_fab2_lib.baseboard_fab2(sch_1):page214_i65:a" )
			)
			( pin "C7R1.2"
				( objectStatus "@baseboard_fab2_lib.baseboard_fab2(sch_1):page214_i65:b" )
			)
			( pin "L4C2.2"
				( objectStatus "@baseboard_fab2_lib.baseboard_fab2(sch_1):page205_i82:f" )
			)
			( pin "L4C2.1"
				( objectStatus "@baseboard_fab2_lib.baseboard_fab2(sch_1):page205_i82:s" )
			)
			( pin "R3U6.1"
				( objectStatus "@baseboard_fab2_lib.baseboard_fab2(sch_1):page216_i145:a" )
			)
			( pin "R3U6.2"
				( objectStatus "@baseboard_fab2_lib.baseboard_fab2(sch_1):page216_i145:b" )
			)
			( pin "C4E23.1"
				( objectStatus "@baseboard_fab2_lib.baseboard_fab2(sch_1):page214_i73:a" )
			)
			( pin "C4E23.2"
				( objectStatus "@baseboard_fab2_lib.baseboard_fab2(sch_1):page214_i73:b" )
			)
			( pin "C7A18.1"
				( objectStatus "@baseboard_fab2_lib.baseboard_fab2(sch_1):page219_i151:\1\" )
			)
			( pin "C7A18.2"
				( objectStatus "@baseboard_fab2_lib.baseboard_fab2(sch_1):page219_i151:\2\" )
			)
			( pin "C4E22.1"
				( objectStatus "@baseboard_fab2_lib.baseboard_fab2(sch_1):page214_i76:a" )
			)
			( pin "C4E22.2"
				( objectStatus "@baseboard_fab2_lib.baseboard_fab2(sch_1):page214_i76:b" )
			)
			( pin "C4E13.1"
				( objectStatus "@baseboard_fab2_lib.baseboard_fab2(sch_1):page214_i77:a" )
			)
			( pin "C4E13.2"
				( objectStatus "@baseboard_fab2_lib.baseboard_fab2(sch_1):page214_i77:b" )
			)
			( pin "C4E18.1"
				( objectStatus "@baseboard_fab2_lib.baseboard_fab2(sch_1):page214_i78:a" )
			)
			( pin "C4E18.2"
				( objectStatus "@baseboard_fab2_lib.baseboard_fab2(sch_1):page214_i78:b" )
			)
			( pin "C4E15.1"
				( objectStatus "@baseboard_fab2_lib.baseboard_fab2(sch_1):page214_i79:a" )
			)
			( pin "C4E15.2"
				( objectStatus "@baseboard_fab2_lib.baseboard_fab2(sch_1):page214_i79:b" )
			)
			( pin "C6R14.1"
				( objectStatus "@baseboard_fab2_lib.baseboard_fab2(sch_1):page214_i80:a" )
			)
			( pin "C6R14.2"
				( objectStatus "@baseboard_fab2_lib.baseboard_fab2(sch_1):page214_i80:b" )
			)
			( pin "C6R10.1"
				( objectStatus "@baseboard_fab2_lib.baseboard_fab2(sch_1):page214_i81:a" )
			)
			( pin "C6R10.2"
				( objectStatus "@baseboard_fab2_lib.baseboard_fab2(sch_1):page214_i81:b" )
			)
			( pin "C6R8.1"
				( objectStatus "@baseboard_fab2_lib.baseboard_fab2(sch_1):page214_i83:a" )
			)
			( pin "C6R8.2"
				( objectStatus "@baseboard_fab2_lib.baseboard_fab2(sch_1):page214_i83:b" )
			)
			( pin "C3D27.1"
				( objectStatus "@baseboard_fab2_lib.baseboard_fab2(sch_1):page214_i96:a" )
			)
			( pin "C3D27.2"
				( objectStatus "@baseboard_fab2_lib.baseboard_fab2(sch_1):page214_i96:b" )
			)
			( pin "R3D28.1"
				( objectStatus "@baseboard_fab2_lib.baseboard_fab2(sch_1):page214_i101:a" )
			)
			( pin "R3D28.2"
				( objectStatus "@baseboard_fab2_lib.baseboard_fab2(sch_1):page214_i101:b" )
			)
			( pin "R3E1.1"
				( objectStatus "@baseboard_fab2_lib.baseboard_fab2(sch_1):page214_i105:a" )
			)
			( pin "R3E1.2"
				( objectStatus "@baseboard_fab2_lib.baseboard_fab2(sch_1):page214_i105:b" )
			)
			( pin "C3E1.1"
				( objectStatus "@baseboard_fab2_lib.baseboard_fab2(sch_1):page214_i108:a" )
			)
			( pin "C3E1.2"
				( objectStatus "@baseboard_fab2_lib.baseboard_fab2(sch_1):page214_i108:b" )
			)
			( pin "R7R1.1"
				( objectStatus "@baseboard_fab2_lib.baseboard_fab2(sch_1):page214_i109:a" )
			)
			( pin "R7R1.2"
				( objectStatus "@baseboard_fab2_lib.baseboard_fab2(sch_1):page214_i109:b" )
			)
			( pin "EU4E2.33"
				( objectStatus "@baseboard_fab2_lib.baseboard_fab2(sch_1):page214_i126:boost" )
			)
			( pin "EU4E2.35"
				( objectStatus "@baseboard_fab2_lib.baseboard_fab2(sch_1):page214_i126:en" )
			)
			( pin "EU4E2.6"
				( objectStatus "@baseboard_fab2_lib.baseboard_fab2(sch_1):page214_i126:gl(0)" )
			)
			( pin "EU4E2.41"
				( objectStatus "@baseboard_fab2_lib.baseboard_fab2(sch_1):page214_i126:gl(1)" )
			)
			( pin "EU4E2.38"
				( objectStatus "@baseboard_fab2_lib.baseboard_fab2(sch_1):page214_i126:iout" )
			)
			( pin "EU4E2.2"
				( objectStatus "@baseboard_fab2_lib.baseboard_fab2(sch_1):page214_i126:lgnd" )
			)
			( pin "EU4E2.31"
				( objectStatus "@baseboard_fab2_lib.baseboard_fab2(sch_1):page214_i126:nc" )
			)
			( pin "EU4E2.37"
				( objectStatus "@baseboard_fab2_lib.baseboard_fab2(sch_1):page214_i126:ocset" )
			)
			( pin "EU4E2.5"
				( objectStatus "@baseboard_fab2_lib.baseboard_fab2(sch_1):page214_i126:pgnd(0)" )
			)
			( pin "EU4E2.7"
				( objectStatus "@baseboard_fab2_lib.baseboard_fab2(sch_1):page214_i126:pgnd(1)" )
			)
			( pin "EU4E2.40"
				( objectStatus "@baseboard_fab2_lib.baseboard_fab2(sch_1):page214_i126:pgnd(2)" )
			)
			( pin "EU4E2.32"
				( objectStatus "@baseboard_fab2_lib.baseboard_fab2(sch_1):page214_i126:phase" )
			)
			( pin "EU4E2.34"
				( objectStatus "@baseboard_fab2_lib.baseboard_fab2(sch_1):page214_i126:pwm" )
			)
			( pin "EU4E2.39"
				( objectStatus "@baseboard_fab2_lib.baseboard_fab2(sch_1):page214_i126:refin" )
			)
			( pin "EU4E2.10"
				( objectStatus "@baseboard_fab2_lib.baseboard_fab2(sch_1):page214_i126:sw" )
			)
			( pin "EU4E2.36"
				( objectStatus "@baseboard_fab2_lib.baseboard_fab2(sch_1):page214_i126:tout_flt" )
			)
			( pin "EU4E2.3"
				( objectStatus "@baseboard_fab2_lib.baseboard_fab2(sch_1):page214_i126:vcc" )
			)
			( pin "EU4E2.4"
				( objectStatus "@baseboard_fab2_lib.baseboard_fab2(sch_1):page214_i126:vdrv" )
			)
			( pin "EU4E2.25"
				( objectStatus "@baseboard_fab2_lib.baseboard_fab2(sch_1):page214_i126:vin(0)" )
			)
			( pin "EU4E2.30"
				( objectStatus "@baseboard_fab2_lib.baseboard_fab2(sch_1):page214_i126:vin(1)" )
			)
			( pin "EU4E2.1"
				( objectStatus "@baseboard_fab2_lib.baseboard_fab2(sch_1):page214_i126:vos" )
			)
			( pin "R4E21.1"
				( objectStatus "@baseboard_fab2_lib.baseboard_fab2(sch_1):page214_i127:a" )
			)
			( pin "R4E21.2"
				( objectStatus "@baseboard_fab2_lib.baseboard_fab2(sch_1):page214_i127:b" )
			)
			( pin "SH3D2.1"
				( objectStatus "@baseboard_fab2_lib.baseboard_fab2(sch_1):page214_i129:a" )
			)
			( pin "SH3D2.2"
				( objectStatus "@baseboard_fab2_lib.baseboard_fab2(sch_1):page214_i129:b" )
			)
			( pin "SH3D1.1"
				( objectStatus "@baseboard_fab2_lib.baseboard_fab2(sch_1):page214_i130:a" )
			)
			( pin "SH3D1.2"
				( objectStatus "@baseboard_fab2_lib.baseboard_fab2(sch_1):page214_i130:b" )
			)
			( pin "Q12W4.4"
				( objectStatus "@baseboard_fab2_lib.baseboard_fab2(sch_1):page197_i35:\drain#4\" )
			)
			( pin "Q12W4.6"
				( objectStatus "@baseboard_fab2_lib.baseboard_fab2(sch_1):page197_i35:\drain#6\" )
			)
			( pin "Q12W4.1"
				( objectStatus "@baseboard_fab2_lib.baseboard_fab2(sch_1):page197_i35:\gate#1\" )
			)
			( pin "Q12W4.3"
				( objectStatus "@baseboard_fab2_lib.baseboard_fab2(sch_1):page197_i35:\gate#3\" )
			)
			( pin "Q12W4.2"
				( objectStatus "@baseboard_fab2_lib.baseboard_fab2(sch_1):page197_i35:\source#2\" )
			)
			( pin "Q12W4.5"
				( objectStatus "@baseboard_fab2_lib.baseboard_fab2(sch_1):page197_i35:\source#5\" )
			)
			( pin "R9M4.1"
				( objectStatus "@baseboard_fab2_lib.baseboard_fab2(sch_1):page197_i29:a" )
			)
			( pin "R9M4.2"
				( objectStatus "@baseboard_fab2_lib.baseboard_fab2(sch_1):page197_i29:b" )
			)
			( pin "C8F19.1"
				( objectStatus "@baseboard_fab2_lib.baseboard_fab2(sch_1):page101_i146:a" )
			)
			( pin "C8F19.2"
				( objectStatus "@baseboard_fab2_lib.baseboard_fab2(sch_1):page101_i146:b" )
			)
			( pin "EU1B1.21"
				( objectStatus "@baseboard_fab2_lib.baseboard_fab2(sch_1):page226_i69:airef1" )
			)
			( pin "EU1B1.23"
				( objectStatus "@baseboard_fab2_lib.baseboard_fab2(sch_1):page226_i69:airef2" )
			)
			( pin "EU1B1.25"
				( objectStatus "@baseboard_fab2_lib.baseboard_fab2(sch_1):page226_i69:airef3" )
			)
			( pin "EU1B1.22"
				( objectStatus "@baseboard_fab2_lib.baseboard_fab2(sch_1):page226_i69:aisen1" )
			)
			( pin "EU1B1.24"
				( objectStatus "@baseboard_fab2_lib.baseboard_fab2(sch_1):page226_i69:aisen2" )
			)
			( pin "EU1B1.26"
				( objectStatus "@baseboard_fab2_lib.baseboard_fab2(sch_1):page226_i69:aisen3" )
			)
			( pin "EU1B1.5"
				( objectStatus "@baseboard_fab2_lib.baseboard_fab2(sch_1):page226_i69:apwm1" )
			)
			( pin "EU1B1.4"
				( objectStatus "@baseboard_fab2_lib.baseboard_fab2(sch_1):page226_i69:apwm2" )
			)
			( pin "EU1B1.3"
				( objectStatus "@baseboard_fab2_lib.baseboard_fab2(sch_1):page226_i69:apwm3" )
			)
			( pin "EU1B1.35"
				( objectStatus "@baseboard_fab2_lib.baseboard_fab2(sch_1):page226_i69:atsen" )
			)
			( pin "EU1B1.20"
				( objectStatus "@baseboard_fab2_lib.baseboard_fab2(sch_1):page226_i69:avref" )
			)
			( pin "EU1B1.10"
				( objectStatus "@baseboard_fab2_lib.baseboard_fab2(sch_1):page226_i69:avren" )
			)
			( pin "EU1B1.9"
				( objectStatus "@baseboard_fab2_lib.baseboard_fab2(sch_1):page226_i69:avrrdy" )
			)
			( pin "EU1B1.19"
				( objectStatus "@baseboard_fab2_lib.baseboard_fab2(sch_1):page226_i69:avsen" )
			)
			( pin "EU1B1.31"
				( objectStatus "@baseboard_fab2_lib.baseboard_fab2(sch_1):page226_i69:biref1" )
			)
			( pin "EU1B1.32"
				( objectStatus "@baseboard_fab2_lib.baseboard_fab2(sch_1):page226_i69:bisen1" )
			)
			( pin "EU1B1.1"
				( objectStatus "@baseboard_fab2_lib.baseboard_fab2(sch_1):page226_i69:bpwm1" )
			)
			( pin "EU1B1.34"
				( objectStatus "@baseboard_fab2_lib.baseboard_fab2(sch_1):page226_i69:btsen" )
			)
			( pin "EU1B1.30"
				( objectStatus "@baseboard_fab2_lib.baseboard_fab2(sch_1):page226_i69:bvref" )
			)
			( pin "EU1B1.29"
				( objectStatus "@baseboard_fab2_lib.baseboard_fab2(sch_1):page226_i69:bvsen" )
			)
			( pin "EU1B1.2"
				( objectStatus "@baseboard_fab2_lib.baseboard_fab2(sch_1):page226_i69:dnc(0)" )
			)
			( pin "EU1B1.28"
				( objectStatus "@baseboard_fab2_lib.baseboard_fab2(sch_1):page226_i69:dnc(1)" )
			)
			( pin "EU1B1.27"
				( objectStatus "@baseboard_fab2_lib.baseboard_fab2(sch_1):page226_i69:gnd" )
			)
			( pin "EU1B1.38"
				( objectStatus "@baseboard_fab2_lib.baseboard_fab2(sch_1):page226_i69:iinsen" )
			)
			( pin "EU1B1.13"
				( objectStatus "@baseboard_fab2_lib.baseboard_fab2(sch_1):page226_i69:mp0" )
			)
			( pin "EU1B1.14"
				( objectStatus "@baseboard_fab2_lib.baseboard_fab2(sch_1):page226_i69:mp1" )
			)
			( pin "EU1B1.18"
				( objectStatus "@baseboard_fab2_lib.baseboard_fab2(sch_1):page226_i69:mp2" )
			)
			( pin "EU1B1.12"
				( objectStatus "@baseboard_fab2_lib.baseboard_fab2(sch_1):page226_i69:pinalrt_n" )
			)
			( pin "EU1B1.8"
				( objectStatus "@baseboard_fab2_lib.baseboard_fab2(sch_1):page226_i69:reset_n" )
			)
			( pin "EU1B1.7"
				( objectStatus "@baseboard_fab2_lib.baseboard_fab2(sch_1):page226_i69:scl" )
			)
			( pin "EU1B1.6"
				( objectStatus "@baseboard_fab2_lib.baseboard_fab2(sch_1):page226_i69:sda" )
			)
			( pin "EU1B1.41"
				( objectStatus "@baseboard_fab2_lib.baseboard_fab2(sch_1):page226_i69:thpad" )
			)
			( pin "EU1B1.17"
				( objectStatus "@baseboard_fab2_lib.baseboard_fab2(sch_1):page226_i69:valrt_n" )
			)
			( pin "EU1B1.15"
				( objectStatus "@baseboard_fab2_lib.baseboard_fab2(sch_1):page226_i69:vclk" )
			)
			( pin "EU1B1.40"
				( objectStatus "@baseboard_fab2_lib.baseboard_fab2(sch_1):page226_i69:vd12" )
			)
			( pin "EU1B1.39"
				( objectStatus "@baseboard_fab2_lib.baseboard_fab2(sch_1):page226_i69:vdd" )
			)
			( pin "EU1B1.16"
				( objectStatus "@baseboard_fab2_lib.baseboard_fab2(sch_1):page226_i69:vdio" )
			)
			( pin "EU1B1.37"
				( objectStatus "@baseboard_fab2_lib.baseboard_fab2(sch_1):page226_i69:vinsen" )
			)
			( pin "EU1B1.11"
				( objectStatus "@baseboard_fab2_lib.baseboard_fab2(sch_1):page226_i69:vrhot_n" )
			)
			( pin "EU1B1.36"
				( objectStatus "@baseboard_fab2_lib.baseboard_fab2(sch_1):page226_i69:xaddr1" )
			)
			( pin "EU1B1.33"
				( objectStatus "@baseboard_fab2_lib.baseboard_fab2(sch_1):page226_i69:xaddr2" )
			)
			( pin "R9M7.1"
				( objectStatus "@baseboard_fab2_lib.baseboard_fab2(sch_1):page226_i57:a" )
			)
			( pin "R9M7.2"
				( objectStatus "@baseboard_fab2_lib.baseboard_fab2(sch_1):page226_i57:b" )
			)
			( pin "EU1G2.21"
				( objectStatus "@baseboard_fab2_lib.baseboard_fab2(sch_1):page223_i69:airef1" )
			)
			( pin "EU1G2.23"
				( objectStatus "@baseboard_fab2_lib.baseboard_fab2(sch_1):page223_i69:airef2" )
			)
			( pin "EU1G2.25"
				( objectStatus "@baseboard_fab2_lib.baseboard_fab2(sch_1):page223_i69:airef3" )
			)
			( pin "EU1G2.22"
				( objectStatus "@baseboard_fab2_lib.baseboard_fab2(sch_1):page223_i69:aisen1" )
			)
			( pin "EU1G2.24"
				( objectStatus "@baseboard_fab2_lib.baseboard_fab2(sch_1):page223_i69:aisen2" )
			)
			( pin "EU1G2.26"
				( objectStatus "@baseboard_fab2_lib.baseboard_fab2(sch_1):page223_i69:aisen3" )
			)
			( pin "EU1G2.5"
				( objectStatus "@baseboard_fab2_lib.baseboard_fab2(sch_1):page223_i69:apwm1" )
			)
			( pin "EU1G2.4"
				( objectStatus "@baseboard_fab2_lib.baseboard_fab2(sch_1):page223_i69:apwm2" )
			)
			( pin "EU1G2.3"
				( objectStatus "@baseboard_fab2_lib.baseboard_fab2(sch_1):page223_i69:apwm3" )
			)
			( pin "EU1G2.35"
				( objectStatus "@baseboard_fab2_lib.baseboard_fab2(sch_1):page223_i69:atsen" )
			)
			( pin "EU1G2.20"
				( objectStatus "@baseboard_fab2_lib.baseboard_fab2(sch_1):page223_i69:avref" )
			)
			( pin "EU1G2.10"
				( objectStatus "@baseboard_fab2_lib.baseboard_fab2(sch_1):page223_i69:avren" )
			)
			( pin "EU1G2.9"
				( objectStatus "@baseboard_fab2_lib.baseboard_fab2(sch_1):page223_i69:avrrdy" )
			)
			( pin "EU1G2.19"
				( objectStatus "@baseboard_fab2_lib.baseboard_fab2(sch_1):page223_i69:avsen" )
			)
			( pin "EU1G2.31"
				( objectStatus "@baseboard_fab2_lib.baseboard_fab2(sch_1):page223_i69:biref1" )
			)
			( pin "EU1G2.32"
				( objectStatus "@baseboard_fab2_lib.baseboard_fab2(sch_1):page223_i69:bisen1" )
			)
			( pin "EU1G2.1"
				( objectStatus "@baseboard_fab2_lib.baseboard_fab2(sch_1):page223_i69:bpwm1" )
			)
			( pin "EU1G2.34"
				( objectStatus "@baseboard_fab2_lib.baseboard_fab2(sch_1):page223_i69:btsen" )
			)
			( pin "EU1G2.30"
				( objectStatus "@baseboard_fab2_lib.baseboard_fab2(sch_1):page223_i69:bvref" )
			)
			( pin "EU1G2.29"
				( objectStatus "@baseboard_fab2_lib.baseboard_fab2(sch_1):page223_i69:bvsen" )
			)
			( pin "EU1G2.2"
				( objectStatus "@baseboard_fab2_lib.baseboard_fab2(sch_1):page223_i69:dnc(0)" )
			)
			( pin "EU1G2.28"
				( objectStatus "@baseboard_fab2_lib.baseboard_fab2(sch_1):page223_i69:dnc(1)" )
			)
			( pin "EU1G2.27"
				( objectStatus "@baseboard_fab2_lib.baseboard_fab2(sch_1):page223_i69:gnd" )
			)
			( pin "EU1G2.38"
				( objectStatus "@baseboard_fab2_lib.baseboard_fab2(sch_1):page223_i69:iinsen" )
			)
			( pin "EU1G2.13"
				( objectStatus "@baseboard_fab2_lib.baseboard_fab2(sch_1):page223_i69:mp0" )
			)
			( pin "EU1G2.14"
				( objectStatus "@baseboard_fab2_lib.baseboard_fab2(sch_1):page223_i69:mp1" )
			)
			( pin "EU1G2.18"
				( objectStatus "@baseboard_fab2_lib.baseboard_fab2(sch_1):page223_i69:mp2" )
			)
			( pin "EU1G2.12"
				( objectStatus "@baseboard_fab2_lib.baseboard_fab2(sch_1):page223_i69:pinalrt_n" )
			)
			( pin "EU1G2.8"
				( objectStatus "@baseboard_fab2_lib.baseboard_fab2(sch_1):page223_i69:reset_n" )
			)
			( pin "EU1G2.7"
				( objectStatus "@baseboard_fab2_lib.baseboard_fab2(sch_1):page223_i69:scl" )
			)
			( pin "EU1G2.6"
				( objectStatus "@baseboard_fab2_lib.baseboard_fab2(sch_1):page223_i69:sda" )
			)
			( pin "EU1G2.41"
				( objectStatus "@baseboard_fab2_lib.baseboard_fab2(sch_1):page223_i69:thpad" )
			)
			( pin "EU1G2.17"
				( objectStatus "@baseboard_fab2_lib.baseboard_fab2(sch_1):page223_i69:valrt_n" )
			)
			( pin "EU1G2.15"
				( objectStatus "@baseboard_fab2_lib.baseboard_fab2(sch_1):page223_i69:vclk" )
			)
			( pin "EU1G2.40"
				( objectStatus "@baseboard_fab2_lib.baseboard_fab2(sch_1):page223_i69:vd12" )
			)
			( pin "EU1G2.39"
				( objectStatus "@baseboard_fab2_lib.baseboard_fab2(sch_1):page223_i69:vdd" )
			)
			( pin "EU1G2.16"
				( objectStatus "@baseboard_fab2_lib.baseboard_fab2(sch_1):page223_i69:vdio" )
			)
			( pin "EU1G2.37"
				( objectStatus "@baseboard_fab2_lib.baseboard_fab2(sch_1):page223_i69:vinsen" )
			)
			( pin "EU1G2.11"
				( objectStatus "@baseboard_fab2_lib.baseboard_fab2(sch_1):page223_i69:vrhot_n" )
			)
			( pin "EU1G2.36"
				( objectStatus "@baseboard_fab2_lib.baseboard_fab2(sch_1):page223_i69:xaddr1" )
			)
			( pin "EU1G2.33"
				( objectStatus "@baseboard_fab2_lib.baseboard_fab2(sch_1):page223_i69:xaddr2" )
			)
			( pin "R9U3.1"
				( objectStatus "@baseboard_fab2_lib.baseboard_fab2(sch_1):page223_i57:a" )
			)
			( pin "R9U3.2"
				( objectStatus "@baseboard_fab2_lib.baseboard_fab2(sch_1):page223_i57:b" )
			)
			( pin "R1B13.1"
				( objectStatus "@baseboard_fab2_lib.baseboard_fab2(sch_1):page226_i75:a" )
			)
			( pin "R1B13.2"
				( objectStatus "@baseboard_fab2_lib.baseboard_fab2(sch_1):page226_i75:b" )
			)
			( pin "R1G8.1"
				( objectStatus "@baseboard_fab2_lib.baseboard_fab2(sch_1):page223_i55:a" )
			)
			( pin "R1G8.2"
				( objectStatus "@baseboard_fab2_lib.baseboard_fab2(sch_1):page223_i55:b" )
			)
			( pin "EU7A5.21"
				( objectStatus "@baseboard_fab2_lib.baseboard_fab2(sch_1):page218_i69:airef1" )
			)
			( pin "EU7A5.23"
				( objectStatus "@baseboard_fab2_lib.baseboard_fab2(sch_1):page218_i69:airef2" )
			)
			( pin "EU7A5.25"
				( objectStatus "@baseboard_fab2_lib.baseboard_fab2(sch_1):page218_i69:airef3" )
			)
			( pin "EU7A5.22"
				( objectStatus "@baseboard_fab2_lib.baseboard_fab2(sch_1):page218_i69:aisen1" )
			)
			( pin "EU7A5.24"
				( objectStatus "@baseboard_fab2_lib.baseboard_fab2(sch_1):page218_i69:aisen2" )
			)
			( pin "EU7A5.26"
				( objectStatus "@baseboard_fab2_lib.baseboard_fab2(sch_1):page218_i69:aisen3" )
			)
			( pin "EU7A5.5"
				( objectStatus "@baseboard_fab2_lib.baseboard_fab2(sch_1):page218_i69:apwm1" )
			)
			( pin "EU7A5.4"
				( objectStatus "@baseboard_fab2_lib.baseboard_fab2(sch_1):page218_i69:apwm2" )
			)
			( pin "EU7A5.3"
				( objectStatus "@baseboard_fab2_lib.baseboard_fab2(sch_1):page218_i69:apwm3" )
			)
			( pin "EU7A5.35"
				( objectStatus "@baseboard_fab2_lib.baseboard_fab2(sch_1):page218_i69:atsen" )
			)
			( pin "EU7A5.20"
				( objectStatus "@baseboard_fab2_lib.baseboard_fab2(sch_1):page218_i69:avref" )
			)
			( pin "EU7A5.10"
				( objectStatus "@baseboard_fab2_lib.baseboard_fab2(sch_1):page218_i69:avren" )
			)
			( pin "EU7A5.9"
				( objectStatus "@baseboard_fab2_lib.baseboard_fab2(sch_1):page218_i69:avrrdy" )
			)
			( pin "EU7A5.19"
				( objectStatus "@baseboard_fab2_lib.baseboard_fab2(sch_1):page218_i69:avsen" )
			)
			( pin "EU7A5.31"
				( objectStatus "@baseboard_fab2_lib.baseboard_fab2(sch_1):page218_i69:biref1" )
			)
			( pin "EU7A5.32"
				( objectStatus "@baseboard_fab2_lib.baseboard_fab2(sch_1):page218_i69:bisen1" )
			)
			( pin "EU7A5.1"
				( objectStatus "@baseboard_fab2_lib.baseboard_fab2(sch_1):page218_i69:bpwm1" )
			)
			( pin "EU7A5.34"
				( objectStatus "@baseboard_fab2_lib.baseboard_fab2(sch_1):page218_i69:btsen" )
			)
			( pin "EU7A5.30"
				( objectStatus "@baseboard_fab2_lib.baseboard_fab2(sch_1):page218_i69:bvref" )
			)
			( pin "EU7A5.29"
				( objectStatus "@baseboard_fab2_lib.baseboard_fab2(sch_1):page218_i69:bvsen" )
			)
			( pin "EU7A5.2"
				( objectStatus "@baseboard_fab2_lib.baseboard_fab2(sch_1):page218_i69:dnc(0)" )
			)
			( pin "EU7A5.28"
				( objectStatus "@baseboard_fab2_lib.baseboard_fab2(sch_1):page218_i69:dnc(1)" )
			)
			( pin "EU7A5.27"
				( objectStatus "@baseboard_fab2_lib.baseboard_fab2(sch_1):page218_i69:gnd" )
			)
			( pin "EU7A5.38"
				( objectStatus "@baseboard_fab2_lib.baseboard_fab2(sch_1):page218_i69:iinsen" )
			)
			( pin "EU7A5.13"
				( objectStatus "@baseboard_fab2_lib.baseboard_fab2(sch_1):page218_i69:mp0" )
			)
			( pin "EU7A5.14"
				( objectStatus "@baseboard_fab2_lib.baseboard_fab2(sch_1):page218_i69:mp1" )
			)
			( pin "EU7A5.18"
				( objectStatus "@baseboard_fab2_lib.baseboard_fab2(sch_1):page218_i69:mp2" )
			)
			( pin "EU7A5.12"
				( objectStatus "@baseboard_fab2_lib.baseboard_fab2(sch_1):page218_i69:pinalrt_n" )
			)
			( pin "EU7A5.8"
				( objectStatus "@baseboard_fab2_lib.baseboard_fab2(sch_1):page218_i69:reset_n" )
			)
			( pin "EU7A5.7"
				( objectStatus "@baseboard_fab2_lib.baseboard_fab2(sch_1):page218_i69:scl" )
			)
			( pin "EU7A5.6"
				( objectStatus "@baseboard_fab2_lib.baseboard_fab2(sch_1):page218_i69:sda" )
			)
			( pin "EU7A5.41"
				( objectStatus "@baseboard_fab2_lib.baseboard_fab2(sch_1):page218_i69:thpad" )
			)
			( pin "EU7A5.17"
				( objectStatus "@baseboard_fab2_lib.baseboard_fab2(sch_1):page218_i69:valrt_n" )
			)
			( pin "EU7A5.15"
				( objectStatus "@baseboard_fab2_lib.baseboard_fab2(sch_1):page218_i69:vclk" )
			)
			( pin "EU7A5.40"
				( objectStatus "@baseboard_fab2_lib.baseboard_fab2(sch_1):page218_i69:vd12" )
			)
			( pin "EU7A5.39"
				( objectStatus "@baseboard_fab2_lib.baseboard_fab2(sch_1):page218_i69:vdd" )
			)
			( pin "EU7A5.16"
				( objectStatus "@baseboard_fab2_lib.baseboard_fab2(sch_1):page218_i69:vdio" )
			)
			( pin "EU7A5.37"
				( objectStatus "@baseboard_fab2_lib.baseboard_fab2(sch_1):page218_i69:vinsen" )
			)
			( pin "EU7A5.11"
				( objectStatus "@baseboard_fab2_lib.baseboard_fab2(sch_1):page218_i69:vrhot_n" )
			)
			( pin "EU7A5.36"
				( objectStatus "@baseboard_fab2_lib.baseboard_fab2(sch_1):page218_i69:xaddr1" )
			)
			( pin "EU7A5.33"
				( objectStatus "@baseboard_fab2_lib.baseboard_fab2(sch_1):page218_i69:xaddr2" )
			)
			( pin "R3L11.1"
				( objectStatus "@baseboard_fab2_lib.baseboard_fab2(sch_1):page218_i67:a" )
			)
			( pin "R3L11.2"
				( objectStatus "@baseboard_fab2_lib.baseboard_fab2(sch_1):page218_i67:b" )
			)
			( pin "R1G6.1"
				( objectStatus "@baseboard_fab2_lib.baseboard_fab2(sch_1):page223_i76:a" )
			)
			( pin "R1G6.2"
				( objectStatus "@baseboard_fab2_lib.baseboard_fab2(sch_1):page223_i76:b" )
			)
			( pin "R7B5.1"
				( objectStatus "@baseboard_fab2_lib.baseboard_fab2(sch_1):page218_i58:a" )
			)
			( pin "R7B5.2"
				( objectStatus "@baseboard_fab2_lib.baseboard_fab2(sch_1):page218_i58:b" )
			)
			( pin "R4G19.1"
				( objectStatus "@baseboard_fab2_lib.baseboard_fab2(sch_1):page221_i33:a" )
			)
			( pin "R4G19.2"
				( objectStatus "@baseboard_fab2_lib.baseboard_fab2(sch_1):page221_i33:b" )
			)
			( pin "C4G14.1"
				( objectStatus "@baseboard_fab2_lib.baseboard_fab2(sch_1):page221_i30:a" )
			)
			( pin "C4G14.2"
				( objectStatus "@baseboard_fab2_lib.baseboard_fab2(sch_1):page221_i30:b" )
			)
			( pin "C4W5.1"
				( objectStatus "@baseboard_fab2_lib.baseboard_fab2(sch_1):page222_i46:a" )
			)
			( pin "C4W5.2"
				( objectStatus "@baseboard_fab2_lib.baseboard_fab2(sch_1):page222_i46:b" )
			)
			( pin "R4G18.1"
				( objectStatus "@baseboard_fab2_lib.baseboard_fab2(sch_1):page221_i25:a" )
			)
			( pin "R4G18.2"
				( objectStatus "@baseboard_fab2_lib.baseboard_fab2(sch_1):page221_i25:b" )
			)
			( pin "C6U16.1"
				( objectStatus "@baseboard_fab2_lib.baseboard_fab2(sch_1):page221_i19:a" )
			)
			( pin "C6U16.2"
				( objectStatus "@baseboard_fab2_lib.baseboard_fab2(sch_1):page221_i19:b" )
			)
			( pin "C6U15.1"
				( objectStatus "@baseboard_fab2_lib.baseboard_fab2(sch_1):page221_i18:a" )
			)
			( pin "C6U15.2"
				( objectStatus "@baseboard_fab2_lib.baseboard_fab2(sch_1):page221_i18:b" )
			)
			( pin "R6U4.1"
				( objectStatus "@baseboard_fab2_lib.baseboard_fab2(sch_1):page221_i14:a" )
			)
			( pin "R6U4.2"
				( objectStatus "@baseboard_fab2_lib.baseboard_fab2(sch_1):page221_i14:b" )
			)
			( pin "C4G15.1"
				( objectStatus "@baseboard_fab2_lib.baseboard_fab2(sch_1):page221_i13:a" )
			)
			( pin "C4G15.2"
				( objectStatus "@baseboard_fab2_lib.baseboard_fab2(sch_1):page221_i13:b" )
			)
			( pin "C6U12.1"
				( objectStatus "@baseboard_fab2_lib.baseboard_fab2(sch_1):page221_i11:a" )
			)
			( pin "C6U12.2"
				( objectStatus "@baseboard_fab2_lib.baseboard_fab2(sch_1):page221_i11:b" )
			)
			( pin "SH5U1.1"
				( objectStatus "@baseboard_fab2_lib.baseboard_fab2(sch_1):page221_i9:a" )
			)
			( pin "SH5U1.2"
				( objectStatus "@baseboard_fab2_lib.baseboard_fab2(sch_1):page221_i9:b" )
			)
			( pin "C4W3.1"
				( objectStatus "@baseboard_fab2_lib.baseboard_fab2(sch_1):page235_i244:a" )
			)
			( pin "C4W3.2"
				( objectStatus "@baseboard_fab2_lib.baseboard_fab2(sch_1):page235_i244:b" )
			)
			( pin "C6G3.1"
				( objectStatus "@baseboard_fab2_lib.baseboard_fab2(sch_1):page216_i6:a" )
			)
			( pin "C6G3.2"
				( objectStatus "@baseboard_fab2_lib.baseboard_fab2(sch_1):page216_i6:b" )
			)
			( pin "C7G31.1"
				( objectStatus "@baseboard_fab2_lib.baseboard_fab2(sch_1):page216_i44:a" )
			)
			( pin "C7G31.2"
				( objectStatus "@baseboard_fab2_lib.baseboard_fab2(sch_1):page216_i44:b" )
			)
			( pin "C3U2.1"
				( objectStatus "@baseboard_fab2_lib.baseboard_fab2(sch_1):page216_i45:a" )
			)
			( pin "C3U2.2"
				( objectStatus "@baseboard_fab2_lib.baseboard_fab2(sch_1):page216_i45:b" )
			)
			( pin "C3U3.1"
				( objectStatus "@baseboard_fab2_lib.baseboard_fab2(sch_1):page216_i46:a" )
			)
			( pin "C3U3.2"
				( objectStatus "@baseboard_fab2_lib.baseboard_fab2(sch_1):page216_i46:b" )
			)
			( pin "C3U4.1"
				( objectStatus "@baseboard_fab2_lib.baseboard_fab2(sch_1):page216_i47:a" )
			)
			( pin "C3U4.2"
				( objectStatus "@baseboard_fab2_lib.baseboard_fab2(sch_1):page216_i47:b" )
			)
			( pin "C7G37.1"
				( objectStatus "@baseboard_fab2_lib.baseboard_fab2(sch_1):page216_i48:a" )
			)
			( pin "C7G37.2"
				( objectStatus "@baseboard_fab2_lib.baseboard_fab2(sch_1):page216_i48:b" )
			)
			( pin "C7G33.1"
				( objectStatus "@baseboard_fab2_lib.baseboard_fab2(sch_1):page216_i50:a" )
			)
			( pin "C7G33.2"
				( objectStatus "@baseboard_fab2_lib.baseboard_fab2(sch_1):page216_i50:b" )
			)
			( pin "C7G29.1"
				( objectStatus "@baseboard_fab2_lib.baseboard_fab2(sch_1):page216_i51:a" )
			)
			( pin "C7G29.2"
				( objectStatus "@baseboard_fab2_lib.baseboard_fab2(sch_1):page216_i51:b" )
			)
			( pin "R3L8.1"
				( objectStatus "@baseboard_fab2_lib.baseboard_fab2(sch_1):page219_i148:a" )
			)
			( pin "R3L8.2"
				( objectStatus "@baseboard_fab2_lib.baseboard_fab2(sch_1):page219_i148:b" )
			)
			( pin "C7G34.1"
				( objectStatus "@baseboard_fab2_lib.baseboard_fab2(sch_1):page216_i54:a" )
			)
			( pin "C7G34.2"
				( objectStatus "@baseboard_fab2_lib.baseboard_fab2(sch_1):page216_i54:b" )
			)
			( pin "CT57.1"
				( objectStatus "@baseboard_fab2_lib.baseboard_fab2(sch_1):page210_i55:a" )
			)
			( pin "CT57.2"
				( objectStatus "@baseboard_fab2_lib.baseboard_fab2(sch_1):page210_i55:b" )
			)
			( pin "L1F2.2"
				( objectStatus "@baseboard_fab2_lib.baseboard_fab2(sch_1):page224_i161:f" )
			)
			( pin "L1F2.1"
				( objectStatus "@baseboard_fab2_lib.baseboard_fab2(sch_1):page224_i161:s" )
			)
			( pin "C7G27.1"
				( objectStatus "@baseboard_fab2_lib.baseboard_fab2(sch_1):page216_i68:a" )
			)
			( pin "C7G27.2"
				( objectStatus "@baseboard_fab2_lib.baseboard_fab2(sch_1):page216_i68:b" )
			)
			( pin "C7G41.1"
				( objectStatus "@baseboard_fab2_lib.baseboard_fab2(sch_1):page216_i72:a" )
			)
			( pin "C7G41.2"
				( objectStatus "@baseboard_fab2_lib.baseboard_fab2(sch_1):page216_i72:b" )
			)
			( pin "CT14.1"
				( objectStatus "@baseboard_fab2_lib.baseboard_fab2(sch_1):page209_i73:a" )
			)
			( pin "CT14.2"
				( objectStatus "@baseboard_fab2_lib.baseboard_fab2(sch_1):page209_i73:b" )
			)
			( pin "R3L6.1"
				( objectStatus "@baseboard_fab2_lib.baseboard_fab2(sch_1):page219_i147:a" )
			)
			( pin "R3L6.2"
				( objectStatus "@baseboard_fab2_lib.baseboard_fab2(sch_1):page219_i147:b" )
			)
			( pin "C7G40.1"
				( objectStatus "@baseboard_fab2_lib.baseboard_fab2(sch_1):page216_i77:a" )
			)
			( pin "C7G40.2"
				( objectStatus "@baseboard_fab2_lib.baseboard_fab2(sch_1):page216_i77:b" )
			)
			( pin "C7G36.1"
				( objectStatus "@baseboard_fab2_lib.baseboard_fab2(sch_1):page216_i78:a" )
			)
			( pin "C7G36.2"
				( objectStatus "@baseboard_fab2_lib.baseboard_fab2(sch_1):page216_i78:b" )
			)
			( pin "C7G30.1"
				( objectStatus "@baseboard_fab2_lib.baseboard_fab2(sch_1):page216_i79:a" )
			)
			( pin "C7G30.2"
				( objectStatus "@baseboard_fab2_lib.baseboard_fab2(sch_1):page216_i79:b" )
			)
			( pin "C3U9.1"
				( objectStatus "@baseboard_fab2_lib.baseboard_fab2(sch_1):page216_i80:a" )
			)
			( pin "C3U9.2"
				( objectStatus "@baseboard_fab2_lib.baseboard_fab2(sch_1):page216_i80:b" )
			)
			( pin "C3U7.1"
				( objectStatus "@baseboard_fab2_lib.baseboard_fab2(sch_1):page216_i81:a" )
			)
			( pin "C3U7.2"
				( objectStatus "@baseboard_fab2_lib.baseboard_fab2(sch_1):page216_i81:b" )
			)
			( pin "C3U6.1"
				( objectStatus "@baseboard_fab2_lib.baseboard_fab2(sch_1):page216_i84:a" )
			)
			( pin "C3U6.2"
				( objectStatus "@baseboard_fab2_lib.baseboard_fab2(sch_1):page216_i84:b" )
			)
			( pin "EU7G2.33"
				( objectStatus "@baseboard_fab2_lib.baseboard_fab2(sch_1):page216_i102:boost" )
			)
			( pin "EU7G2.35"
				( objectStatus "@baseboard_fab2_lib.baseboard_fab2(sch_1):page216_i102:en" )
			)
			( pin "EU7G2.6"
				( objectStatus "@baseboard_fab2_lib.baseboard_fab2(sch_1):page216_i102:gl(0)" )
			)
			( pin "EU7G2.41"
				( objectStatus "@baseboard_fab2_lib.baseboard_fab2(sch_1):page216_i102:gl(1)" )
			)
			( pin "EU7G2.38"
				( objectStatus "@baseboard_fab2_lib.baseboard_fab2(sch_1):page216_i102:iout" )
			)
			( pin "EU7G2.2"
				( objectStatus "@baseboard_fab2_lib.baseboard_fab2(sch_1):page216_i102:lgnd" )
			)
			( pin "EU7G2.31"
				( objectStatus "@baseboard_fab2_lib.baseboard_fab2(sch_1):page216_i102:nc" )
			)
			( pin "EU7G2.37"
				( objectStatus "@baseboard_fab2_lib.baseboard_fab2(sch_1):page216_i102:ocset" )
			)
			( pin "EU7G2.5"
				( objectStatus "@baseboard_fab2_lib.baseboard_fab2(sch_1):page216_i102:pgnd(0)" )
			)
			( pin "EU7G2.7"
				( objectStatus "@baseboard_fab2_lib.baseboard_fab2(sch_1):page216_i102:pgnd(1)" )
			)
			( pin "EU7G2.40"
				( objectStatus "@baseboard_fab2_lib.baseboard_fab2(sch_1):page216_i102:pgnd(2)" )
			)
			( pin "EU7G2.32"
				( objectStatus "@baseboard_fab2_lib.baseboard_fab2(sch_1):page216_i102:phase" )
			)
			( pin "EU7G2.34"
				( objectStatus "@baseboard_fab2_lib.baseboard_fab2(sch_1):page216_i102:pwm" )
			)
			( pin "EU7G2.39"
				( objectStatus "@baseboard_fab2_lib.baseboard_fab2(sch_1):page216_i102:refin" )
			)
			( pin "EU7G2.10"
				( objectStatus "@baseboard_fab2_lib.baseboard_fab2(sch_1):page216_i102:sw" )
			)
			( pin "EU7G2.36"
				( objectStatus "@baseboard_fab2_lib.baseboard_fab2(sch_1):page216_i102:tout_flt" )
			)
			( pin "EU7G2.3"
				( objectStatus "@baseboard_fab2_lib.baseboard_fab2(sch_1):page216_i102:vcc" )
			)
			( pin "EU7G2.4"
				( objectStatus "@baseboard_fab2_lib.baseboard_fab2(sch_1):page216_i102:vdrv" )
			)
			( pin "EU7G2.25"
				( objectStatus "@baseboard_fab2_lib.baseboard_fab2(sch_1):page216_i102:vin(0)" )
			)
			( pin "EU7G2.30"
				( objectStatus "@baseboard_fab2_lib.baseboard_fab2(sch_1):page216_i102:vin(1)" )
			)
			( pin "EU7G2.1"
				( objectStatus "@baseboard_fab2_lib.baseboard_fab2(sch_1):page216_i102:vos" )
			)
			( pin "EU7G3.33"
				( objectStatus "@baseboard_fab2_lib.baseboard_fab2(sch_1):page216_i103:boost" )
			)
			( pin "EU7G3.35"
				( objectStatus "@baseboard_fab2_lib.baseboard_fab2(sch_1):page216_i103:en" )
			)
			( pin "EU7G3.6"
				( objectStatus "@baseboard_fab2_lib.baseboard_fab2(sch_1):page216_i103:gl(0)" )
			)
			( pin "EU7G3.41"
				( objectStatus "@baseboard_fab2_lib.baseboard_fab2(sch_1):page216_i103:gl(1)" )
			)
			( pin "EU7G3.38"
				( objectStatus "@baseboard_fab2_lib.baseboard_fab2(sch_1):page216_i103:iout" )
			)
			( pin "EU7G3.2"
				( objectStatus "@baseboard_fab2_lib.baseboard_fab2(sch_1):page216_i103:lgnd" )
			)
			( pin "EU7G3.31"
				( objectStatus "@baseboard_fab2_lib.baseboard_fab2(sch_1):page216_i103:nc" )
			)
			( pin "EU7G3.37"
				( objectStatus "@baseboard_fab2_lib.baseboard_fab2(sch_1):page216_i103:ocset" )
			)
			( pin "EU7G3.5"
				( objectStatus "@baseboard_fab2_lib.baseboard_fab2(sch_1):page216_i103:pgnd(0)" )
			)
			( pin "EU7G3.7"
				( objectStatus "@baseboard_fab2_lib.baseboard_fab2(sch_1):page216_i103:pgnd(1)" )
			)
			( pin "EU7G3.40"
				( objectStatus "@baseboard_fab2_lib.baseboard_fab2(sch_1):page216_i103:pgnd(2)" )
			)
			( pin "EU7G3.32"
				( objectStatus "@baseboard_fab2_lib.baseboard_fab2(sch_1):page216_i103:phase" )
			)
			( pin "EU7G3.34"
				( objectStatus "@baseboard_fab2_lib.baseboard_fab2(sch_1):page216_i103:pwm" )
			)
			( pin "EU7G3.39"
				( objectStatus "@baseboard_fab2_lib.baseboard_fab2(sch_1):page216_i103:refin" )
			)
			( pin "EU7G3.10"
				( objectStatus "@baseboard_fab2_lib.baseboard_fab2(sch_1):page216_i103:sw" )
			)
			( pin "EU7G3.36"
				( objectStatus "@baseboard_fab2_lib.baseboard_fab2(sch_1):page216_i103:tout_flt" )
			)
			( pin "EU7G3.3"
				( objectStatus "@baseboard_fab2_lib.baseboard_fab2(sch_1):page216_i103:vcc" )
			)
			( pin "EU7G3.4"
				( objectStatus "@baseboard_fab2_lib.baseboard_fab2(sch_1):page216_i103:vdrv" )
			)
			( pin "EU7G3.25"
				( objectStatus "@baseboard_fab2_lib.baseboard_fab2(sch_1):page216_i103:vin(0)" )
			)
			( pin "EU7G3.30"
				( objectStatus "@baseboard_fab2_lib.baseboard_fab2(sch_1):page216_i103:vin(1)" )
			)
			( pin "EU7G3.1"
				( objectStatus "@baseboard_fab2_lib.baseboard_fab2(sch_1):page216_i103:vos" )
			)
			( pin "R7G25.1"
				( objectStatus "@baseboard_fab2_lib.baseboard_fab2(sch_1):page216_i104:a" )
			)
			( pin "R7G25.2"
				( objectStatus "@baseboard_fab2_lib.baseboard_fab2(sch_1):page216_i104:b" )
			)
			( pin "R7G30.1"
				( objectStatus "@baseboard_fab2_lib.baseboard_fab2(sch_1):page216_i106:a" )
			)
			( pin "R7G30.2"
				( objectStatus "@baseboard_fab2_lib.baseboard_fab2(sch_1):page216_i106:b" )
			)
			( pin "R3U4.1"
				( objectStatus "@baseboard_fab2_lib.baseboard_fab2(sch_1):page217_i58:a" )
			)
			( pin "R3U4.2"
				( objectStatus "@baseboard_fab2_lib.baseboard_fab2(sch_1):page217_i58:b" )
			)
			( pin "R4U6.1"
				( objectStatus "@baseboard_fab2_lib.baseboard_fab2(sch_1):page217_i74:a" )
			)
			( pin "R4U6.2"
				( objectStatus "@baseboard_fab2_lib.baseboard_fab2(sch_1):page217_i74:b" )
			)
			( pin "C7G28.1"
				( objectStatus "@baseboard_fab2_lib.baseboard_fab2(sch_1):page217_i75:a" )
			)
			( pin "C7G28.2"
				( objectStatus "@baseboard_fab2_lib.baseboard_fab2(sch_1):page217_i75:b" )
			)
			( pin "C3U1.1"
				( objectStatus "@baseboard_fab2_lib.baseboard_fab2(sch_1):page217_i76:a" )
			)
			( pin "C3U1.2"
				( objectStatus "@baseboard_fab2_lib.baseboard_fab2(sch_1):page217_i76:b" )
			)
			( pin "C3U5.1"
				( objectStatus "@baseboard_fab2_lib.baseboard_fab2(sch_1):page217_i77:a" )
			)
			( pin "C3U5.2"
				( objectStatus "@baseboard_fab2_lib.baseboard_fab2(sch_1):page217_i77:b" )
			)
			( pin "C3U8.1"
				( objectStatus "@baseboard_fab2_lib.baseboard_fab2(sch_1):page217_i78:a" )
			)
			( pin "C3U8.2"
				( objectStatus "@baseboard_fab2_lib.baseboard_fab2(sch_1):page217_i78:b" )
			)
			( pin "C5U14.1"
				( objectStatus "@baseboard_fab2_lib.baseboard_fab2(sch_1):page217_i322:a" )
			)
			( pin "C5U14.2"
				( objectStatus "@baseboard_fab2_lib.baseboard_fab2(sch_1):page217_i322:b" )
			)
			( pin "C4T4.1"
				( objectStatus "@baseboard_fab2_lib.baseboard_fab2(sch_1):page217_i319:a" )
			)
			( pin "C4T4.2"
				( objectStatus "@baseboard_fab2_lib.baseboard_fab2(sch_1):page217_i319:b" )
			)
			( pin "C5G9.1"
				( objectStatus "@baseboard_fab2_lib.baseboard_fab2(sch_1):page217_i318:a" )
			)
			( pin "C5G9.2"
				( objectStatus "@baseboard_fab2_lib.baseboard_fab2(sch_1):page217_i318:b" )
			)
			( pin "C5P41.1"
				( objectStatus "@baseboard_fab2_lib.baseboard_fab2(sch_1):page217_i323:a" )
			)
			( pin "C5P41.2"
				( objectStatus "@baseboard_fab2_lib.baseboard_fab2(sch_1):page217_i323:b" )
			)
			( pin "C5P43.1"
				( objectStatus "@baseboard_fab2_lib.baseboard_fab2(sch_1):page217_i326:a" )
			)
			( pin "C5P43.2"
				( objectStatus "@baseboard_fab2_lib.baseboard_fab2(sch_1):page217_i326:b" )
			)
			( pin "C5P42.1"
				( objectStatus "@baseboard_fab2_lib.baseboard_fab2(sch_1):page217_i325:a" )
			)
			( pin "C5P42.2"
				( objectStatus "@baseboard_fab2_lib.baseboard_fab2(sch_1):page217_i325:b" )
			)
			( pin "C5U13.1"
				( objectStatus "@baseboard_fab2_lib.baseboard_fab2(sch_1):page217_i321:a" )
			)
			( pin "C5U13.2"
				( objectStatus "@baseboard_fab2_lib.baseboard_fab2(sch_1):page217_i321:b" )
			)
			( pin "C5A20.1"
				( objectStatus "@baseboard_fab2_lib.baseboard_fab2(sch_1):page220_i308:a" )
			)
			( pin "C5A20.2"
				( objectStatus "@baseboard_fab2_lib.baseboard_fab2(sch_1):page220_i308:b" )
			)
			( pin "L7A5.2"
				( objectStatus "@baseboard_fab2_lib.baseboard_fab2(sch_1):page220_i241:f" )
			)
			( pin "L7A5.1"
				( objectStatus "@baseboard_fab2_lib.baseboard_fab2(sch_1):page220_i241:s" )
			)
			( pin "C7G2.1"
				( objectStatus "@baseboard_fab2_lib.baseboard_fab2(sch_1):page217_i175:a" )
			)
			( pin "C7G2.2"
				( objectStatus "@baseboard_fab2_lib.baseboard_fab2(sch_1):page217_i175:b" )
			)
			( pin "C5A10.1"
				( objectStatus "@baseboard_fab2_lib.baseboard_fab2(sch_1):page220_i321:a" )
			)
			( pin "C5A10.2"
				( objectStatus "@baseboard_fab2_lib.baseboard_fab2(sch_1):page220_i321:b" )
			)
			( pin "C5U5.1"
				( objectStatus "@baseboard_fab2_lib.baseboard_fab2(sch_1):page217_i286:a" )
			)
			( pin "C5U5.2"
				( objectStatus "@baseboard_fab2_lib.baseboard_fab2(sch_1):page217_i286:b" )
			)
			( pin "C5U4.1"
				( objectStatus "@baseboard_fab2_lib.baseboard_fab2(sch_1):page217_i285:a" )
			)
			( pin "C5U4.2"
				( objectStatus "@baseboard_fab2_lib.baseboard_fab2(sch_1):page217_i285:b" )
			)
			( pin "C5U3.1"
				( objectStatus "@baseboard_fab2_lib.baseboard_fab2(sch_1):page217_i284:a" )
			)
			( pin "C5U3.2"
				( objectStatus "@baseboard_fab2_lib.baseboard_fab2(sch_1):page217_i284:b" )
			)
			( pin "C5U2.1"
				( objectStatus "@baseboard_fab2_lib.baseboard_fab2(sch_1):page217_i283:a" )
			)
			( pin "C5U2.2"
				( objectStatus "@baseboard_fab2_lib.baseboard_fab2(sch_1):page217_i283:b" )
			)
			( pin "C5U16.1"
				( objectStatus "@baseboard_fab2_lib.baseboard_fab2(sch_1):page221_i46:a" )
			)
			( pin "C5U16.2"
				( objectStatus "@baseboard_fab2_lib.baseboard_fab2(sch_1):page221_i46:b" )
			)
			( pin "C5F2.1"
				( objectStatus "@baseboard_fab2_lib.baseboard_fab2(sch_1):page217_i205:a" )
			)
			( pin "C5F2.2"
				( objectStatus "@baseboard_fab2_lib.baseboard_fab2(sch_1):page217_i205:b" )
			)
			( pin "C5F1.1"
				( objectStatus "@baseboard_fab2_lib.baseboard_fab2(sch_1):page217_i206:a" )
			)
			( pin "C5F1.2"
				( objectStatus "@baseboard_fab2_lib.baseboard_fab2(sch_1):page217_i206:b" )
			)
			( pin "C5G10.1"
				( objectStatus "@baseboard_fab2_lib.baseboard_fab2(sch_1):page217_i207:a" )
			)
			( pin "C5G10.2"
				( objectStatus "@baseboard_fab2_lib.baseboard_fab2(sch_1):page217_i207:b" )
			)
			( pin "C5T2.1"
				( objectStatus "@baseboard_fab2_lib.baseboard_fab2(sch_1):page217_i208:a" )
			)
			( pin "C5T2.2"
				( objectStatus "@baseboard_fab2_lib.baseboard_fab2(sch_1):page217_i208:b" )
			)
			( pin "C5U11.1"
				( objectStatus "@baseboard_fab2_lib.baseboard_fab2(sch_1):page217_i209:a" )
			)
			( pin "C5U11.2"
				( objectStatus "@baseboard_fab2_lib.baseboard_fab2(sch_1):page217_i209:b" )
			)
			( pin "C5T13.1"
				( objectStatus "@baseboard_fab2_lib.baseboard_fab2(sch_1):page217_i210:a" )
			)
			( pin "C5T13.2"
				( objectStatus "@baseboard_fab2_lib.baseboard_fab2(sch_1):page217_i210:b" )
			)
			( pin "C5T4.1"
				( objectStatus "@baseboard_fab2_lib.baseboard_fab2(sch_1):page217_i211:a" )
			)
			( pin "C5T4.2"
				( objectStatus "@baseboard_fab2_lib.baseboard_fab2(sch_1):page217_i211:b" )
			)
			( pin "C5T1.1"
				( objectStatus "@baseboard_fab2_lib.baseboard_fab2(sch_1):page217_i212:a" )
			)
			( pin "C5T1.2"
				( objectStatus "@baseboard_fab2_lib.baseboard_fab2(sch_1):page217_i212:b" )
			)
			( pin "C5G19.1"
				( objectStatus "@baseboard_fab2_lib.baseboard_fab2(sch_1):page217_i213:a" )
			)
			( pin "C5G19.2"
				( objectStatus "@baseboard_fab2_lib.baseboard_fab2(sch_1):page217_i213:b" )
			)
			( pin "C5G3.1"
				( objectStatus "@baseboard_fab2_lib.baseboard_fab2(sch_1):page217_i314:a" )
			)
			( pin "C5G3.2"
				( objectStatus "@baseboard_fab2_lib.baseboard_fab2(sch_1):page217_i314:b" )
			)
			( pin "C5A19.1"
				( objectStatus "@baseboard_fab2_lib.baseboard_fab2(sch_1):page220_i277:a" )
			)
			( pin "C5A19.2"
				( objectStatus "@baseboard_fab2_lib.baseboard_fab2(sch_1):page220_i277:b" )
			)
			( pin "C5G15.1"
				( objectStatus "@baseboard_fab2_lib.baseboard_fab2(sch_1):page217_i313:a" )
			)
			( pin "C5G15.2"
				( objectStatus "@baseboard_fab2_lib.baseboard_fab2(sch_1):page217_i313:b" )
			)
			( pin "C5G16.1"
				( objectStatus "@baseboard_fab2_lib.baseboard_fab2(sch_1):page217_i312:a" )
			)
			( pin "C5G16.2"
				( objectStatus "@baseboard_fab2_lib.baseboard_fab2(sch_1):page217_i312:b" )
			)
			( pin "C5A18.1"
				( objectStatus "@baseboard_fab2_lib.baseboard_fab2(sch_1):page220_i276:a" )
			)
			( pin "C5A18.2"
				( objectStatus "@baseboard_fab2_lib.baseboard_fab2(sch_1):page220_i276:b" )
			)
			( pin "C5A17.1"
				( objectStatus "@baseboard_fab2_lib.baseboard_fab2(sch_1):page220_i275:a" )
			)
			( pin "C5A17.2"
				( objectStatus "@baseboard_fab2_lib.baseboard_fab2(sch_1):page220_i275:b" )
			)
			( pin "C5G14.1"
				( objectStatus "@baseboard_fab2_lib.baseboard_fab2(sch_1):page217_i311:a" )
			)
			( pin "C5G14.2"
				( objectStatus "@baseboard_fab2_lib.baseboard_fab2(sch_1):page217_i311:b" )
			)
			( pin "C5A4.1"
				( objectStatus "@baseboard_fab2_lib.baseboard_fab2(sch_1):page220_i274:a" )
			)
			( pin "C5A4.2"
				( objectStatus "@baseboard_fab2_lib.baseboard_fab2(sch_1):page220_i274:b" )
			)
			( pin "C5G17.1"
				( objectStatus "@baseboard_fab2_lib.baseboard_fab2(sch_1):page217_i310:a" )
			)
			( pin "C5G17.2"
				( objectStatus "@baseboard_fab2_lib.baseboard_fab2(sch_1):page217_i310:b" )
			)
			( pin "C5G18.1"
				( objectStatus "@baseboard_fab2_lib.baseboard_fab2(sch_1):page217_i309:a" )
			)
			( pin "C5G18.2"
				( objectStatus "@baseboard_fab2_lib.baseboard_fab2(sch_1):page217_i309:b" )
			)
			( pin "C5A16.1"
				( objectStatus "@baseboard_fab2_lib.baseboard_fab2(sch_1):page220_i273:a" )
			)
			( pin "C5A16.2"
				( objectStatus "@baseboard_fab2_lib.baseboard_fab2(sch_1):page220_i273:b" )
			)
			( pin "C5A9.1"
				( objectStatus "@baseboard_fab2_lib.baseboard_fab2(sch_1):page220_i272:a" )
			)
			( pin "C5A9.2"
				( objectStatus "@baseboard_fab2_lib.baseboard_fab2(sch_1):page220_i272:b" )
			)
			( pin "C5G8.1"
				( objectStatus "@baseboard_fab2_lib.baseboard_fab2(sch_1):page217_i308:a" )
			)
			( pin "C5G8.2"
				( objectStatus "@baseboard_fab2_lib.baseboard_fab2(sch_1):page217_i308:b" )
			)
			( pin "C5G1.1"
				( objectStatus "@baseboard_fab2_lib.baseboard_fab2(sch_1):page217_i307:a" )
			)
			( pin "C5G1.2"
				( objectStatus "@baseboard_fab2_lib.baseboard_fab2(sch_1):page217_i307:b" )
			)
			( pin "C5A8.1"
				( objectStatus "@baseboard_fab2_lib.baseboard_fab2(sch_1):page220_i271:a" )
			)
			( pin "C5A8.2"
				( objectStatus "@baseboard_fab2_lib.baseboard_fab2(sch_1):page220_i271:b" )
			)
			( pin "C5A3.1"
				( objectStatus "@baseboard_fab2_lib.baseboard_fab2(sch_1):page220_i270:a" )
			)
			( pin "C5A3.2"
				( objectStatus "@baseboard_fab2_lib.baseboard_fab2(sch_1):page220_i270:b" )
			)
			( pin "C5G7.1"
				( objectStatus "@baseboard_fab2_lib.baseboard_fab2(sch_1):page217_i306:a" )
			)
			( pin "C5G7.2"
				( objectStatus "@baseboard_fab2_lib.baseboard_fab2(sch_1):page217_i306:b" )
			)
			( pin "C5G5.1"
				( objectStatus "@baseboard_fab2_lib.baseboard_fab2(sch_1):page217_i305:a" )
			)
			( pin "C5G5.2"
				( objectStatus "@baseboard_fab2_lib.baseboard_fab2(sch_1):page217_i305:b" )
			)
			( pin "C5A7.1"
				( objectStatus "@baseboard_fab2_lib.baseboard_fab2(sch_1):page220_i269:a" )
			)
			( pin "C5A7.2"
				( objectStatus "@baseboard_fab2_lib.baseboard_fab2(sch_1):page220_i269:b" )
			)
			( pin "C5A6.1"
				( objectStatus "@baseboard_fab2_lib.baseboard_fab2(sch_1):page220_i268:a" )
			)
			( pin "C5A6.2"
				( objectStatus "@baseboard_fab2_lib.baseboard_fab2(sch_1):page220_i268:b" )
			)
			( pin "C5G6.1"
				( objectStatus "@baseboard_fab2_lib.baseboard_fab2(sch_1):page217_i304:a" )
			)
			( pin "C5G6.2"
				( objectStatus "@baseboard_fab2_lib.baseboard_fab2(sch_1):page217_i304:b" )
			)
			( pin "C5A14.1"
				( objectStatus "@baseboard_fab2_lib.baseboard_fab2(sch_1):page220_i267:a" )
			)
			( pin "C5A14.2"
				( objectStatus "@baseboard_fab2_lib.baseboard_fab2(sch_1):page220_i267:b" )
			)
			( pin "C5G13.1"
				( objectStatus "@baseboard_fab2_lib.baseboard_fab2(sch_1):page217_i303:a" )
			)
			( pin "C5G13.2"
				( objectStatus "@baseboard_fab2_lib.baseboard_fab2(sch_1):page217_i303:b" )
			)
			( pin "C5G4.1"
				( objectStatus "@baseboard_fab2_lib.baseboard_fab2(sch_1):page217_i302:a" )
			)
			( pin "C5G4.2"
				( objectStatus "@baseboard_fab2_lib.baseboard_fab2(sch_1):page217_i302:b" )
			)
			( pin "C5A2.1"
				( objectStatus "@baseboard_fab2_lib.baseboard_fab2(sch_1):page220_i266:a" )
			)
			( pin "C5A2.2"
				( objectStatus "@baseboard_fab2_lib.baseboard_fab2(sch_1):page220_i266:b" )
			)
			( pin "C5D8.1"
				( objectStatus "@baseboard_fab2_lib.baseboard_fab2(sch_1):page220_i261:a" )
			)
			( pin "C5D8.2"
				( objectStatus "@baseboard_fab2_lib.baseboard_fab2(sch_1):page220_i261:b" )
			)
			( pin "C5G2.1"
				( objectStatus "@baseboard_fab2_lib.baseboard_fab2(sch_1):page217_i301:a" )
			)
			( pin "C5G2.2"
				( objectStatus "@baseboard_fab2_lib.baseboard_fab2(sch_1):page217_i301:b" )
			)
			( pin "C5G12.1"
				( objectStatus "@baseboard_fab2_lib.baseboard_fab2(sch_1):page217_i300:a" )
			)
			( pin "C5G12.2"
				( objectStatus "@baseboard_fab2_lib.baseboard_fab2(sch_1):page217_i300:b" )
			)
			( pin "C5D7.1"
				( objectStatus "@baseboard_fab2_lib.baseboard_fab2(sch_1):page220_i260:a" )
			)
			( pin "C5D7.2"
				( objectStatus "@baseboard_fab2_lib.baseboard_fab2(sch_1):page220_i260:b" )
			)
			( pin "C5D6.1"
				( objectStatus "@baseboard_fab2_lib.baseboard_fab2(sch_1):page220_i259:a" )
			)
			( pin "C5D6.2"
				( objectStatus "@baseboard_fab2_lib.baseboard_fab2(sch_1):page220_i259:b" )
			)
			( pin "C5G11.1"
				( objectStatus "@baseboard_fab2_lib.baseboard_fab2(sch_1):page217_i299:a" )
			)
			( pin "C5G11.2"
				( objectStatus "@baseboard_fab2_lib.baseboard_fab2(sch_1):page217_i299:b" )
			)
			( pin "C5D9.1"
				( objectStatus "@baseboard_fab2_lib.baseboard_fab2(sch_1):page220_i258:a" )
			)
			( pin "C5D9.2"
				( objectStatus "@baseboard_fab2_lib.baseboard_fab2(sch_1):page220_i258:b" )
			)
			( pin "SH4U1.1"
				( objectStatus "@baseboard_fab2_lib.baseboard_fab2(sch_1):page217_i259:a" )
			)
			( pin "SH4U1.2"
				( objectStatus "@baseboard_fab2_lib.baseboard_fab2(sch_1):page217_i259:b" )
			)
			( pin "SH4U2.1"
				( objectStatus "@baseboard_fab2_lib.baseboard_fab2(sch_1):page217_i260:a" )
			)
			( pin "SH4U2.2"
				( objectStatus "@baseboard_fab2_lib.baseboard_fab2(sch_1):page217_i260:b" )
			)
			( pin "R1G12.1"
				( objectStatus "@baseboard_fab2_lib.baseboard_fab2(sch_1):page223_i54:a" )
			)
			( pin "R1G12.2"
				( objectStatus "@baseboard_fab2_lib.baseboard_fab2(sch_1):page223_i54:b" )
			)
			( pin "R1G11.1"
				( objectStatus "@baseboard_fab2_lib.baseboard_fab2(sch_1):page223_i49:a" )
			)
			( pin "R1G11.2"
				( objectStatus "@baseboard_fab2_lib.baseboard_fab2(sch_1):page223_i49:b" )
			)
			( pin "C5T3.1"
				( objectStatus "@baseboard_fab2_lib.baseboard_fab2(sch_1):page221_i40:a" )
			)
			( pin "C5T3.2"
				( objectStatus "@baseboard_fab2_lib.baseboard_fab2(sch_1):page221_i40:b" )
			)
			( pin "C7A28.1"
				( objectStatus "@baseboard_fab2_lib.baseboard_fab2(sch_1):page218_i14:a" )
			)
			( pin "C7A28.2"
				( objectStatus "@baseboard_fab2_lib.baseboard_fab2(sch_1):page218_i14:b" )
			)
			( pin "R3M6.1"
				( objectStatus "@baseboard_fab2_lib.baseboard_fab2(sch_1):page218_i15:a" )
			)
			( pin "R3M6.2"
				( objectStatus "@baseboard_fab2_lib.baseboard_fab2(sch_1):page218_i15:b" )
			)
			( pin "C7A29.1"
				( objectStatus "@baseboard_fab2_lib.baseboard_fab2(sch_1):page218_i16:a" )
			)
			( pin "C7A29.2"
				( objectStatus "@baseboard_fab2_lib.baseboard_fab2(sch_1):page218_i16:b" )
			)
			( pin "CF17.1"
				( objectStatus "@baseboard_fab2_lib.baseboard_fab2(sch_1):page218_i17:\1\" )
			)
			( pin "CF17.2"
				( objectStatus "@baseboard_fab2_lib.baseboard_fab2(sch_1):page218_i17:\2\" )
			)
			( pin "R7A17.1"
				( objectStatus "@baseboard_fab2_lib.baseboard_fab2(sch_1):page218_i21:a" )
			)
			( pin "R7A17.2"
				( objectStatus "@baseboard_fab2_lib.baseboard_fab2(sch_1):page218_i21:b" )
			)
			( pin "C8L3.1"
				( objectStatus "@baseboard_fab2_lib.baseboard_fab2(sch_1):page230_i41:a" )
			)
			( pin "C8L3.2"
				( objectStatus "@baseboard_fab2_lib.baseboard_fab2(sch_1):page230_i41:b" )
			)
			( pin "C5L4.1"
				( objectStatus "@baseboard_fab2_lib.baseboard_fab2(sch_1):page222_i45:a" )
			)
			( pin "C5L4.2"
				( objectStatus "@baseboard_fab2_lib.baseboard_fab2(sch_1):page222_i45:b" )
			)
			( pin "R6L9.1"
				( objectStatus "@baseboard_fab2_lib.baseboard_fab2(sch_1):page222_i23:a" )
			)
			( pin "R6L9.2"
				( objectStatus "@baseboard_fab2_lib.baseboard_fab2(sch_1):page222_i23:b" )
			)
			( pin "C4A12.1"
				( objectStatus "@baseboard_fab2_lib.baseboard_fab2(sch_1):page222_i22:a" )
			)
			( pin "C4A12.2"
				( objectStatus "@baseboard_fab2_lib.baseboard_fab2(sch_1):page222_i22:b" )
			)
			( pin "C4A9.1"
				( objectStatus "@baseboard_fab2_lib.baseboard_fab2(sch_1):page222_i20:a" )
			)
			( pin "C4A9.2"
				( objectStatus "@baseboard_fab2_lib.baseboard_fab2(sch_1):page222_i20:b" )
			)
			( pin "R1B12.1"
				( objectStatus "@baseboard_fab2_lib.baseboard_fab2(sch_1):page226_i72:a" )
			)
			( pin "R1B12.2"
				( objectStatus "@baseboard_fab2_lib.baseboard_fab2(sch_1):page226_i72:b" )
			)
			( pin "R3M5.1"
				( objectStatus "@baseboard_fab2_lib.baseboard_fab2(sch_1):page218_i34:a" )
			)
			( pin "R3M5.2"
				( objectStatus "@baseboard_fab2_lib.baseboard_fab2(sch_1):page218_i34:b" )
			)
			( pin "R3M1.1"
				( objectStatus "@baseboard_fab2_lib.baseboard_fab2(sch_1):page218_i35:a" )
			)
			( pin "R3M1.2"
				( objectStatus "@baseboard_fab2_lib.baseboard_fab2(sch_1):page218_i35:b" )
			)
			( pin "C6L3.1"
				( objectStatus "@baseboard_fab2_lib.baseboard_fab2(sch_1):page222_i17:a" )
			)
			( pin "C6L3.2"
				( objectStatus "@baseboard_fab2_lib.baseboard_fab2(sch_1):page222_i17:b" )
			)
			( pin "C6L4.1"
				( objectStatus "@baseboard_fab2_lib.baseboard_fab2(sch_1):page222_i15:a" )
			)
			( pin "C6L4.2"
				( objectStatus "@baseboard_fab2_lib.baseboard_fab2(sch_1):page222_i15:b" )
			)
			( pin "C7A37.1"
				( objectStatus "@baseboard_fab2_lib.baseboard_fab2(sch_1):page218_i40:a" )
			)
			( pin "C7A37.2"
				( objectStatus "@baseboard_fab2_lib.baseboard_fab2(sch_1):page218_i40:b" )
			)
			( pin "R12W31.1"
				( objectStatus "@baseboard_fab2_lib.baseboard_fab2(sch_1):page223_i75:a" )
			)
			( pin "R12W31.2"
				( objectStatus "@baseboard_fab2_lib.baseboard_fab2(sch_1):page223_i75:b" )
			)
			( pin "EU4A1.3"
				( objectStatus "@baseboard_fab2_lib.baseboard_fab2(sch_1):page222_i13:agnd" )
			)
			( pin "EU4A1.2"
				( objectStatus "@baseboard_fab2_lib.baseboard_fab2(sch_1):page222_i13:bias" )
			)
			( pin "EU4A1.7"
				( objectStatus "@baseboard_fab2_lib.baseboard_fab2(sch_1):page222_i13:en" )
			)
			( pin "EU4A1.5"
				( objectStatus "@baseboard_fab2_lib.baseboard_fab2(sch_1):page222_i13:pg" )
			)
			( pin "EU4A1.8"
				( objectStatus "@baseboard_fab2_lib.baseboard_fab2(sch_1):page222_i13:pgnd" )
			)
			( pin "EU4A1.6"
				( objectStatus "@baseboard_fab2_lib.baseboard_fab2(sch_1):page222_i13:sns" )
			)
			( pin "EU4A1.11"
				( objectStatus "@baseboard_fab2_lib.baseboard_fab2(sch_1):page222_i13:thpad" )
			)
			( pin "EU4A1.4"
				( objectStatus "@baseboard_fab2_lib.baseboard_fab2(sch_1):page222_i13:vddq" )
			)
			( pin "EU4A1.10"
				( objectStatus "@baseboard_fab2_lib.baseboard_fab2(sch_1):page222_i13:vin" )
			)
			( pin "EU4A1.1"
				( objectStatus "@baseboard_fab2_lib.baseboard_fab2(sch_1):page222_i13:vref" )
			)
			( pin "EU4A1.9"
				( objectStatus "@baseboard_fab2_lib.baseboard_fab2(sch_1):page222_i13:vtt" )
			)
			( pin "R7B1.1"
				( objectStatus "@baseboard_fab2_lib.baseboard_fab2(sch_1):page218_i59:a" )
			)
			( pin "R7B1.2"
				( objectStatus "@baseboard_fab2_lib.baseboard_fab2(sch_1):page218_i59:b" )
			)
			( pin "R3M3.1"
				( objectStatus "@baseboard_fab2_lib.baseboard_fab2(sch_1):page218_i60:a" )
			)
			( pin "R3M3.2"
				( objectStatus "@baseboard_fab2_lib.baseboard_fab2(sch_1):page218_i60:b" )
			)
			( pin "R6L11.1"
				( objectStatus "@baseboard_fab2_lib.baseboard_fab2(sch_1):page222_i10:a" )
			)
			( pin "R6L11.2"
				( objectStatus "@baseboard_fab2_lib.baseboard_fab2(sch_1):page222_i10:b" )
			)
			( pin "C4A11.1"
				( objectStatus "@baseboard_fab2_lib.baseboard_fab2(sch_1):page222_i9:a" )
			)
			( pin "C4A11.2"
				( objectStatus "@baseboard_fab2_lib.baseboard_fab2(sch_1):page222_i9:b" )
			)
			( pin "C7A12.1"
				( objectStatus "@baseboard_fab2_lib.baseboard_fab2(sch_1):page219_i44:a" )
			)
			( pin "C7A12.2"
				( objectStatus "@baseboard_fab2_lib.baseboard_fab2(sch_1):page219_i44:b" )
			)
			( pin "C3L2.1"
				( objectStatus "@baseboard_fab2_lib.baseboard_fab2(sch_1):page219_i45:a" )
			)
			( pin "C3L2.2"
				( objectStatus "@baseboard_fab2_lib.baseboard_fab2(sch_1):page219_i45:b" )
			)
			( pin "C3L4.1"
				( objectStatus "@baseboard_fab2_lib.baseboard_fab2(sch_1):page219_i46:a" )
			)
			( pin "C3L4.2"
				( objectStatus "@baseboard_fab2_lib.baseboard_fab2(sch_1):page219_i46:b" )
			)
			( pin "C3L13.1"
				( objectStatus "@baseboard_fab2_lib.baseboard_fab2(sch_1):page219_i47:a" )
			)
			( pin "C3L13.2"
				( objectStatus "@baseboard_fab2_lib.baseboard_fab2(sch_1):page219_i47:b" )
			)
			( pin "C7A11.1"
				( objectStatus "@baseboard_fab2_lib.baseboard_fab2(sch_1):page219_i48:a" )
			)
			( pin "C7A11.2"
				( objectStatus "@baseboard_fab2_lib.baseboard_fab2(sch_1):page219_i48:b" )
			)
			( pin "C7A16.1"
				( objectStatus "@baseboard_fab2_lib.baseboard_fab2(sch_1):page219_i50:a" )
			)
			( pin "C7A16.2"
				( objectStatus "@baseboard_fab2_lib.baseboard_fab2(sch_1):page219_i50:b" )
			)
			( pin "C7A5.1"
				( objectStatus "@baseboard_fab2_lib.baseboard_fab2(sch_1):page219_i51:a" )
			)
			( pin "C7A5.2"
				( objectStatus "@baseboard_fab2_lib.baseboard_fab2(sch_1):page219_i51:b" )
			)
			( pin "R9U12.1"
				( objectStatus "@baseboard_fab2_lib.baseboard_fab2(sch_1):page224_i151:a" )
			)
			( pin "R9U12.2"
				( objectStatus "@baseboard_fab2_lib.baseboard_fab2(sch_1):page224_i151:b" )
			)
			( pin "C7G42.1"
				( objectStatus "@baseboard_fab2_lib.baseboard_fab2(sch_1):page216_i150:\1\" )
			)
			( pin "C7G42.2"
				( objectStatus "@baseboard_fab2_lib.baseboard_fab2(sch_1):page216_i150:\2\" )
			)
			( pin "C7A17.1"
				( objectStatus "@baseboard_fab2_lib.baseboard_fab2(sch_1):page219_i54:a" )
			)
			( pin "C7A17.2"
				( objectStatus "@baseboard_fab2_lib.baseboard_fab2(sch_1):page219_i54:b" )
			)
			( pin "L7G1.2"
				( objectStatus "@baseboard_fab2_lib.baseboard_fab2(sch_1):page216_i153:f" )
			)
			( pin "L7G1.1"
				( objectStatus "@baseboard_fab2_lib.baseboard_fab2(sch_1):page216_i153:s" )
			)
			( pin "L7A3.2"
				( objectStatus "@baseboard_fab2_lib.baseboard_fab2(sch_1):page219_i158:f" )
			)
			( pin "L7A3.1"
				( objectStatus "@baseboard_fab2_lib.baseboard_fab2(sch_1):page219_i158:s" )
			)
			( pin "C6A4.1"
				( objectStatus "@baseboard_fab2_lib.baseboard_fab2(sch_1):page219_i68:a" )
			)
			( pin "C6A4.2"
				( objectStatus "@baseboard_fab2_lib.baseboard_fab2(sch_1):page219_i68:b" )
			)
			( pin "C7A25.1"
				( objectStatus "@baseboard_fab2_lib.baseboard_fab2(sch_1):page219_i72:a" )
			)
			( pin "C7A25.2"
				( objectStatus "@baseboard_fab2_lib.baseboard_fab2(sch_1):page219_i72:b" )
			)
			( pin "C7C20.1"
				( objectStatus "@baseboard_fab2_lib.baseboard_fab2(sch_1):page212_i143:\1\" )
			)
			( pin "C7C20.2"
				( objectStatus "@baseboard_fab2_lib.baseboard_fab2(sch_1):page212_i143:\2\" )
			)
			( pin "C7A22.1"
				( objectStatus "@baseboard_fab2_lib.baseboard_fab2(sch_1):page219_i75:a" )
			)
			( pin "C7A22.2"
				( objectStatus "@baseboard_fab2_lib.baseboard_fab2(sch_1):page219_i75:b" )
			)
			( pin "R9U1.1"
				( objectStatus "@baseboard_fab2_lib.baseboard_fab2(sch_1):page224_i150:a" )
			)
			( pin "R9U1.2"
				( objectStatus "@baseboard_fab2_lib.baseboard_fab2(sch_1):page224_i150:b" )
			)
			( pin "C7A24.1"
				( objectStatus "@baseboard_fab2_lib.baseboard_fab2(sch_1):page219_i77:a" )
			)
			( pin "C7A24.2"
				( objectStatus "@baseboard_fab2_lib.baseboard_fab2(sch_1):page219_i77:b" )
			)
			( pin "C7A20.1"
				( objectStatus "@baseboard_fab2_lib.baseboard_fab2(sch_1):page219_i78:a" )
			)
			( pin "C7A20.2"
				( objectStatus "@baseboard_fab2_lib.baseboard_fab2(sch_1):page219_i78:b" )
			)
			( pin "C7A21.1"
				( objectStatus "@baseboard_fab2_lib.baseboard_fab2(sch_1):page219_i79:a" )
			)
			( pin "C7A21.2"
				( objectStatus "@baseboard_fab2_lib.baseboard_fab2(sch_1):page219_i79:b" )
			)
			( pin "C3L17.1"
				( objectStatus "@baseboard_fab2_lib.baseboard_fab2(sch_1):page219_i80:a" )
			)
			( pin "C3L17.2"
				( objectStatus "@baseboard_fab2_lib.baseboard_fab2(sch_1):page219_i80:b" )
			)
			( pin "C3L16.1"
				( objectStatus "@baseboard_fab2_lib.baseboard_fab2(sch_1):page219_i81:a" )
			)
			( pin "C3L16.2"
				( objectStatus "@baseboard_fab2_lib.baseboard_fab2(sch_1):page219_i81:b" )
			)
			( pin "C3L15.1"
				( objectStatus "@baseboard_fab2_lib.baseboard_fab2(sch_1):page219_i84:a" )
			)
			( pin "C3L15.2"
				( objectStatus "@baseboard_fab2_lib.baseboard_fab2(sch_1):page219_i84:b" )
			)
			( pin "C6A1.1"
				( objectStatus "@baseboard_fab2_lib.baseboard_fab2(sch_1):page219_i87:a" )
			)
			( pin "C6A1.2"
				( objectStatus "@baseboard_fab2_lib.baseboard_fab2(sch_1):page219_i87:b" )
			)
			( pin "EU7A1.33"
				( objectStatus "@baseboard_fab2_lib.baseboard_fab2(sch_1):page219_i106:boost" )
			)
			( pin "EU7A1.35"
				( objectStatus "@baseboard_fab2_lib.baseboard_fab2(sch_1):page219_i106:en" )
			)
			( pin "EU7A1.6"
				( objectStatus "@baseboard_fab2_lib.baseboard_fab2(sch_1):page219_i106:gl(0)" )
			)
			( pin "EU7A1.41"
				( objectStatus "@baseboard_fab2_lib.baseboard_fab2(sch_1):page219_i106:gl(1)" )
			)
			( pin "EU7A1.38"
				( objectStatus "@baseboard_fab2_lib.baseboard_fab2(sch_1):page219_i106:iout" )
			)
			( pin "EU7A1.2"
				( objectStatus "@baseboard_fab2_lib.baseboard_fab2(sch_1):page219_i106:lgnd" )
			)
			( pin "EU7A1.31"
				( objectStatus "@baseboard_fab2_lib.baseboard_fab2(sch_1):page219_i106:nc" )
			)
			( pin "EU7A1.37"
				( objectStatus "@baseboard_fab2_lib.baseboard_fab2(sch_1):page219_i106:ocset" )
			)
			( pin "EU7A1.5"
				( objectStatus "@baseboard_fab2_lib.baseboard_fab2(sch_1):page219_i106:pgnd(0)" )
			)
			( pin "EU7A1.7"
				( objectStatus "@baseboard_fab2_lib.baseboard_fab2(sch_1):page219_i106:pgnd(1)" )
			)
			( pin "EU7A1.40"
				( objectStatus "@baseboard_fab2_lib.baseboard_fab2(sch_1):page219_i106:pgnd(2)" )
			)
			( pin "EU7A1.32"
				( objectStatus "@baseboard_fab2_lib.baseboard_fab2(sch_1):page219_i106:phase" )
			)
			( pin "EU7A1.34"
				( objectStatus "@baseboard_fab2_lib.baseboard_fab2(sch_1):page219_i106:pwm" )
			)
			( pin "EU7A1.39"
				( objectStatus "@baseboard_fab2_lib.baseboard_fab2(sch_1):page219_i106:refin" )
			)
			( pin "EU7A1.10"
				( objectStatus "@baseboard_fab2_lib.baseboard_fab2(sch_1):page219_i106:sw" )
			)
			( pin "EU7A1.36"
				( objectStatus "@baseboard_fab2_lib.baseboard_fab2(sch_1):page219_i106:tout_flt" )
			)
			( pin "EU7A1.3"
				( objectStatus "@baseboard_fab2_lib.baseboard_fab2(sch_1):page219_i106:vcc" )
			)
			( pin "EU7A1.4"
				( objectStatus "@baseboard_fab2_lib.baseboard_fab2(sch_1):page219_i106:vdrv" )
			)
			( pin "EU7A1.25"
				( objectStatus "@baseboard_fab2_lib.baseboard_fab2(sch_1):page219_i106:vin(0)" )
			)
			( pin "EU7A1.30"
				( objectStatus "@baseboard_fab2_lib.baseboard_fab2(sch_1):page219_i106:vin(1)" )
			)
			( pin "EU7A1.1"
				( objectStatus "@baseboard_fab2_lib.baseboard_fab2(sch_1):page219_i106:vos" )
			)
			( pin "EU7A4.33"
				( objectStatus "@baseboard_fab2_lib.baseboard_fab2(sch_1):page219_i107:boost" )
			)
			( pin "EU7A4.35"
				( objectStatus "@baseboard_fab2_lib.baseboard_fab2(sch_1):page219_i107:en" )
			)
			( pin "EU7A4.6"
				( objectStatus "@baseboard_fab2_lib.baseboard_fab2(sch_1):page219_i107:gl(0)" )
			)
			( pin "EU7A4.41"
				( objectStatus "@baseboard_fab2_lib.baseboard_fab2(sch_1):page219_i107:gl(1)" )
			)
			( pin "EU7A4.38"
				( objectStatus "@baseboard_fab2_lib.baseboard_fab2(sch_1):page219_i107:iout" )
			)
			( pin "EU7A4.2"
				( objectStatus "@baseboard_fab2_lib.baseboard_fab2(sch_1):page219_i107:lgnd" )
			)
			( pin "EU7A4.31"
				( objectStatus "@baseboard_fab2_lib.baseboard_fab2(sch_1):page219_i107:nc" )
			)
			( pin "EU7A4.37"
				( objectStatus "@baseboard_fab2_lib.baseboard_fab2(sch_1):page219_i107:ocset" )
			)
			( pin "EU7A4.5"
				( objectStatus "@baseboard_fab2_lib.baseboard_fab2(sch_1):page219_i107:pgnd(0)" )
			)
			( pin "EU7A4.7"
				( objectStatus "@baseboard_fab2_lib.baseboard_fab2(sch_1):page219_i107:pgnd(1)" )
			)
			( pin "EU7A4.40"
				( objectStatus "@baseboard_fab2_lib.baseboard_fab2(sch_1):page219_i107:pgnd(2)" )
			)
			( pin "EU7A4.32"
				( objectStatus "@baseboard_fab2_lib.baseboard_fab2(sch_1):page219_i107:phase" )
			)
			( pin "EU7A4.34"
				( objectStatus "@baseboard_fab2_lib.baseboard_fab2(sch_1):page219_i107:pwm" )
			)
			( pin "EU7A4.39"
				( objectStatus "@baseboard_fab2_lib.baseboard_fab2(sch_1):page219_i107:refin" )
			)
			( pin "EU7A4.10"
				( objectStatus "@baseboard_fab2_lib.baseboard_fab2(sch_1):page219_i107:sw" )
			)
			( pin "EU7A4.36"
				( objectStatus "@baseboard_fab2_lib.baseboard_fab2(sch_1):page219_i107:tout_flt" )
			)
			( pin "EU7A4.3"
				( objectStatus "@baseboard_fab2_lib.baseboard_fab2(sch_1):page219_i107:vcc" )
			)
			( pin "EU7A4.4"
				( objectStatus "@baseboard_fab2_lib.baseboard_fab2(sch_1):page219_i107:vdrv" )
			)
			( pin "EU7A4.25"
				( objectStatus "@baseboard_fab2_lib.baseboard_fab2(sch_1):page219_i107:vin(0)" )
			)
			( pin "EU7A4.30"
				( objectStatus "@baseboard_fab2_lib.baseboard_fab2(sch_1):page219_i107:vin(1)" )
			)
			( pin "EU7A4.1"
				( objectStatus "@baseboard_fab2_lib.baseboard_fab2(sch_1):page219_i107:vos" )
			)
			( pin "R7A20.1"
				( objectStatus "@baseboard_fab2_lib.baseboard_fab2(sch_1):page219_i108:a" )
			)
			( pin "R7A20.2"
				( objectStatus "@baseboard_fab2_lib.baseboard_fab2(sch_1):page219_i108:b" )
			)
			( pin "R7A21.1"
				( objectStatus "@baseboard_fab2_lib.baseboard_fab2(sch_1):page219_i110:a" )
			)
			( pin "R7A21.2"
				( objectStatus "@baseboard_fab2_lib.baseboard_fab2(sch_1):page219_i110:b" )
			)
			( pin "R4L4.1"
				( objectStatus "@baseboard_fab2_lib.baseboard_fab2(sch_1):page220_i58:a" )
			)
			( pin "R4L4.2"
				( objectStatus "@baseboard_fab2_lib.baseboard_fab2(sch_1):page220_i58:b" )
			)
			( pin "R4L2.1"
				( objectStatus "@baseboard_fab2_lib.baseboard_fab2(sch_1):page220_i74:a" )
			)
			( pin "R4L2.2"
				( objectStatus "@baseboard_fab2_lib.baseboard_fab2(sch_1):page220_i74:b" )
			)
			( pin "C3L6.1"
				( objectStatus "@baseboard_fab2_lib.baseboard_fab2(sch_1):page220_i75:a" )
			)
			( pin "C3L6.2"
				( objectStatus "@baseboard_fab2_lib.baseboard_fab2(sch_1):page220_i75:b" )
			)
			( pin "C3L14.1"
				( objectStatus "@baseboard_fab2_lib.baseboard_fab2(sch_1):page220_i76:a" )
			)
			( pin "C3L14.2"
				( objectStatus "@baseboard_fab2_lib.baseboard_fab2(sch_1):page220_i76:b" )
			)
			( pin "C6A5.1"
				( objectStatus "@baseboard_fab2_lib.baseboard_fab2(sch_1):page220_i77:a" )
			)
			( pin "C6A5.2"
				( objectStatus "@baseboard_fab2_lib.baseboard_fab2(sch_1):page220_i77:b" )
			)
			( pin "C4L5.1"
				( objectStatus "@baseboard_fab2_lib.baseboard_fab2(sch_1):page220_i78:a" )
			)
			( pin "C4L5.2"
				( objectStatus "@baseboard_fab2_lib.baseboard_fab2(sch_1):page220_i78:b" )
			)
			( pin "C5P5.1"
				( objectStatus "@baseboard_fab2_lib.baseboard_fab2(sch_1):page220_i317:a" )
			)
			( pin "C5P5.2"
				( objectStatus "@baseboard_fab2_lib.baseboard_fab2(sch_1):page220_i317:b" )
			)
			( pin "C5P3.1"
				( objectStatus "@baseboard_fab2_lib.baseboard_fab2(sch_1):page220_i315:a" )
			)
			( pin "C5P3.2"
				( objectStatus "@baseboard_fab2_lib.baseboard_fab2(sch_1):page220_i315:b" )
			)
			( pin "C5L14.1"
				( objectStatus "@baseboard_fab2_lib.baseboard_fab2(sch_1):page220_i313:a" )
			)
			( pin "C5L14.2"
				( objectStatus "@baseboard_fab2_lib.baseboard_fab2(sch_1):page220_i313:b" )
			)
			( pin "C5P4.1"
				( objectStatus "@baseboard_fab2_lib.baseboard_fab2(sch_1):page220_i318:a" )
			)
			( pin "C5P4.2"
				( objectStatus "@baseboard_fab2_lib.baseboard_fab2(sch_1):page220_i318:b" )
			)
			( pin "C5M12.1"
				( objectStatus "@baseboard_fab2_lib.baseboard_fab2(sch_1):page220_i312:a" )
			)
			( pin "C5M12.2"
				( objectStatus "@baseboard_fab2_lib.baseboard_fab2(sch_1):page220_i312:b" )
			)
			( pin "C5M8.1"
				( objectStatus "@baseboard_fab2_lib.baseboard_fab2(sch_1):page220_i314:a" )
			)
			( pin "C5M8.2"
				( objectStatus "@baseboard_fab2_lib.baseboard_fab2(sch_1):page220_i314:b" )
			)
			( pin "C5L2.1"
				( objectStatus "@baseboard_fab2_lib.baseboard_fab2(sch_1):page220_i311:a" )
			)
			( pin "C5L2.2"
				( objectStatus "@baseboard_fab2_lib.baseboard_fab2(sch_1):page220_i311:b" )
			)
			( pin "C6W11.1"
				( objectStatus "@baseboard_fab2_lib.baseboard_fab2(sch_1):page221_i44:a" )
			)
			( pin "C6W11.2"
				( objectStatus "@baseboard_fab2_lib.baseboard_fab2(sch_1):page221_i44:b" )
			)
			( pin "L1F1.2"
				( objectStatus "@baseboard_fab2_lib.baseboard_fab2(sch_1):page225_i253:f" )
			)
			( pin "L1F1.1"
				( objectStatus "@baseboard_fab2_lib.baseboard_fab2(sch_1):page225_i253:s" )
			)
			( pin "C8P34.1"
				( objectStatus "@baseboard_fab2_lib.baseboard_fab2(sch_1):page225_i315:a" )
			)
			( pin "C8P34.2"
				( objectStatus "@baseboard_fab2_lib.baseboard_fab2(sch_1):page225_i315:b" )
			)
			( pin "C8P31.1"
				( objectStatus "@baseboard_fab2_lib.baseboard_fab2(sch_1):page225_i314:a" )
			)
			( pin "C8P31.2"
				( objectStatus "@baseboard_fab2_lib.baseboard_fab2(sch_1):page225_i314:b" )
			)
			( pin "C5A13.1"
				( objectStatus "@baseboard_fab2_lib.baseboard_fab2(sch_1):page220_i265:a" )
			)
			( pin "C5A13.2"
				( objectStatus "@baseboard_fab2_lib.baseboard_fab2(sch_1):page220_i265:b" )
			)
			( pin "C5A12.1"
				( objectStatus "@baseboard_fab2_lib.baseboard_fab2(sch_1):page220_i264:a" )
			)
			( pin "C5A12.2"
				( objectStatus "@baseboard_fab2_lib.baseboard_fab2(sch_1):page220_i264:b" )
			)
			( pin "C5A15.1"
				( objectStatus "@baseboard_fab2_lib.baseboard_fab2(sch_1):page220_i263:a" )
			)
			( pin "C5A15.2"
				( objectStatus "@baseboard_fab2_lib.baseboard_fab2(sch_1):page220_i263:b" )
			)
			( pin "C5A1.1"
				( objectStatus "@baseboard_fab2_lib.baseboard_fab2(sch_1):page220_i262:a" )
			)
			( pin "C5A1.2"
				( objectStatus "@baseboard_fab2_lib.baseboard_fab2(sch_1):page220_i262:b" )
			)
			( pin "C5L15.1"
				( objectStatus "@baseboard_fab2_lib.baseboard_fab2(sch_1):page220_i192:a" )
			)
			( pin "C5L15.2"
				( objectStatus "@baseboard_fab2_lib.baseboard_fab2(sch_1):page220_i192:b" )
			)
			( pin "C5A5.1"
				( objectStatus "@baseboard_fab2_lib.baseboard_fab2(sch_1):page220_i193:a" )
			)
			( pin "C5A5.2"
				( objectStatus "@baseboard_fab2_lib.baseboard_fab2(sch_1):page220_i193:b" )
			)
			( pin "C5B1.1"
				( objectStatus "@baseboard_fab2_lib.baseboard_fab2(sch_1):page220_i194:a" )
			)
			( pin "C5B1.2"
				( objectStatus "@baseboard_fab2_lib.baseboard_fab2(sch_1):page220_i194:b" )
			)
			( pin "C5M9.1"
				( objectStatus "@baseboard_fab2_lib.baseboard_fab2(sch_1):page220_i195:a" )
			)
			( pin "C5M9.2"
				( objectStatus "@baseboard_fab2_lib.baseboard_fab2(sch_1):page220_i195:b" )
			)
			( pin "C4M5.1"
				( objectStatus "@baseboard_fab2_lib.baseboard_fab2(sch_1):page220_i196:a" )
			)
			( pin "C4M5.2"
				( objectStatus "@baseboard_fab2_lib.baseboard_fab2(sch_1):page220_i196:b" )
			)
			( pin "C5B2.1"
				( objectStatus "@baseboard_fab2_lib.baseboard_fab2(sch_1):page220_i197:a" )
			)
			( pin "C5B2.2"
				( objectStatus "@baseboard_fab2_lib.baseboard_fab2(sch_1):page220_i197:b" )
			)
			( pin "C5M10.1"
				( objectStatus "@baseboard_fab2_lib.baseboard_fab2(sch_1):page220_i198:a" )
			)
			( pin "C5M10.2"
				( objectStatus "@baseboard_fab2_lib.baseboard_fab2(sch_1):page220_i198:b" )
			)
			( pin "C5M3.1"
				( objectStatus "@baseboard_fab2_lib.baseboard_fab2(sch_1):page220_i199:a" )
			)
			( pin "C5M3.2"
				( objectStatus "@baseboard_fab2_lib.baseboard_fab2(sch_1):page220_i199:b" )
			)
			( pin "C5M11.1"
				( objectStatus "@baseboard_fab2_lib.baseboard_fab2(sch_1):page220_i200:a" )
			)
			( pin "C5M11.2"
				( objectStatus "@baseboard_fab2_lib.baseboard_fab2(sch_1):page220_i200:b" )
			)
			( pin "C5A11.1"
				( objectStatus "@baseboard_fab2_lib.baseboard_fab2(sch_1):page220_i293:a" )
			)
			( pin "C5A11.2"
				( objectStatus "@baseboard_fab2_lib.baseboard_fab2(sch_1):page220_i293:b" )
			)
			( pin "C4M2.1"
				( objectStatus "@baseboard_fab2_lib.baseboard_fab2(sch_1):page220_i292:a" )
			)
			( pin "C4M2.2"
				( objectStatus "@baseboard_fab2_lib.baseboard_fab2(sch_1):page220_i292:b" )
			)
			( pin "C5M1.1"
				( objectStatus "@baseboard_fab2_lib.baseboard_fab2(sch_1):page220_i291:a" )
			)
			( pin "C5M1.2"
				( objectStatus "@baseboard_fab2_lib.baseboard_fab2(sch_1):page220_i291:b" )
			)
			( pin "C5M2.1"
				( objectStatus "@baseboard_fab2_lib.baseboard_fab2(sch_1):page220_i290:a" )
			)
			( pin "C5M2.2"
				( objectStatus "@baseboard_fab2_lib.baseboard_fab2(sch_1):page220_i290:b" )
			)
			( pin "C5M4.1"
				( objectStatus "@baseboard_fab2_lib.baseboard_fab2(sch_1):page220_i289:a" )
			)
			( pin "C5M4.2"
				( objectStatus "@baseboard_fab2_lib.baseboard_fab2(sch_1):page220_i289:b" )
			)
			( pin "C5M5.1"
				( objectStatus "@baseboard_fab2_lib.baseboard_fab2(sch_1):page220_i288:a" )
			)
			( pin "C5M5.2"
				( objectStatus "@baseboard_fab2_lib.baseboard_fab2(sch_1):page220_i288:b" )
			)
			( pin "C5M6.1"
				( objectStatus "@baseboard_fab2_lib.baseboard_fab2(sch_1):page220_i287:a" )
			)
			( pin "C5M6.2"
				( objectStatus "@baseboard_fab2_lib.baseboard_fab2(sch_1):page220_i287:b" )
			)
			( pin "C5M7.1"
				( objectStatus "@baseboard_fab2_lib.baseboard_fab2(sch_1):page220_i286:a" )
			)
			( pin "C5M7.2"
				( objectStatus "@baseboard_fab2_lib.baseboard_fab2(sch_1):page220_i286:b" )
			)
			( pin "C5L13.1"
				( objectStatus "@baseboard_fab2_lib.baseboard_fab2(sch_1):page220_i285:a" )
			)
			( pin "C5L13.2"
				( objectStatus "@baseboard_fab2_lib.baseboard_fab2(sch_1):page220_i285:b" )
			)
			( pin "C5L12.1"
				( objectStatus "@baseboard_fab2_lib.baseboard_fab2(sch_1):page220_i284:a" )
			)
			( pin "C5L12.2"
				( objectStatus "@baseboard_fab2_lib.baseboard_fab2(sch_1):page220_i284:b" )
			)
			( pin "C5L11.1"
				( objectStatus "@baseboard_fab2_lib.baseboard_fab2(sch_1):page220_i283:a" )
			)
			( pin "C5L11.2"
				( objectStatus "@baseboard_fab2_lib.baseboard_fab2(sch_1):page220_i283:b" )
			)
			( pin "C5L10.1"
				( objectStatus "@baseboard_fab2_lib.baseboard_fab2(sch_1):page220_i282:a" )
			)
			( pin "C5L10.2"
				( objectStatus "@baseboard_fab2_lib.baseboard_fab2(sch_1):page220_i282:b" )
			)
			( pin "C5L9.1"
				( objectStatus "@baseboard_fab2_lib.baseboard_fab2(sch_1):page220_i281:a" )
			)
			( pin "C5L9.2"
				( objectStatus "@baseboard_fab2_lib.baseboard_fab2(sch_1):page220_i281:b" )
			)
			( pin "C5L8.1"
				( objectStatus "@baseboard_fab2_lib.baseboard_fab2(sch_1):page220_i280:a" )
			)
			( pin "C5L8.2"
				( objectStatus "@baseboard_fab2_lib.baseboard_fab2(sch_1):page220_i280:b" )
			)
			( pin "C5L7.1"
				( objectStatus "@baseboard_fab2_lib.baseboard_fab2(sch_1):page220_i279:a" )
			)
			( pin "C5L7.2"
				( objectStatus "@baseboard_fab2_lib.baseboard_fab2(sch_1):page220_i279:b" )
			)
			( pin "C5L6.1"
				( objectStatus "@baseboard_fab2_lib.baseboard_fab2(sch_1):page220_i278:a" )
			)
			( pin "C5L6.2"
				( objectStatus "@baseboard_fab2_lib.baseboard_fab2(sch_1):page220_i278:b" )
			)
			( pin "C2G14.1"
				( objectStatus "@baseboard_fab2_lib.baseboard_fab2(sch_1):page225_i287:a" )
			)
			( pin "C2G14.2"
				( objectStatus "@baseboard_fab2_lib.baseboard_fab2(sch_1):page225_i287:b" )
			)
			( pin "C2G13.1"
				( objectStatus "@baseboard_fab2_lib.baseboard_fab2(sch_1):page225_i286:a" )
			)
			( pin "C2G13.2"
				( objectStatus "@baseboard_fab2_lib.baseboard_fab2(sch_1):page225_i286:b" )
			)
			( pin "C3G2.1"
				( objectStatus "@baseboard_fab2_lib.baseboard_fab2(sch_1):page225_i285:a" )
			)
			( pin "C3G2.2"
				( objectStatus "@baseboard_fab2_lib.baseboard_fab2(sch_1):page225_i285:b" )
			)
			( pin "C3G1.1"
				( objectStatus "@baseboard_fab2_lib.baseboard_fab2(sch_1):page225_i284:a" )
			)
			( pin "C3G1.2"
				( objectStatus "@baseboard_fab2_lib.baseboard_fab2(sch_1):page225_i284:b" )
			)
			( pin "C2G6.1"
				( objectStatus "@baseboard_fab2_lib.baseboard_fab2(sch_1):page225_i283:a" )
			)
			( pin "C2G6.2"
				( objectStatus "@baseboard_fab2_lib.baseboard_fab2(sch_1):page225_i283:b" )
			)
			( pin "C2G5.1"
				( objectStatus "@baseboard_fab2_lib.baseboard_fab2(sch_1):page225_i282:a" )
			)
			( pin "C2G5.2"
				( objectStatus "@baseboard_fab2_lib.baseboard_fab2(sch_1):page225_i282:b" )
			)
			( pin "C2G4.1"
				( objectStatus "@baseboard_fab2_lib.baseboard_fab2(sch_1):page225_i281:a" )
			)
			( pin "C2G4.2"
				( objectStatus "@baseboard_fab2_lib.baseboard_fab2(sch_1):page225_i281:b" )
			)
			( pin "C2G3.1"
				( objectStatus "@baseboard_fab2_lib.baseboard_fab2(sch_1):page225_i280:a" )
			)
			( pin "C2G3.2"
				( objectStatus "@baseboard_fab2_lib.baseboard_fab2(sch_1):page225_i280:b" )
			)
			( pin "C2G2.1"
				( objectStatus "@baseboard_fab2_lib.baseboard_fab2(sch_1):page225_i279:a" )
			)
			( pin "C2G2.2"
				( objectStatus "@baseboard_fab2_lib.baseboard_fab2(sch_1):page225_i279:b" )
			)
			( pin "C2G9.1"
				( objectStatus "@baseboard_fab2_lib.baseboard_fab2(sch_1):page225_i278:a" )
			)
			( pin "C2G9.2"
				( objectStatus "@baseboard_fab2_lib.baseboard_fab2(sch_1):page225_i278:b" )
			)
			( pin "C2G1.1"
				( objectStatus "@baseboard_fab2_lib.baseboard_fab2(sch_1):page225_i277:a" )
			)
			( pin "C2G1.2"
				( objectStatus "@baseboard_fab2_lib.baseboard_fab2(sch_1):page225_i277:b" )
			)
			( pin "C2G12.1"
				( objectStatus "@baseboard_fab2_lib.baseboard_fab2(sch_1):page225_i276:a" )
			)
			( pin "C2G12.2"
				( objectStatus "@baseboard_fab2_lib.baseboard_fab2(sch_1):page225_i276:b" )
			)
			( pin "C2D42.1"
				( objectStatus "@baseboard_fab2_lib.baseboard_fab2(sch_1):page225_i273:a" )
			)
			( pin "C2D42.2"
				( objectStatus "@baseboard_fab2_lib.baseboard_fab2(sch_1):page225_i273:b" )
			)
			( pin "C2D44.1"
				( objectStatus "@baseboard_fab2_lib.baseboard_fab2(sch_1):page225_i272:a" )
			)
			( pin "C2D44.2"
				( objectStatus "@baseboard_fab2_lib.baseboard_fab2(sch_1):page225_i272:b" )
			)
			( pin "C2D41.1"
				( objectStatus "@baseboard_fab2_lib.baseboard_fab2(sch_1):page225_i271:a" )
			)
			( pin "C2D41.2"
				( objectStatus "@baseboard_fab2_lib.baseboard_fab2(sch_1):page225_i271:b" )
			)
			( pin "C2D43.1"
				( objectStatus "@baseboard_fab2_lib.baseboard_fab2(sch_1):page225_i270:a" )
			)
			( pin "C2D43.2"
				( objectStatus "@baseboard_fab2_lib.baseboard_fab2(sch_1):page225_i270:b" )
			)
			( pin "SH4L2.1"
				( objectStatus "@baseboard_fab2_lib.baseboard_fab2(sch_1):page220_i239:a" )
			)
			( pin "SH4L2.2"
				( objectStatus "@baseboard_fab2_lib.baseboard_fab2(sch_1):page220_i239:b" )
			)
			( pin "SH4L1.1"
				( objectStatus "@baseboard_fab2_lib.baseboard_fab2(sch_1):page220_i240:a" )
			)
			( pin "SH4L1.2"
				( objectStatus "@baseboard_fab2_lib.baseboard_fab2(sch_1):page220_i240:b" )
			)
			( pin "R7B4.1"
				( objectStatus "@baseboard_fab2_lib.baseboard_fab2(sch_1):page218_i57:a" )
			)
			( pin "R7B4.2"
				( objectStatus "@baseboard_fab2_lib.baseboard_fab2(sch_1):page218_i57:b" )
			)
			( pin "EU4G3.3"
				( objectStatus "@baseboard_fab2_lib.baseboard_fab2(sch_1):page221_i15:agnd" )
			)
			( pin "EU4G3.2"
				( objectStatus "@baseboard_fab2_lib.baseboard_fab2(sch_1):page221_i15:bias" )
			)
			( pin "EU4G3.7"
				( objectStatus "@baseboard_fab2_lib.baseboard_fab2(sch_1):page221_i15:en" )
			)
			( pin "EU4G3.5"
				( objectStatus "@baseboard_fab2_lib.baseboard_fab2(sch_1):page221_i15:pg" )
			)
			( pin "EU4G3.8"
				( objectStatus "@baseboard_fab2_lib.baseboard_fab2(sch_1):page221_i15:pgnd" )
			)
			( pin "EU4G3.6"
				( objectStatus "@baseboard_fab2_lib.baseboard_fab2(sch_1):page221_i15:sns" )
			)
			( pin "EU4G3.11"
				( objectStatus "@baseboard_fab2_lib.baseboard_fab2(sch_1):page221_i15:thpad" )
			)
			( pin "EU4G3.4"
				( objectStatus "@baseboard_fab2_lib.baseboard_fab2(sch_1):page221_i15:vddq" )
			)
			( pin "EU4G3.10"
				( objectStatus "@baseboard_fab2_lib.baseboard_fab2(sch_1):page221_i15:vin" )
			)
			( pin "EU4G3.1"
				( objectStatus "@baseboard_fab2_lib.baseboard_fab2(sch_1):page221_i15:vref" )
			)
			( pin "EU4G3.9"
				( objectStatus "@baseboard_fab2_lib.baseboard_fab2(sch_1):page221_i15:vtt" )
			)
			( pin "R7A11.1"
				( objectStatus "@baseboard_fab2_lib.baseboard_fab2(sch_1):page218_i56:a" )
			)
			( pin "R7A11.2"
				( objectStatus "@baseboard_fab2_lib.baseboard_fab2(sch_1):page218_i56:b" )
			)
			( pin "C4G16.1"
				( objectStatus "@baseboard_fab2_lib.baseboard_fab2(sch_1):page221_i22:a" )
			)
			( pin "C4G16.2"
				( objectStatus "@baseboard_fab2_lib.baseboard_fab2(sch_1):page221_i22:b" )
			)
			( pin "C4G24.1"
				( objectStatus "@baseboard_fab2_lib.baseboard_fab2(sch_1):page221_i24:a" )
			)
			( pin "C4G24.2"
				( objectStatus "@baseboard_fab2_lib.baseboard_fab2(sch_1):page221_i24:b" )
			)
			( pin "R12W30.1"
				( objectStatus "@baseboard_fab2_lib.baseboard_fab2(sch_1):page218_i55:a" )
			)
			( pin "R12W30.2"
				( objectStatus "@baseboard_fab2_lib.baseboard_fab2(sch_1):page218_i55:b" )
			)
			( pin "R12W29.1"
				( objectStatus "@baseboard_fab2_lib.baseboard_fab2(sch_1):page218_i46:a" )
			)
			( pin "R12W29.2"
				( objectStatus "@baseboard_fab2_lib.baseboard_fab2(sch_1):page218_i46:b" )
			)
			( pin "R7A12.1"
				( objectStatus "@baseboard_fab2_lib.baseboard_fab2(sch_1):page218_i45:a" )
			)
			( pin "R7A12.2"
				( objectStatus "@baseboard_fab2_lib.baseboard_fab2(sch_1):page218_i45:b" )
			)
			( pin "C7T1.1"
				( objectStatus "@baseboard_fab2_lib.baseboard_fab2(sch_1):page225_i309:a" )
			)
			( pin "C7T1.2"
				( objectStatus "@baseboard_fab2_lib.baseboard_fab2(sch_1):page225_i309:b" )
			)
			( pin "C7B3.1"
				( objectStatus "@baseboard_fab2_lib.baseboard_fab2(sch_1):page218_i41:a" )
			)
			( pin "C7B3.2"
				( objectStatus "@baseboard_fab2_lib.baseboard_fab2(sch_1):page218_i41:b" )
			)
			( pin "C7A38.1"
				( objectStatus "@baseboard_fab2_lib.baseboard_fab2(sch_1):page218_i38:a" )
			)
			( pin "C7A38.2"
				( objectStatus "@baseboard_fab2_lib.baseboard_fab2(sch_1):page218_i38:b" )
			)
			( pin "R1G22.1"
				( objectStatus "@baseboard_fab2_lib.baseboard_fab2(sch_1):page223_i74:a" )
			)
			( pin "R1G22.2"
				( objectStatus "@baseboard_fab2_lib.baseboard_fab2(sch_1):page223_i74:b" )
			)
			( pin "C7B1.1"
				( objectStatus "@baseboard_fab2_lib.baseboard_fab2(sch_1):page218_i30:a" )
			)
			( pin "C7B1.2"
				( objectStatus "@baseboard_fab2_lib.baseboard_fab2(sch_1):page218_i30:b" )
			)
			( pin "C7B2.1"
				( objectStatus "@baseboard_fab2_lib.baseboard_fab2(sch_1):page218_i28:a" )
			)
			( pin "C7B2.2"
				( objectStatus "@baseboard_fab2_lib.baseboard_fab2(sch_1):page218_i28:b" )
			)
			( pin "CF18.1"
				( objectStatus "@baseboard_fab2_lib.baseboard_fab2(sch_1):page218_i20:\1\" )
			)
			( pin "CF18.2"
				( objectStatus "@baseboard_fab2_lib.baseboard_fab2(sch_1):page218_i20:\2\" )
			)
			( pin "RF18.1"
				( objectStatus "@baseboard_fab2_lib.baseboard_fab2(sch_1):page218_i19:a" )
			)
			( pin "RF18.2"
				( objectStatus "@baseboard_fab2_lib.baseboard_fab2(sch_1):page218_i19:b" )
			)
			( pin "RF17.1"
				( objectStatus "@baseboard_fab2_lib.baseboard_fab2(sch_1):page218_i18:a" )
			)
			( pin "RF17.2"
				( objectStatus "@baseboard_fab2_lib.baseboard_fab2(sch_1):page218_i18:b" )
			)
			( pin "R7A7.1"
				( objectStatus "@baseboard_fab2_lib.baseboard_fab2(sch_1):page218_i13:a" )
			)
			( pin "R7A7.2"
				( objectStatus "@baseboard_fab2_lib.baseboard_fab2(sch_1):page218_i13:b" )
			)
			( pin "C4A10.1"
				( objectStatus "@baseboard_fab2_lib.baseboard_fab2(sch_1):page222_i12:a" )
			)
			( pin "C4A10.2"
				( objectStatus "@baseboard_fab2_lib.baseboard_fab2(sch_1):page222_i12:b" )
			)
			( pin "R1G16.1"
				( objectStatus "@baseboard_fab2_lib.baseboard_fab2(sch_1):page223_i48:a" )
			)
			( pin "R1G16.2"
				( objectStatus "@baseboard_fab2_lib.baseboard_fab2(sch_1):page223_i48:b" )
			)
			( pin "R12W34.1"
				( objectStatus "@baseboard_fab2_lib.baseboard_fab2(sch_1):page226_i74:a" )
			)
			( pin "R12W34.2"
				( objectStatus "@baseboard_fab2_lib.baseboard_fab2(sch_1):page226_i74:b" )
			)
			( pin "R12W32.1"
				( objectStatus "@baseboard_fab2_lib.baseboard_fab2(sch_1):page223_i45:a" )
			)
			( pin "R12W32.2"
				( objectStatus "@baseboard_fab2_lib.baseboard_fab2(sch_1):page223_i45:b" )
			)
			( pin "C6W12.1"
				( objectStatus "@baseboard_fab2_lib.baseboard_fab2(sch_1):page229_i43:a" )
			)
			( pin "C6W12.2"
				( objectStatus "@baseboard_fab2_lib.baseboard_fab2(sch_1):page229_i43:b" )
			)
			( pin "C4A1.1"
				( objectStatus "@baseboard_fab2_lib.baseboard_fab2(sch_1):page222_i28:a" )
			)
			( pin "C4A1.2"
				( objectStatus "@baseboard_fab2_lib.baseboard_fab2(sch_1):page222_i28:b" )
			)
			( pin "SH5L1.1"
				( objectStatus "@baseboard_fab2_lib.baseboard_fab2(sch_1):page222_i30:a" )
			)
			( pin "SH5L1.2"
				( objectStatus "@baseboard_fab2_lib.baseboard_fab2(sch_1):page222_i30:b" )
			)
			( pin "R4A6.1"
				( objectStatus "@baseboard_fab2_lib.baseboard_fab2(sch_1):page222_i31:a" )
			)
			( pin "R4A6.2"
				( objectStatus "@baseboard_fab2_lib.baseboard_fab2(sch_1):page222_i31:b" )
			)
			( pin "C1G22.1"
				( objectStatus "@baseboard_fab2_lib.baseboard_fab2(sch_1):page223_i43:a" )
			)
			( pin "C1G22.2"
				( objectStatus "@baseboard_fab2_lib.baseboard_fab2(sch_1):page223_i43:b" )
			)
			( pin "C1G21.1"
				( objectStatus "@baseboard_fab2_lib.baseboard_fab2(sch_1):page223_i40:a" )
			)
			( pin "C1G21.2"
				( objectStatus "@baseboard_fab2_lib.baseboard_fab2(sch_1):page223_i40:b" )
			)
			( pin "C1G25.1"
				( objectStatus "@baseboard_fab2_lib.baseboard_fab2(sch_1):page223_i35:a" )
			)
			( pin "C1G25.2"
				( objectStatus "@baseboard_fab2_lib.baseboard_fab2(sch_1):page223_i35:b" )
			)
			( pin "R9U8.1"
				( objectStatus "@baseboard_fab2_lib.baseboard_fab2(sch_1):page223_i31:a" )
			)
			( pin "R9U8.2"
				( objectStatus "@baseboard_fab2_lib.baseboard_fab2(sch_1):page223_i31:b" )
			)
			( pin "RF20.1"
				( objectStatus "@baseboard_fab2_lib.baseboard_fab2(sch_1):page223_i19:a" )
			)
			( pin "RF20.2"
				( objectStatus "@baseboard_fab2_lib.baseboard_fab2(sch_1):page223_i19:b" )
			)
			( pin "R1G7.1"
				( objectStatus "@baseboard_fab2_lib.baseboard_fab2(sch_1):page223_i18:a" )
			)
			( pin "R1G7.2"
				( objectStatus "@baseboard_fab2_lib.baseboard_fab2(sch_1):page223_i18:b" )
			)
			( pin "CF19.1"
				( objectStatus "@baseboard_fab2_lib.baseboard_fab2(sch_1):page223_i15:\1\" )
			)
			( pin "CF19.2"
				( objectStatus "@baseboard_fab2_lib.baseboard_fab2(sch_1):page223_i15:\2\" )
			)
			( pin "C1G16.1"
				( objectStatus "@baseboard_fab2_lib.baseboard_fab2(sch_1):page223_i12:a" )
			)
			( pin "C1G16.2"
				( objectStatus "@baseboard_fab2_lib.baseboard_fab2(sch_1):page223_i12:b" )
			)
			( pin "U25W16.12"
				( objectStatus "@baseboard_fab2_lib.baseboard_fab2(sch_1):page268_i38:a(0)" )
			)
			( pin "U25W16.9"
				( objectStatus "@baseboard_fab2_lib.baseboard_fab2(sch_1):page268_i38:a(1)" )
			)
			( pin "U25W16.5"
				( objectStatus "@baseboard_fab2_lib.baseboard_fab2(sch_1):page268_i38:a(2)" )
			)
			( pin "U25W16.2"
				( objectStatus "@baseboard_fab2_lib.baseboard_fab2(sch_1):page268_i38:a(3)" )
			)
			( pin "U25W16.11"
				( objectStatus "@baseboard_fab2_lib.baseboard_fab2(sch_1):page268_i38:b(0)" )
			)
			( pin "U25W16.8"
				( objectStatus "@baseboard_fab2_lib.baseboard_fab2(sch_1):page268_i38:b(1)" )
			)
			( pin "U25W16.6"
				( objectStatus "@baseboard_fab2_lib.baseboard_fab2(sch_1):page268_i38:b(2)" )
			)
			( pin "U25W16.3"
				( objectStatus "@baseboard_fab2_lib.baseboard_fab2(sch_1):page268_i38:b(3)" )
			)
			( pin "U25W16.13"
				( objectStatus "@baseboard_fab2_lib.baseboard_fab2(sch_1):page268_i38:oe(0)" )
			)
			( pin "U25W16.10"
				( objectStatus "@baseboard_fab2_lib.baseboard_fab2(sch_1):page268_i38:oe(1)" )
			)
			( pin "U25W16.4"
				( objectStatus "@baseboard_fab2_lib.baseboard_fab2(sch_1):page268_i38:oe(2)" )
			)
			( pin "U25W16.1"
				( objectStatus "@baseboard_fab2_lib.baseboard_fab2(sch_1):page268_i38:oe(3)" )
			)
			( pin "R1G5.1"
				( objectStatus "@baseboard_fab2_lib.baseboard_fab2(sch_1):page223_i13:a" )
			)
			( pin "R1G5.2"
				( objectStatus "@baseboard_fab2_lib.baseboard_fab2(sch_1):page223_i13:b" )
			)
			( pin "R9U7.1"
				( objectStatus "@baseboard_fab2_lib.baseboard_fab2(sch_1):page223_i14:a" )
			)
			( pin "R9U7.2"
				( objectStatus "@baseboard_fab2_lib.baseboard_fab2(sch_1):page223_i14:b" )
			)
			( pin "RF19.1"
				( objectStatus "@baseboard_fab2_lib.baseboard_fab2(sch_1):page223_i16:a" )
			)
			( pin "RF19.2"
				( objectStatus "@baseboard_fab2_lib.baseboard_fab2(sch_1):page223_i16:b" )
			)
			( pin "CF20.1"
				( objectStatus "@baseboard_fab2_lib.baseboard_fab2(sch_1):page223_i17:\1\" )
			)
			( pin "CF20.2"
				( objectStatus "@baseboard_fab2_lib.baseboard_fab2(sch_1):page223_i17:\2\" )
			)
			( pin "R1B5.1"
				( objectStatus "@baseboard_fab2_lib.baseboard_fab2(sch_1):page226_i55:a" )
			)
			( pin "R1B5.2"
				( objectStatus "@baseboard_fab2_lib.baseboard_fab2(sch_1):page226_i55:b" )
			)
			( pin "R1B4.1"
				( objectStatus "@baseboard_fab2_lib.baseboard_fab2(sch_1):page226_i54:a" )
			)
			( pin "R1B4.2"
				( objectStatus "@baseboard_fab2_lib.baseboard_fab2(sch_1):page226_i54:b" )
			)
			( pin "EU4G2.3"
				( objectStatus "@baseboard_fab2_lib.baseboard_fab2(sch_1):page229_i37:agnd" )
			)
			( pin "EU4G2.2"
				( objectStatus "@baseboard_fab2_lib.baseboard_fab2(sch_1):page229_i37:bias" )
			)
			( pin "EU4G2.7"
				( objectStatus "@baseboard_fab2_lib.baseboard_fab2(sch_1):page229_i37:en" )
			)
			( pin "EU4G2.5"
				( objectStatus "@baseboard_fab2_lib.baseboard_fab2(sch_1):page229_i37:pg" )
			)
			( pin "EU4G2.8"
				( objectStatus "@baseboard_fab2_lib.baseboard_fab2(sch_1):page229_i37:pgnd" )
			)
			( pin "EU4G2.6"
				( objectStatus "@baseboard_fab2_lib.baseboard_fab2(sch_1):page229_i37:sns" )
			)
			( pin "EU4G2.11"
				( objectStatus "@baseboard_fab2_lib.baseboard_fab2(sch_1):page229_i37:thpad" )
			)
			( pin "EU4G2.4"
				( objectStatus "@baseboard_fab2_lib.baseboard_fab2(sch_1):page229_i37:vddq" )
			)
			( pin "EU4G2.10"
				( objectStatus "@baseboard_fab2_lib.baseboard_fab2(sch_1):page229_i37:vin" )
			)
			( pin "EU4G2.1"
				( objectStatus "@baseboard_fab2_lib.baseboard_fab2(sch_1):page229_i37:vref" )
			)
			( pin "EU4G2.9"
				( objectStatus "@baseboard_fab2_lib.baseboard_fab2(sch_1):page229_i37:vtt" )
			)
			( pin "C1G24.1"
				( objectStatus "@baseboard_fab2_lib.baseboard_fab2(sch_1):page223_i27:a" )
			)
			( pin "C1G24.2"
				( objectStatus "@baseboard_fab2_lib.baseboard_fab2(sch_1):page223_i27:b" )
			)
			( pin "R9U10.1"
				( objectStatus "@baseboard_fab2_lib.baseboard_fab2(sch_1):page223_i32:a" )
			)
			( pin "R9U10.2"
				( objectStatus "@baseboard_fab2_lib.baseboard_fab2(sch_1):page223_i32:b" )
			)
			( pin "C1G27.1"
				( objectStatus "@baseboard_fab2_lib.baseboard_fab2(sch_1):page223_i36:a" )
			)
			( pin "C1G27.2"
				( objectStatus "@baseboard_fab2_lib.baseboard_fab2(sch_1):page223_i36:b" )
			)
			( pin "C6W13.1"
				( objectStatus "@baseboard_fab2_lib.baseboard_fab2(sch_1):page230_i43:a" )
			)
			( pin "C6W13.2"
				( objectStatus "@baseboard_fab2_lib.baseboard_fab2(sch_1):page230_i43:b" )
			)
			( pin "R1G10.1"
				( objectStatus "@baseboard_fab2_lib.baseboard_fab2(sch_1):page223_i41:a" )
			)
			( pin "R1G10.2"
				( objectStatus "@baseboard_fab2_lib.baseboard_fab2(sch_1):page223_i41:b" )
			)
			( pin "C1G23.1"
				( objectStatus "@baseboard_fab2_lib.baseboard_fab2(sch_1):page223_i44:a" )
			)
			( pin "C1G23.2"
				( objectStatus "@baseboard_fab2_lib.baseboard_fab2(sch_1):page223_i44:b" )
			)
			( pin "R1G9.1"
				( objectStatus "@baseboard_fab2_lib.baseboard_fab2(sch_1):page223_i50:a" )
			)
			( pin "R1G9.2"
				( objectStatus "@baseboard_fab2_lib.baseboard_fab2(sch_1):page223_i50:b" )
			)
			( pin "R12W33.1"
				( objectStatus "@baseboard_fab2_lib.baseboard_fab2(sch_1):page223_i53:a" )
			)
			( pin "R12W33.2"
				( objectStatus "@baseboard_fab2_lib.baseboard_fab2(sch_1):page223_i53:b" )
			)
			( pin "C2F2.1"
				( objectStatus "@baseboard_fab2_lib.baseboard_fab2(sch_1):page229_i28:a" )
			)
			( pin "C2F2.2"
				( objectStatus "@baseboard_fab2_lib.baseboard_fab2(sch_1):page229_i28:b" )
			)
			( pin "C4G13.1"
				( objectStatus "@baseboard_fab2_lib.baseboard_fab2(sch_1):page229_i26:a" )
			)
			( pin "C4G13.2"
				( objectStatus "@baseboard_fab2_lib.baseboard_fab2(sch_1):page229_i26:b" )
			)
			( pin "C4G20.1"
				( objectStatus "@baseboard_fab2_lib.baseboard_fab2(sch_1):page229_i23:a" )
			)
			( pin "C4G20.2"
				( objectStatus "@baseboard_fab2_lib.baseboard_fab2(sch_1):page229_i23:b" )
			)
			( pin "C6U14.1"
				( objectStatus "@baseboard_fab2_lib.baseboard_fab2(sch_1):page229_i18:a" )
			)
			( pin "C6U14.2"
				( objectStatus "@baseboard_fab2_lib.baseboard_fab2(sch_1):page229_i18:b" )
			)
			( pin "C4G18.1"
				( objectStatus "@baseboard_fab2_lib.baseboard_fab2(sch_1):page229_i16:a" )
			)
			( pin "C4G18.2"
				( objectStatus "@baseboard_fab2_lib.baseboard_fab2(sch_1):page229_i16:b" )
			)
			( pin "SH8U1.1"
				( objectStatus "@baseboard_fab2_lib.baseboard_fab2(sch_1):page229_i12:a" )
			)
			( pin "SH8U1.2"
				( objectStatus "@baseboard_fab2_lib.baseboard_fab2(sch_1):page229_i12:b" )
			)
			( pin "C6U13.1"
				( objectStatus "@baseboard_fab2_lib.baseboard_fab2(sch_1):page229_i11:a" )
			)
			( pin "C6U13.2"
				( objectStatus "@baseboard_fab2_lib.baseboard_fab2(sch_1):page229_i11:b" )
			)
			( pin "R4W1.1"
				( objectStatus "@baseboard_fab2_lib.baseboard_fab2(sch_1):page191_i195:a" )
			)
			( pin "R4W1.2"
				( objectStatus "@baseboard_fab2_lib.baseboard_fab2(sch_1):page191_i195:b" )
			)
			( pin "R6U7.1"
				( objectStatus "@baseboard_fab2_lib.baseboard_fab2(sch_1):page229_i9:a" )
			)
			( pin "R6U7.2"
				( objectStatus "@baseboard_fab2_lib.baseboard_fab2(sch_1):page229_i9:b" )
			)
			( pin "C4W2.1"
				( objectStatus "@baseboard_fab2_lib.baseboard_fab2(sch_1):page213_i101:a" )
			)
			( pin "C4W2.2"
				( objectStatus "@baseboard_fab2_lib.baseboard_fab2(sch_1):page213_i101:b" )
			)
			( pin "C1G17.1"
				( objectStatus "@baseboard_fab2_lib.baseboard_fab2(sch_1):page224_i6:a" )
			)
			( pin "C1G17.2"
				( objectStatus "@baseboard_fab2_lib.baseboard_fab2(sch_1):page224_i6:b" )
			)
			( pin "C1G11.1"
				( objectStatus "@baseboard_fab2_lib.baseboard_fab2(sch_1):page224_i44:a" )
			)
			( pin "C1G11.2"
				( objectStatus "@baseboard_fab2_lib.baseboard_fab2(sch_1):page224_i44:b" )
			)
			( pin "C9U6.1"
				( objectStatus "@baseboard_fab2_lib.baseboard_fab2(sch_1):page224_i45:a" )
			)
			( pin "C9U6.2"
				( objectStatus "@baseboard_fab2_lib.baseboard_fab2(sch_1):page224_i45:b" )
			)
			( pin "C9U4.1"
				( objectStatus "@baseboard_fab2_lib.baseboard_fab2(sch_1):page224_i46:a" )
			)
			( pin "C9U4.2"
				( objectStatus "@baseboard_fab2_lib.baseboard_fab2(sch_1):page224_i46:b" )
			)
			( pin "C9T4.1"
				( objectStatus "@baseboard_fab2_lib.baseboard_fab2(sch_1):page224_i47:a" )
			)
			( pin "C9T4.2"
				( objectStatus "@baseboard_fab2_lib.baseboard_fab2(sch_1):page224_i47:b" )
			)
			( pin "C1F27.1"
				( objectStatus "@baseboard_fab2_lib.baseboard_fab2(sch_1):page224_i48:a" )
			)
			( pin "C1F27.2"
				( objectStatus "@baseboard_fab2_lib.baseboard_fab2(sch_1):page224_i48:b" )
			)
			( pin "C1G6.1"
				( objectStatus "@baseboard_fab2_lib.baseboard_fab2(sch_1):page224_i50:a" )
			)
			( pin "C1G6.2"
				( objectStatus "@baseboard_fab2_lib.baseboard_fab2(sch_1):page224_i50:b" )
			)
			( pin "C1G14.1"
				( objectStatus "@baseboard_fab2_lib.baseboard_fab2(sch_1):page224_i51:a" )
			)
			( pin "C1G14.2"
				( objectStatus "@baseboard_fab2_lib.baseboard_fab2(sch_1):page224_i51:b" )
			)
			( pin "R3L4.1"
				( objectStatus "@baseboard_fab2_lib.baseboard_fab2(sch_1):page236_i177:a" )
			)
			( pin "R3L4.2"
				( objectStatus "@baseboard_fab2_lib.baseboard_fab2(sch_1):page236_i177:b" )
			)
			( pin "C3L29.1"
				( objectStatus "@baseboard_fab2_lib.baseboard_fab2(sch_1):page236_i181:\1\" )
			)
			( pin "C3L29.2"
				( objectStatus "@baseboard_fab2_lib.baseboard_fab2(sch_1):page236_i181:\2\" )
			)
			( pin "C1G5.1"
				( objectStatus "@baseboard_fab2_lib.baseboard_fab2(sch_1):page224_i54:a" )
			)
			( pin "C1G5.2"
				( objectStatus "@baseboard_fab2_lib.baseboard_fab2(sch_1):page224_i54:b" )
			)
			( pin "L1A2.2"
				( objectStatus "@baseboard_fab2_lib.baseboard_fab2(sch_1):page227_i152:f" )
			)
			( pin "L1A2.1"
				( objectStatus "@baseboard_fab2_lib.baseboard_fab2(sch_1):page227_i152:s" )
			)
			( pin "C1G20.1"
				( objectStatus "@baseboard_fab2_lib.baseboard_fab2(sch_1):page224_i68:a" )
			)
			( pin "C1G20.2"
				( objectStatus "@baseboard_fab2_lib.baseboard_fab2(sch_1):page224_i68:b" )
			)
			( pin "C1G29.1"
				( objectStatus "@baseboard_fab2_lib.baseboard_fab2(sch_1):page224_i72:a" )
			)
			( pin "C1G29.2"
				( objectStatus "@baseboard_fab2_lib.baseboard_fab2(sch_1):page224_i72:b" )
			)
			( pin "C3L1.1"
				( objectStatus "@baseboard_fab2_lib.baseboard_fab2(sch_1):page236_i180:\1\" )
			)
			( pin "C3L1.2"
				( objectStatus "@baseboard_fab2_lib.baseboard_fab2(sch_1):page236_i180:\2\" )
			)
			( pin "C1F26.1"
				( objectStatus "@baseboard_fab2_lib.baseboard_fab2(sch_1):page224_i75:a" )
			)
			( pin "C1F26.2"
				( objectStatus "@baseboard_fab2_lib.baseboard_fab2(sch_1):page224_i75:b" )
			)
			( pin "R3L1.1"
				( objectStatus "@baseboard_fab2_lib.baseboard_fab2(sch_1):page236_i175:a" )
			)
			( pin "R3L1.2"
				( objectStatus "@baseboard_fab2_lib.baseboard_fab2(sch_1):page236_i175:b" )
			)
			( pin "C1G28.1"
				( objectStatus "@baseboard_fab2_lib.baseboard_fab2(sch_1):page224_i77:a" )
			)
			( pin "C1G28.2"
				( objectStatus "@baseboard_fab2_lib.baseboard_fab2(sch_1):page224_i77:b" )
			)
			( pin "C1F28.1"
				( objectStatus "@baseboard_fab2_lib.baseboard_fab2(sch_1):page224_i78:a" )
			)
			( pin "C1F28.2"
				( objectStatus "@baseboard_fab2_lib.baseboard_fab2(sch_1):page224_i78:b" )
			)
			( pin "C1G13.1"
				( objectStatus "@baseboard_fab2_lib.baseboard_fab2(sch_1):page224_i79:a" )
			)
			( pin "C1G13.2"
				( objectStatus "@baseboard_fab2_lib.baseboard_fab2(sch_1):page224_i79:b" )
			)
			( pin "C9U3.1"
				( objectStatus "@baseboard_fab2_lib.baseboard_fab2(sch_1):page224_i80:a" )
			)
			( pin "C9U3.2"
				( objectStatus "@baseboard_fab2_lib.baseboard_fab2(sch_1):page224_i80:b" )
			)
			( pin "C9T6.1"
				( objectStatus "@baseboard_fab2_lib.baseboard_fab2(sch_1):page224_i81:a" )
			)
			( pin "C9T6.2"
				( objectStatus "@baseboard_fab2_lib.baseboard_fab2(sch_1):page224_i81:b" )
			)
			( pin "C9T9.1"
				( objectStatus "@baseboard_fab2_lib.baseboard_fab2(sch_1):page224_i84:a" )
			)
			( pin "C9T9.2"
				( objectStatus "@baseboard_fab2_lib.baseboard_fab2(sch_1):page224_i84:b" )
			)
			( pin "EU1G1.33"
				( objectStatus "@baseboard_fab2_lib.baseboard_fab2(sch_1):page224_i110:boost" )
			)
			( pin "EU1G1.35"
				( objectStatus "@baseboard_fab2_lib.baseboard_fab2(sch_1):page224_i110:en" )
			)
			( pin "EU1G1.6"
				( objectStatus "@baseboard_fab2_lib.baseboard_fab2(sch_1):page224_i110:gl(0)" )
			)
			( pin "EU1G1.41"
				( objectStatus "@baseboard_fab2_lib.baseboard_fab2(sch_1):page224_i110:gl(1)" )
			)
			( pin "EU1G1.38"
				( objectStatus "@baseboard_fab2_lib.baseboard_fab2(sch_1):page224_i110:iout" )
			)
			( pin "EU1G1.2"
				( objectStatus "@baseboard_fab2_lib.baseboard_fab2(sch_1):page224_i110:lgnd" )
			)
			( pin "EU1G1.31"
				( objectStatus "@baseboard_fab2_lib.baseboard_fab2(sch_1):page224_i110:nc" )
			)
			( pin "EU1G1.37"
				( objectStatus "@baseboard_fab2_lib.baseboard_fab2(sch_1):page224_i110:ocset" )
			)
			( pin "EU1G1.5"
				( objectStatus "@baseboard_fab2_lib.baseboard_fab2(sch_1):page224_i110:pgnd(0)" )
			)
			( pin "EU1G1.7"
				( objectStatus "@baseboard_fab2_lib.baseboard_fab2(sch_1):page224_i110:pgnd(1)" )
			)
			( pin "EU1G1.40"
				( objectStatus "@baseboard_fab2_lib.baseboard_fab2(sch_1):page224_i110:pgnd(2)" )
			)
			( pin "EU1G1.32"
				( objectStatus "@baseboard_fab2_lib.baseboard_fab2(sch_1):page224_i110:phase" )
			)
			( pin "EU1G1.34"
				( objectStatus "@baseboard_fab2_lib.baseboard_fab2(sch_1):page224_i110:pwm" )
			)
			( pin "EU1G1.39"
				( objectStatus "@baseboard_fab2_lib.baseboard_fab2(sch_1):page224_i110:refin" )
			)
			( pin "EU1G1.10"
				( objectStatus "@baseboard_fab2_lib.baseboard_fab2(sch_1):page224_i110:sw" )
			)
			( pin "EU1G1.36"
				( objectStatus "@baseboard_fab2_lib.baseboard_fab2(sch_1):page224_i110:tout_flt" )
			)
			( pin "EU1G1.3"
				( objectStatus "@baseboard_fab2_lib.baseboard_fab2(sch_1):page224_i110:vcc" )
			)
			( pin "EU1G1.4"
				( objectStatus "@baseboard_fab2_lib.baseboard_fab2(sch_1):page224_i110:vdrv" )
			)
			( pin "EU1G1.25"
				( objectStatus "@baseboard_fab2_lib.baseboard_fab2(sch_1):page224_i110:vin(0)" )
			)
			( pin "EU1G1.30"
				( objectStatus "@baseboard_fab2_lib.baseboard_fab2(sch_1):page224_i110:vin(1)" )
			)
			( pin "EU1G1.1"
				( objectStatus "@baseboard_fab2_lib.baseboard_fab2(sch_1):page224_i110:vos" )
			)
			( pin "EU1F1.33"
				( objectStatus "@baseboard_fab2_lib.baseboard_fab2(sch_1):page224_i111:boost" )
			)
			( pin "EU1F1.35"
				( objectStatus "@baseboard_fab2_lib.baseboard_fab2(sch_1):page224_i111:en" )
			)
			( pin "EU1F1.6"
				( objectStatus "@baseboard_fab2_lib.baseboard_fab2(sch_1):page224_i111:gl(0)" )
			)
			( pin "EU1F1.41"
				( objectStatus "@baseboard_fab2_lib.baseboard_fab2(sch_1):page224_i111:gl(1)" )
			)
			( pin "EU1F1.38"
				( objectStatus "@baseboard_fab2_lib.baseboard_fab2(sch_1):page224_i111:iout" )
			)
			( pin "EU1F1.2"
				( objectStatus "@baseboard_fab2_lib.baseboard_fab2(sch_1):page224_i111:lgnd" )
			)
			( pin "EU1F1.31"
				( objectStatus "@baseboard_fab2_lib.baseboard_fab2(sch_1):page224_i111:nc" )
			)
			( pin "EU1F1.37"
				( objectStatus "@baseboard_fab2_lib.baseboard_fab2(sch_1):page224_i111:ocset" )
			)
			( pin "EU1F1.5"
				( objectStatus "@baseboard_fab2_lib.baseboard_fab2(sch_1):page224_i111:pgnd(0)" )
			)
			( pin "EU1F1.7"
				( objectStatus "@baseboard_fab2_lib.baseboard_fab2(sch_1):page224_i111:pgnd(1)" )
			)
			( pin "EU1F1.40"
				( objectStatus "@baseboard_fab2_lib.baseboard_fab2(sch_1):page224_i111:pgnd(2)" )
			)
			( pin "EU1F1.32"
				( objectStatus "@baseboard_fab2_lib.baseboard_fab2(sch_1):page224_i111:phase" )
			)
			( pin "EU1F1.34"
				( objectStatus "@baseboard_fab2_lib.baseboard_fab2(sch_1):page224_i111:pwm" )
			)
			( pin "EU1F1.39"
				( objectStatus "@baseboard_fab2_lib.baseboard_fab2(sch_1):page224_i111:refin" )
			)
			( pin "EU1F1.10"
				( objectStatus "@baseboard_fab2_lib.baseboard_fab2(sch_1):page224_i111:sw" )
			)
			( pin "EU1F1.36"
				( objectStatus "@baseboard_fab2_lib.baseboard_fab2(sch_1):page224_i111:tout_flt" )
			)
			( pin "EU1F1.3"
				( objectStatus "@baseboard_fab2_lib.baseboard_fab2(sch_1):page224_i111:vcc" )
			)
			( pin "EU1F1.4"
				( objectStatus "@baseboard_fab2_lib.baseboard_fab2(sch_1):page224_i111:vdrv" )
			)
			( pin "EU1F1.25"
				( objectStatus "@baseboard_fab2_lib.baseboard_fab2(sch_1):page224_i111:vin(0)" )
			)
			( pin "EU1F1.30"
				( objectStatus "@baseboard_fab2_lib.baseboard_fab2(sch_1):page224_i111:vin(1)" )
			)
			( pin "EU1F1.1"
				( objectStatus "@baseboard_fab2_lib.baseboard_fab2(sch_1):page224_i111:vos" )
			)
			( pin "R1G26.1"
				( objectStatus "@baseboard_fab2_lib.baseboard_fab2(sch_1):page224_i112:a" )
			)
			( pin "R1G26.2"
				( objectStatus "@baseboard_fab2_lib.baseboard_fab2(sch_1):page224_i112:b" )
			)
			( pin "R1G25.1"
				( objectStatus "@baseboard_fab2_lib.baseboard_fab2(sch_1):page224_i114:a" )
			)
			( pin "R1G25.2"
				( objectStatus "@baseboard_fab2_lib.baseboard_fab2(sch_1):page224_i114:b" )
			)
			( pin "R1G20.1"
				( objectStatus "@baseboard_fab2_lib.baseboard_fab2(sch_1):page225_i58:a" )
			)
			( pin "R1G20.2"
				( objectStatus "@baseboard_fab2_lib.baseboard_fab2(sch_1):page225_i58:b" )
			)
			( pin "R7U2.1"
				( objectStatus "@baseboard_fab2_lib.baseboard_fab2(sch_1):page225_i74:a" )
			)
			( pin "R7U2.2"
				( objectStatus "@baseboard_fab2_lib.baseboard_fab2(sch_1):page225_i74:b" )
			)
			( pin "C9T5.1"
				( objectStatus "@baseboard_fab2_lib.baseboard_fab2(sch_1):page225_i75:a" )
			)
			( pin "C9T5.2"
				( objectStatus "@baseboard_fab2_lib.baseboard_fab2(sch_1):page225_i75:b" )
			)
			( pin "C9U2.1"
				( objectStatus "@baseboard_fab2_lib.baseboard_fab2(sch_1):page225_i76:a" )
			)
			( pin "C9U2.2"
				( objectStatus "@baseboard_fab2_lib.baseboard_fab2(sch_1):page225_i76:b" )
			)
			( pin "C9U9.1"
				( objectStatus "@baseboard_fab2_lib.baseboard_fab2(sch_1):page225_i77:a" )
			)
			( pin "C9U9.2"
				( objectStatus "@baseboard_fab2_lib.baseboard_fab2(sch_1):page225_i77:b" )
			)
			( pin "C9U5.1"
				( objectStatus "@baseboard_fab2_lib.baseboard_fab2(sch_1):page225_i78:a" )
			)
			( pin "C9U5.2"
				( objectStatus "@baseboard_fab2_lib.baseboard_fab2(sch_1):page225_i78:b" )
			)
			( pin "C8U8.1"
				( objectStatus "@baseboard_fab2_lib.baseboard_fab2(sch_1):page225_i320:a" )
			)
			( pin "C8U8.2"
				( objectStatus "@baseboard_fab2_lib.baseboard_fab2(sch_1):page225_i320:b" )
			)
			( pin "C8L1.1"
				( objectStatus "@baseboard_fab2_lib.baseboard_fab2(sch_1):page228_i301:a" )
			)
			( pin "C8L1.2"
				( objectStatus "@baseboard_fab2_lib.baseboard_fab2(sch_1):page228_i301:b" )
			)
			( pin "C2G16.1"
				( objectStatus "@baseboard_fab2_lib.baseboard_fab2(sch_1):page225_i311:a" )
			)
			( pin "C2G16.2"
				( objectStatus "@baseboard_fab2_lib.baseboard_fab2(sch_1):page225_i311:b" )
			)
			( pin "C7U7.1"
				( objectStatus "@baseboard_fab2_lib.baseboard_fab2(sch_1):page225_i308:a" )
			)
			( pin "C7U7.2"
				( objectStatus "@baseboard_fab2_lib.baseboard_fab2(sch_1):page225_i308:b" )
			)
			( pin "C8L11.1"
				( objectStatus "@baseboard_fab2_lib.baseboard_fab2(sch_1):page228_i302:a" )
			)
			( pin "C8L11.2"
				( objectStatus "@baseboard_fab2_lib.baseboard_fab2(sch_1):page228_i302:b" )
			)
			( pin "C8U12.1"
				( objectStatus "@baseboard_fab2_lib.baseboard_fab2(sch_1):page225_i310:a" )
			)
			( pin "C8U12.2"
				( objectStatus "@baseboard_fab2_lib.baseboard_fab2(sch_1):page225_i310:b" )
			)
			( pin "C8P30.1"
				( objectStatus "@baseboard_fab2_lib.baseboard_fab2(sch_1):page225_i313:a" )
			)
			( pin "C8P30.2"
				( objectStatus "@baseboard_fab2_lib.baseboard_fab2(sch_1):page225_i313:b" )
			)
			( pin "C2G7.1"
				( objectStatus "@baseboard_fab2_lib.baseboard_fab2(sch_1):page225_i312:a" )
			)
			( pin "C2G7.2"
				( objectStatus "@baseboard_fab2_lib.baseboard_fab2(sch_1):page225_i312:b" )
			)
			( pin "L1B1.2"
				( objectStatus "@baseboard_fab2_lib.baseboard_fab2(sch_1):page228_i247:f" )
			)
			( pin "L1B1.1"
				( objectStatus "@baseboard_fab2_lib.baseboard_fab2(sch_1):page228_i247:s" )
			)
			( pin "C7P2.1"
				( objectStatus "@baseboard_fab2_lib.baseboard_fab2(sch_1):page228_i305:a" )
			)
			( pin "C7P2.2"
				( objectStatus "@baseboard_fab2_lib.baseboard_fab2(sch_1):page228_i305:b" )
			)
			( pin "C2G11.1"
				( objectStatus "@baseboard_fab2_lib.baseboard_fab2(sch_1):page225_i275:a" )
			)
			( pin "C2G11.2"
				( objectStatus "@baseboard_fab2_lib.baseboard_fab2(sch_1):page225_i275:b" )
			)
			( pin "C2G10.1"
				( objectStatus "@baseboard_fab2_lib.baseboard_fab2(sch_1):page225_i274:a" )
			)
			( pin "C2G10.2"
				( objectStatus "@baseboard_fab2_lib.baseboard_fab2(sch_1):page225_i274:b" )
			)
			( pin "C8C12.1"
				( objectStatus "@baseboard_fab2_lib.baseboard_fab2(sch_1):page188_i121:a" )
			)
			( pin "C8C12.2"
				( objectStatus "@baseboard_fab2_lib.baseboard_fab2(sch_1):page188_i121:b" )
			)
			( pin "C8C13.1"
				( objectStatus "@baseboard_fab2_lib.baseboard_fab2(sch_1):page188_i120:a" )
			)
			( pin "C8C13.2"
				( objectStatus "@baseboard_fab2_lib.baseboard_fab2(sch_1):page188_i120:b" )
			)
			( pin "C8P3.1"
				( objectStatus "@baseboard_fab2_lib.baseboard_fab2(sch_1):page228_i306:a" )
			)
			( pin "C8P3.2"
				( objectStatus "@baseboard_fab2_lib.baseboard_fab2(sch_1):page228_i306:b" )
			)
			( pin "C1G2.1"
				( objectStatus "@baseboard_fab2_lib.baseboard_fab2(sch_1):page225_i250:\1\" )
			)
			( pin "C1G2.2"
				( objectStatus "@baseboard_fab2_lib.baseboard_fab2(sch_1):page225_i250:\2\" )
			)
			( pin "C22W3.1"
				( objectStatus "@baseboard_fab2_lib.baseboard_fab2(sch_1):page225_i249:\1\" )
			)
			( pin "C22W3.2"
				( objectStatus "@baseboard_fab2_lib.baseboard_fab2(sch_1):page225_i249:\2\" )
			)
			( pin "C4B1.1"
				( objectStatus "@baseboard_fab2_lib.baseboard_fab2(sch_1):page234_i223:\1\" )
			)
			( pin "C4B1.2"
				( objectStatus "@baseboard_fab2_lib.baseboard_fab2(sch_1):page234_i223:\2\" )
			)
			( pin "C22W5.1"
				( objectStatus "@baseboard_fab2_lib.baseboard_fab2(sch_1):page234_i222:\1\" )
			)
			( pin "C22W5.2"
				( objectStatus "@baseboard_fab2_lib.baseboard_fab2(sch_1):page234_i222:\2\" )
			)
			( pin "C8T4.1"
				( objectStatus "@baseboard_fab2_lib.baseboard_fab2(sch_1):page225_i196:a" )
			)
			( pin "C8T4.2"
				( objectStatus "@baseboard_fab2_lib.baseboard_fab2(sch_1):page225_i196:b" )
			)
			( pin "C2G8.1"
				( objectStatus "@baseboard_fab2_lib.baseboard_fab2(sch_1):page225_i197:a" )
			)
			( pin "C2G8.2"
				( objectStatus "@baseboard_fab2_lib.baseboard_fab2(sch_1):page225_i197:b" )
			)
			( pin "C8T2.1"
				( objectStatus "@baseboard_fab2_lib.baseboard_fab2(sch_1):page225_i198:a" )
			)
			( pin "C8T2.2"
				( objectStatus "@baseboard_fab2_lib.baseboard_fab2(sch_1):page225_i198:b" )
			)
			( pin "C8U13.1"
				( objectStatus "@baseboard_fab2_lib.baseboard_fab2(sch_1):page225_i199:a" )
			)
			( pin "C8U13.2"
				( objectStatus "@baseboard_fab2_lib.baseboard_fab2(sch_1):page225_i199:b" )
			)
			( pin "C2G15.1"
				( objectStatus "@baseboard_fab2_lib.baseboard_fab2(sch_1):page225_i200:a" )
			)
			( pin "C2G15.2"
				( objectStatus "@baseboard_fab2_lib.baseboard_fab2(sch_1):page225_i200:b" )
			)
			( pin "C2F1.1"
				( objectStatus "@baseboard_fab2_lib.baseboard_fab2(sch_1):page225_i201:a" )
			)
			( pin "C2F1.2"
				( objectStatus "@baseboard_fab2_lib.baseboard_fab2(sch_1):page225_i201:b" )
			)
			( pin "C8T1.1"
				( objectStatus "@baseboard_fab2_lib.baseboard_fab2(sch_1):page225_i202:a" )
			)
			( pin "C8T1.2"
				( objectStatus "@baseboard_fab2_lib.baseboard_fab2(sch_1):page225_i202:b" )
			)
			( pin "C8U9.1"
				( objectStatus "@baseboard_fab2_lib.baseboard_fab2(sch_1):page225_i203:a" )
			)
			( pin "C8U9.2"
				( objectStatus "@baseboard_fab2_lib.baseboard_fab2(sch_1):page225_i203:b" )
			)
			( pin "C8T11.1"
				( objectStatus "@baseboard_fab2_lib.baseboard_fab2(sch_1):page225_i204:a" )
			)
			( pin "C8T11.2"
				( objectStatus "@baseboard_fab2_lib.baseboard_fab2(sch_1):page225_i204:b" )
			)
			( pin "C2A2.1"
				( objectStatus "@baseboard_fab2_lib.baseboard_fab2(sch_1):page228_i283:a" )
			)
			( pin "C2A2.2"
				( objectStatus "@baseboard_fab2_lib.baseboard_fab2(sch_1):page228_i283:b" )
			)
			( pin "C2A1.1"
				( objectStatus "@baseboard_fab2_lib.baseboard_fab2(sch_1):page228_i282:a" )
			)
			( pin "C2A1.2"
				( objectStatus "@baseboard_fab2_lib.baseboard_fab2(sch_1):page228_i282:b" )
			)
			( pin "C2A12.1"
				( objectStatus "@baseboard_fab2_lib.baseboard_fab2(sch_1):page228_i281:a" )
			)
			( pin "C2A12.2"
				( objectStatus "@baseboard_fab2_lib.baseboard_fab2(sch_1):page228_i281:b" )
			)
			( pin "C2A13.1"
				( objectStatus "@baseboard_fab2_lib.baseboard_fab2(sch_1):page228_i280:a" )
			)
			( pin "C2A13.2"
				( objectStatus "@baseboard_fab2_lib.baseboard_fab2(sch_1):page228_i280:b" )
			)
			( pin "C2A11.1"
				( objectStatus "@baseboard_fab2_lib.baseboard_fab2(sch_1):page228_i279:a" )
			)
			( pin "C2A11.2"
				( objectStatus "@baseboard_fab2_lib.baseboard_fab2(sch_1):page228_i279:b" )
			)
			( pin "C2A10.1"
				( objectStatus "@baseboard_fab2_lib.baseboard_fab2(sch_1):page228_i278:a" )
			)
			( pin "C2A10.2"
				( objectStatus "@baseboard_fab2_lib.baseboard_fab2(sch_1):page228_i278:b" )
			)
			( pin "C2A9.1"
				( objectStatus "@baseboard_fab2_lib.baseboard_fab2(sch_1):page228_i277:a" )
			)
			( pin "C2A9.2"
				( objectStatus "@baseboard_fab2_lib.baseboard_fab2(sch_1):page228_i277:b" )
			)
			( pin "C3A2.1"
				( objectStatus "@baseboard_fab2_lib.baseboard_fab2(sch_1):page228_i276:a" )
			)
			( pin "C3A2.2"
				( objectStatus "@baseboard_fab2_lib.baseboard_fab2(sch_1):page228_i276:b" )
			)
			( pin "C3A1.1"
				( objectStatus "@baseboard_fab2_lib.baseboard_fab2(sch_1):page228_i275:a" )
			)
			( pin "C3A1.2"
				( objectStatus "@baseboard_fab2_lib.baseboard_fab2(sch_1):page228_i275:b" )
			)
			( pin "C2A7.1"
				( objectStatus "@baseboard_fab2_lib.baseboard_fab2(sch_1):page228_i274:a" )
			)
			( pin "C2A7.2"
				( objectStatus "@baseboard_fab2_lib.baseboard_fab2(sch_1):page228_i274:b" )
			)
			( pin "C2A6.1"
				( objectStatus "@baseboard_fab2_lib.baseboard_fab2(sch_1):page228_i273:a" )
			)
			( pin "C2A6.2"
				( objectStatus "@baseboard_fab2_lib.baseboard_fab2(sch_1):page228_i273:b" )
			)
			( pin "C2A14.1"
				( objectStatus "@baseboard_fab2_lib.baseboard_fab2(sch_1):page228_i272:a" )
			)
			( pin "C2A14.2"
				( objectStatus "@baseboard_fab2_lib.baseboard_fab2(sch_1):page228_i272:b" )
			)
			( pin "C2D6.1"
				( objectStatus "@baseboard_fab2_lib.baseboard_fab2(sch_1):page228_i267:a" )
			)
			( pin "C2D6.2"
				( objectStatus "@baseboard_fab2_lib.baseboard_fab2(sch_1):page228_i267:b" )
			)
			( pin "C2D5.1"
				( objectStatus "@baseboard_fab2_lib.baseboard_fab2(sch_1):page228_i266:a" )
			)
			( pin "C2D5.2"
				( objectStatus "@baseboard_fab2_lib.baseboard_fab2(sch_1):page228_i266:b" )
			)
			( pin "C2D4.1"
				( objectStatus "@baseboard_fab2_lib.baseboard_fab2(sch_1):page228_i265:a" )
			)
			( pin "C2D4.2"
				( objectStatus "@baseboard_fab2_lib.baseboard_fab2(sch_1):page228_i265:b" )
			)
			( pin "C2D7.1"
				( objectStatus "@baseboard_fab2_lib.baseboard_fab2(sch_1):page228_i264:a" )
			)
			( pin "C2D7.2"
				( objectStatus "@baseboard_fab2_lib.baseboard_fab2(sch_1):page228_i264:b" )
			)
			( pin "SH7U1.1"
				( objectStatus "@baseboard_fab2_lib.baseboard_fab2(sch_1):page225_i243:a" )
			)
			( pin "SH7U1.2"
				( objectStatus "@baseboard_fab2_lib.baseboard_fab2(sch_1):page225_i243:b" )
			)
			( pin "SH7U2.1"
				( objectStatus "@baseboard_fab2_lib.baseboard_fab2(sch_1):page225_i244:a" )
			)
			( pin "SH7U2.2"
				( objectStatus "@baseboard_fab2_lib.baseboard_fab2(sch_1):page225_i244:b" )
			)
			( pin "R12W18.1"
				( objectStatus "@baseboard_fab2_lib.baseboard_fab2(sch_1):page197_i114:\1\" )
			)
			( pin "R12W18.2"
				( objectStatus "@baseboard_fab2_lib.baseboard_fab2(sch_1):page197_i114:\2\" )
			)
			( pin "R1B16.1"
				( objectStatus "@baseboard_fab2_lib.baseboard_fab2(sch_1):page226_i13:a" )
			)
			( pin "R1B16.2"
				( objectStatus "@baseboard_fab2_lib.baseboard_fab2(sch_1):page226_i13:b" )
			)
			( pin "R9M9.1"
				( objectStatus "@baseboard_fab2_lib.baseboard_fab2(sch_1):page226_i14:a" )
			)
			( pin "R9M9.2"
				( objectStatus "@baseboard_fab2_lib.baseboard_fab2(sch_1):page226_i14:b" )
			)
			( pin "RF21.1"
				( objectStatus "@baseboard_fab2_lib.baseboard_fab2(sch_1):page226_i16:a" )
			)
			( pin "RF21.2"
				( objectStatus "@baseboard_fab2_lib.baseboard_fab2(sch_1):page226_i16:b" )
			)
			( pin "CF22.1"
				( objectStatus "@baseboard_fab2_lib.baseboard_fab2(sch_1):page226_i17:\1\" )
			)
			( pin "CF22.2"
				( objectStatus "@baseboard_fab2_lib.baseboard_fab2(sch_1):page226_i17:\2\" )
			)
			( pin "R12W9.1"
				( objectStatus "@baseboard_fab2_lib.baseboard_fab2(sch_1):page197_i21:a" )
			)
			( pin "R12W9.2"
				( objectStatus "@baseboard_fab2_lib.baseboard_fab2(sch_1):page197_i21:b" )
			)
			( pin "C1B11.1"
				( objectStatus "@baseboard_fab2_lib.baseboard_fab2(sch_1):page226_i23:a" )
			)
			( pin "C1B11.2"
				( objectStatus "@baseboard_fab2_lib.baseboard_fab2(sch_1):page226_i23:b" )
			)
			( pin "Q12W2.4"
				( objectStatus "@baseboard_fab2_lib.baseboard_fab2(sch_1):page197_i19:\drain#4\" )
			)
			( pin "Q12W2.6"
				( objectStatus "@baseboard_fab2_lib.baseboard_fab2(sch_1):page197_i19:\drain#6\" )
			)
			( pin "Q12W2.1"
				( objectStatus "@baseboard_fab2_lib.baseboard_fab2(sch_1):page197_i19:\gate#1\" )
			)
			( pin "Q12W2.3"
				( objectStatus "@baseboard_fab2_lib.baseboard_fab2(sch_1):page197_i19:\gate#3\" )
			)
			( pin "Q12W2.2"
				( objectStatus "@baseboard_fab2_lib.baseboard_fab2(sch_1):page197_i19:\source#2\" )
			)
			( pin "Q12W2.5"
				( objectStatus "@baseboard_fab2_lib.baseboard_fab2(sch_1):page197_i19:\source#5\" )
			)
			( pin "R2L9.1"
				( objectStatus "@baseboard_fab2_lib.baseboard_fab2(sch_1):page235_i254:a" )
			)
			( pin "R2L9.2"
				( objectStatus "@baseboard_fab2_lib.baseboard_fab2(sch_1):page235_i254:b" )
			)
			( pin "C1B5.1"
				( objectStatus "@baseboard_fab2_lib.baseboard_fab2(sch_1):page226_i32:a" )
			)
			( pin "C1B5.2"
				( objectStatus "@baseboard_fab2_lib.baseboard_fab2(sch_1):page226_i32:b" )
			)
			( pin "R9M3.1"
				( objectStatus "@baseboard_fab2_lib.baseboard_fab2(sch_1):page226_i36:a" )
			)
			( pin "R9M3.2"
				( objectStatus "@baseboard_fab2_lib.baseboard_fab2(sch_1):page226_i36:b" )
			)
			( pin "C12W4.1"
				( objectStatus "@baseboard_fab2_lib.baseboard_fab2(sch_1):page197_i18:a" )
			)
			( pin "C12W4.2"
				( objectStatus "@baseboard_fab2_lib.baseboard_fab2(sch_1):page197_i18:b" )
			)
			( pin "R1B10.1"
				( objectStatus "@baseboard_fab2_lib.baseboard_fab2(sch_1):page226_i41:a" )
			)
			( pin "R1B10.2"
				( objectStatus "@baseboard_fab2_lib.baseboard_fab2(sch_1):page226_i41:b" )
			)
			( pin "C1B2.1"
				( objectStatus "@baseboard_fab2_lib.baseboard_fab2(sch_1):page226_i44:a" )
			)
			( pin "C1B2.2"
				( objectStatus "@baseboard_fab2_lib.baseboard_fab2(sch_1):page226_i44:b" )
			)
			( pin "R1B2.1"
				( objectStatus "@baseboard_fab2_lib.baseboard_fab2(sch_1):page226_i50:a" )
			)
			( pin "R1B2.2"
				( objectStatus "@baseboard_fab2_lib.baseboard_fab2(sch_1):page226_i50:b" )
			)
			( pin "R12W36.1"
				( objectStatus "@baseboard_fab2_lib.baseboard_fab2(sch_1):page226_i53:a" )
			)
			( pin "R12W36.2"
				( objectStatus "@baseboard_fab2_lib.baseboard_fab2(sch_1):page226_i53:b" )
			)
			( pin "R4F2.1"
				( objectStatus "@baseboard_fab2_lib.baseboard_fab2(sch_1):page197_i14:a" )
			)
			( pin "R4F2.2"
				( objectStatus "@baseboard_fab2_lib.baseboard_fab2(sch_1):page197_i14:b" )
			)
			( pin "R12W3.1"
				( objectStatus "@baseboard_fab2_lib.baseboard_fab2(sch_1):page197_i115:\1\" )
			)
			( pin "R12W3.2"
				( objectStatus "@baseboard_fab2_lib.baseboard_fab2(sch_1):page197_i115:\2\" )
			)
			( pin "C12W1.1"
				( objectStatus "@baseboard_fab2_lib.baseboard_fab2(sch_1):page197_i8:a" )
			)
			( pin "C12W1.2"
				( objectStatus "@baseboard_fab2_lib.baseboard_fab2(sch_1):page197_i8:b" )
			)
			( pin "R4B12.1"
				( objectStatus "@baseboard_fab2_lib.baseboard_fab2(sch_1):page197_i6:a" )
			)
			( pin "R4B12.2"
				( objectStatus "@baseboard_fab2_lib.baseboard_fab2(sch_1):page197_i6:b" )
			)
			( pin "C4W1.1"
				( objectStatus "@baseboard_fab2_lib.baseboard_fab2(sch_1):page211_i97:a" )
			)
			( pin "C4W1.2"
				( objectStatus "@baseboard_fab2_lib.baseboard_fab2(sch_1):page211_i97:b" )
			)
			( pin "C1A12.1"
				( objectStatus "@baseboard_fab2_lib.baseboard_fab2(sch_1):page227_i6:a" )
			)
			( pin "C1A12.2"
				( objectStatus "@baseboard_fab2_lib.baseboard_fab2(sch_1):page227_i6:b" )
			)
			( pin "C1A18.1"
				( objectStatus "@baseboard_fab2_lib.baseboard_fab2(sch_1):page227_i44:a" )
			)
			( pin "C1A18.2"
				( objectStatus "@baseboard_fab2_lib.baseboard_fab2(sch_1):page227_i44:b" )
			)
			( pin "C9L11.1"
				( objectStatus "@baseboard_fab2_lib.baseboard_fab2(sch_1):page227_i45:a" )
			)
			( pin "C9L11.2"
				( objectStatus "@baseboard_fab2_lib.baseboard_fab2(sch_1):page227_i45:b" )
			)
			( pin "C9L10.1"
				( objectStatus "@baseboard_fab2_lib.baseboard_fab2(sch_1):page227_i46:a" )
			)
			( pin "C9L10.2"
				( objectStatus "@baseboard_fab2_lib.baseboard_fab2(sch_1):page227_i46:b" )
			)
			( pin "C9L6.1"
				( objectStatus "@baseboard_fab2_lib.baseboard_fab2(sch_1):page227_i47:a" )
			)
			( pin "C9L6.2"
				( objectStatus "@baseboard_fab2_lib.baseboard_fab2(sch_1):page227_i47:b" )
			)
			( pin "C1A19.1"
				( objectStatus "@baseboard_fab2_lib.baseboard_fab2(sch_1):page227_i48:a" )
			)
			( pin "C1A19.2"
				( objectStatus "@baseboard_fab2_lib.baseboard_fab2(sch_1):page227_i48:b" )
			)
			( pin "C1B20.1"
				( objectStatus "@baseboard_fab2_lib.baseboard_fab2(sch_1):page227_i50:a" )
			)
			( pin "C1B20.2"
				( objectStatus "@baseboard_fab2_lib.baseboard_fab2(sch_1):page227_i50:b" )
			)
			( pin "C1A10.1"
				( objectStatus "@baseboard_fab2_lib.baseboard_fab2(sch_1):page227_i51:a" )
			)
			( pin "C1A10.2"
				( objectStatus "@baseboard_fab2_lib.baseboard_fab2(sch_1):page227_i51:b" )
			)
			( pin "C1D5.1"
				( objectStatus "@baseboard_fab2_lib.baseboard_fab2(sch_1):page208_i119:\1\" )
			)
			( pin "C1D5.2"
				( objectStatus "@baseboard_fab2_lib.baseboard_fab2(sch_1):page208_i119:\2\" )
			)
			( pin "C1B21.1"
				( objectStatus "@baseboard_fab2_lib.baseboard_fab2(sch_1):page227_i54:a" )
			)
			( pin "C1B21.2"
				( objectStatus "@baseboard_fab2_lib.baseboard_fab2(sch_1):page227_i54:b" )
			)
			( pin "L7C1.2"
				( objectStatus "@baseboard_fab2_lib.baseboard_fab2(sch_1):page212_i142:f" )
			)
			( pin "L7C1.1"
				( objectStatus "@baseboard_fab2_lib.baseboard_fab2(sch_1):page212_i142:s" )
			)
			( pin "L7C2.2"
				( objectStatus "@baseboard_fab2_lib.baseboard_fab2(sch_1):page212_i141:f" )
			)
			( pin "L7C2.1"
				( objectStatus "@baseboard_fab2_lib.baseboard_fab2(sch_1):page212_i141:s" )
			)
			( pin "C1A1.1"
				( objectStatus "@baseboard_fab2_lib.baseboard_fab2(sch_1):page227_i68:a" )
			)
			( pin "C1A1.2"
				( objectStatus "@baseboard_fab2_lib.baseboard_fab2(sch_1):page227_i68:b" )
			)
			( pin "C1A13.1"
				( objectStatus "@baseboard_fab2_lib.baseboard_fab2(sch_1):page227_i72:a" )
			)
			( pin "C1A13.2"
				( objectStatus "@baseboard_fab2_lib.baseboard_fab2(sch_1):page227_i72:b" )
			)
			( pin "C1C3.1"
				( objectStatus "@baseboard_fab2_lib.baseboard_fab2(sch_1):page210_i73:\1\" )
			)
			( pin "C1C3.2"
				( objectStatus "@baseboard_fab2_lib.baseboard_fab2(sch_1):page210_i73:\2\" )
			)
			( pin "C1A8.1"
				( objectStatus "@baseboard_fab2_lib.baseboard_fab2(sch_1):page227_i75:a" )
			)
			( pin "C1A8.2"
				( objectStatus "@baseboard_fab2_lib.baseboard_fab2(sch_1):page227_i75:b" )
			)
			( pin "C1A6.1"
				( objectStatus "@baseboard_fab2_lib.baseboard_fab2(sch_1):page227_i77:a" )
			)
			( pin "C1A6.2"
				( objectStatus "@baseboard_fab2_lib.baseboard_fab2(sch_1):page227_i77:b" )
			)
			( pin "C1A20.1"
				( objectStatus "@baseboard_fab2_lib.baseboard_fab2(sch_1):page227_i78:a" )
			)
			( pin "C1A20.2"
				( objectStatus "@baseboard_fab2_lib.baseboard_fab2(sch_1):page227_i78:b" )
			)
			( pin "C1A9.1"
				( objectStatus "@baseboard_fab2_lib.baseboard_fab2(sch_1):page227_i79:a" )
			)
			( pin "C1A9.2"
				( objectStatus "@baseboard_fab2_lib.baseboard_fab2(sch_1):page227_i79:b" )
			)
			( pin "C9L5.1"
				( objectStatus "@baseboard_fab2_lib.baseboard_fab2(sch_1):page227_i80:a" )
			)
			( pin "C9L5.2"
				( objectStatus "@baseboard_fab2_lib.baseboard_fab2(sch_1):page227_i80:b" )
			)
			( pin "C9L13.1"
				( objectStatus "@baseboard_fab2_lib.baseboard_fab2(sch_1):page227_i81:a" )
			)
			( pin "C9L13.2"
				( objectStatus "@baseboard_fab2_lib.baseboard_fab2(sch_1):page227_i81:b" )
			)
			( pin "C9L14.1"
				( objectStatus "@baseboard_fab2_lib.baseboard_fab2(sch_1):page227_i84:a" )
			)
			( pin "C9L14.2"
				( objectStatus "@baseboard_fab2_lib.baseboard_fab2(sch_1):page227_i84:b" )
			)
			( pin "EU1A2.33"
				( objectStatus "@baseboard_fab2_lib.baseboard_fab2(sch_1):page227_i101:boost" )
			)
			( pin "EU1A2.35"
				( objectStatus "@baseboard_fab2_lib.baseboard_fab2(sch_1):page227_i101:en" )
			)
			( pin "EU1A2.6"
				( objectStatus "@baseboard_fab2_lib.baseboard_fab2(sch_1):page227_i101:gl(0)" )
			)
			( pin "EU1A2.41"
				( objectStatus "@baseboard_fab2_lib.baseboard_fab2(sch_1):page227_i101:gl(1)" )
			)
			( pin "EU1A2.38"
				( objectStatus "@baseboard_fab2_lib.baseboard_fab2(sch_1):page227_i101:iout" )
			)
			( pin "EU1A2.2"
				( objectStatus "@baseboard_fab2_lib.baseboard_fab2(sch_1):page227_i101:lgnd" )
			)
			( pin "EU1A2.31"
				( objectStatus "@baseboard_fab2_lib.baseboard_fab2(sch_1):page227_i101:nc" )
			)
			( pin "EU1A2.37"
				( objectStatus "@baseboard_fab2_lib.baseboard_fab2(sch_1):page227_i101:ocset" )
			)
			( pin "EU1A2.5"
				( objectStatus "@baseboard_fab2_lib.baseboard_fab2(sch_1):page227_i101:pgnd(0)" )
			)
			( pin "EU1A2.7"
				( objectStatus "@baseboard_fab2_lib.baseboard_fab2(sch_1):page227_i101:pgnd(1)" )
			)
			( pin "EU1A2.40"
				( objectStatus "@baseboard_fab2_lib.baseboard_fab2(sch_1):page227_i101:pgnd(2)" )
			)
			( pin "EU1A2.32"
				( objectStatus "@baseboard_fab2_lib.baseboard_fab2(sch_1):page227_i101:phase" )
			)
			( pin "EU1A2.34"
				( objectStatus "@baseboard_fab2_lib.baseboard_fab2(sch_1):page227_i101:pwm" )
			)
			( pin "EU1A2.39"
				( objectStatus "@baseboard_fab2_lib.baseboard_fab2(sch_1):page227_i101:refin" )
			)
			( pin "EU1A2.10"
				( objectStatus "@baseboard_fab2_lib.baseboard_fab2(sch_1):page227_i101:sw" )
			)
			( pin "EU1A2.36"
				( objectStatus "@baseboard_fab2_lib.baseboard_fab2(sch_1):page227_i101:tout_flt" )
			)
			( pin "EU1A2.3"
				( objectStatus "@baseboard_fab2_lib.baseboard_fab2(sch_1):page227_i101:vcc" )
			)
			( pin "EU1A2.4"
				( objectStatus "@baseboard_fab2_lib.baseboard_fab2(sch_1):page227_i101:vdrv" )
			)
			( pin "EU1A2.25"
				( objectStatus "@baseboard_fab2_lib.baseboard_fab2(sch_1):page227_i101:vin(0)" )
			)
			( pin "EU1A2.30"
				( objectStatus "@baseboard_fab2_lib.baseboard_fab2(sch_1):page227_i101:vin(1)" )
			)
			( pin "EU1A2.1"
				( objectStatus "@baseboard_fab2_lib.baseboard_fab2(sch_1):page227_i101:vos" )
			)
			( pin "EU1A1.33"
				( objectStatus "@baseboard_fab2_lib.baseboard_fab2(sch_1):page227_i102:boost" )
			)
			( pin "EU1A1.35"
				( objectStatus "@baseboard_fab2_lib.baseboard_fab2(sch_1):page227_i102:en" )
			)
			( pin "EU1A1.6"
				( objectStatus "@baseboard_fab2_lib.baseboard_fab2(sch_1):page227_i102:gl(0)" )
			)
			( pin "EU1A1.41"
				( objectStatus "@baseboard_fab2_lib.baseboard_fab2(sch_1):page227_i102:gl(1)" )
			)
			( pin "EU1A1.38"
				( objectStatus "@baseboard_fab2_lib.baseboard_fab2(sch_1):page227_i102:iout" )
			)
			( pin "EU1A1.2"
				( objectStatus "@baseboard_fab2_lib.baseboard_fab2(sch_1):page227_i102:lgnd" )
			)
			( pin "EU1A1.31"
				( objectStatus "@baseboard_fab2_lib.baseboard_fab2(sch_1):page227_i102:nc" )
			)
			( pin "EU1A1.37"
				( objectStatus "@baseboard_fab2_lib.baseboard_fab2(sch_1):page227_i102:ocset" )
			)
			( pin "EU1A1.5"
				( objectStatus "@baseboard_fab2_lib.baseboard_fab2(sch_1):page227_i102:pgnd(0)" )
			)
			( pin "EU1A1.7"
				( objectStatus "@baseboard_fab2_lib.baseboard_fab2(sch_1):page227_i102:pgnd(1)" )
			)
			( pin "EU1A1.40"
				( objectStatus "@baseboard_fab2_lib.baseboard_fab2(sch_1):page227_i102:pgnd(2)" )
			)
			( pin "EU1A1.32"
				( objectStatus "@baseboard_fab2_lib.baseboard_fab2(sch_1):page227_i102:phase" )
			)
			( pin "EU1A1.34"
				( objectStatus "@baseboard_fab2_lib.baseboard_fab2(sch_1):page227_i102:pwm" )
			)
			( pin "EU1A1.39"
				( objectStatus "@baseboard_fab2_lib.baseboard_fab2(sch_1):page227_i102:refin" )
			)
			( pin "EU1A1.10"
				( objectStatus "@baseboard_fab2_lib.baseboard_fab2(sch_1):page227_i102:sw" )
			)
			( pin "EU1A1.36"
				( objectStatus "@baseboard_fab2_lib.baseboard_fab2(sch_1):page227_i102:tout_flt" )
			)
			( pin "EU1A1.3"
				( objectStatus "@baseboard_fab2_lib.baseboard_fab2(sch_1):page227_i102:vcc" )
			)
			( pin "EU1A1.4"
				( objectStatus "@baseboard_fab2_lib.baseboard_fab2(sch_1):page227_i102:vdrv" )
			)
			( pin "EU1A1.25"
				( objectStatus "@baseboard_fab2_lib.baseboard_fab2(sch_1):page227_i102:vin(0)" )
			)
			( pin "EU1A1.30"
				( objectStatus "@baseboard_fab2_lib.baseboard_fab2(sch_1):page227_i102:vin(1)" )
			)
			( pin "EU1A1.1"
				( objectStatus "@baseboard_fab2_lib.baseboard_fab2(sch_1):page227_i102:vos" )
			)
			( pin "R1A3.1"
				( objectStatus "@baseboard_fab2_lib.baseboard_fab2(sch_1):page227_i103:a" )
			)
			( pin "R1A3.2"
				( objectStatus "@baseboard_fab2_lib.baseboard_fab2(sch_1):page227_i103:b" )
			)
			( pin "R1A2.1"
				( objectStatus "@baseboard_fab2_lib.baseboard_fab2(sch_1):page227_i105:a" )
			)
			( pin "R1A2.2"
				( objectStatus "@baseboard_fab2_lib.baseboard_fab2(sch_1):page227_i105:b" )
			)
			( pin "R1A1.1"
				( objectStatus "@baseboard_fab2_lib.baseboard_fab2(sch_1):page228_i58:a" )
			)
			( pin "R1A1.2"
				( objectStatus "@baseboard_fab2_lib.baseboard_fab2(sch_1):page228_i58:b" )
			)
			( pin "R7L2.1"
				( objectStatus "@baseboard_fab2_lib.baseboard_fab2(sch_1):page228_i74:a" )
			)
			( pin "R7L2.2"
				( objectStatus "@baseboard_fab2_lib.baseboard_fab2(sch_1):page228_i74:b" )
			)
			( pin "C9L9.1"
				( objectStatus "@baseboard_fab2_lib.baseboard_fab2(sch_1):page228_i75:a" )
			)
			( pin "C9L9.2"
				( objectStatus "@baseboard_fab2_lib.baseboard_fab2(sch_1):page228_i75:b" )
			)
			( pin "C9L12.1"
				( objectStatus "@baseboard_fab2_lib.baseboard_fab2(sch_1):page228_i76:a" )
			)
			( pin "C9L12.2"
				( objectStatus "@baseboard_fab2_lib.baseboard_fab2(sch_1):page228_i76:b" )
			)
			( pin "C9L4.1"
				( objectStatus "@baseboard_fab2_lib.baseboard_fab2(sch_1):page228_i77:a" )
			)
			( pin "C9L4.2"
				( objectStatus "@baseboard_fab2_lib.baseboard_fab2(sch_1):page228_i77:b" )
			)
			( pin "C9L2.1"
				( objectStatus "@baseboard_fab2_lib.baseboard_fab2(sch_1):page228_i78:a" )
			)
			( pin "C9L2.2"
				( objectStatus "@baseboard_fab2_lib.baseboard_fab2(sch_1):page228_i78:b" )
			)
			( pin "C8L2.1"
				( objectStatus "@baseboard_fab2_lib.baseboard_fab2(sch_1):page228_i310:a" )
			)
			( pin "C8L2.2"
				( objectStatus "@baseboard_fab2_lib.baseboard_fab2(sch_1):page228_i310:b" )
			)
			( pin "C8M11.1"
				( objectStatus "@baseboard_fab2_lib.baseboard_fab2(sch_1):page228_i311:a" )
			)
			( pin "C8M11.2"
				( objectStatus "@baseboard_fab2_lib.baseboard_fab2(sch_1):page228_i311:b" )
			)
			( pin "C8U10.1"
				( objectStatus "@baseboard_fab2_lib.baseboard_fab2(sch_1):page229_i42:a" )
			)
			( pin "C8U10.2"
				( objectStatus "@baseboard_fab2_lib.baseboard_fab2(sch_1):page229_i42:b" )
			)
			( pin "C7L1.1"
				( objectStatus "@baseboard_fab2_lib.baseboard_fab2(sch_1):page228_i314:a" )
			)
			( pin "C7L1.2"
				( objectStatus "@baseboard_fab2_lib.baseboard_fab2(sch_1):page228_i314:b" )
			)
			( pin "C8T3.1"
				( objectStatus "@baseboard_fab2_lib.baseboard_fab2(sch_1):page229_i41:a" )
			)
			( pin "C8T3.2"
				( objectStatus "@baseboard_fab2_lib.baseboard_fab2(sch_1):page229_i41:b" )
			)
			( pin "C8P4.1"
				( objectStatus "@baseboard_fab2_lib.baseboard_fab2(sch_1):page228_i307:a" )
			)
			( pin "C8P4.2"
				( objectStatus "@baseboard_fab2_lib.baseboard_fab2(sch_1):page228_i307:b" )
			)
			( pin "C1B10.1"
				( objectStatus "@baseboard_fab2_lib.baseboard_fab2(sch_1):page228_i175:a" )
			)
			( pin "C1B10.2"
				( objectStatus "@baseboard_fab2_lib.baseboard_fab2(sch_1):page228_i175:b" )
			)
			( pin "C8M7.1"
				( objectStatus "@baseboard_fab2_lib.baseboard_fab2(sch_1):page228_i312:a" )
			)
			( pin "C8M7.2"
				( objectStatus "@baseboard_fab2_lib.baseboard_fab2(sch_1):page228_i312:b" )
			)
			( pin "C7P1.1"
				( objectStatus "@baseboard_fab2_lib.baseboard_fab2(sch_1):page228_i308:a" )
			)
			( pin "C7P1.2"
				( objectStatus "@baseboard_fab2_lib.baseboard_fab2(sch_1):page228_i308:b" )
			)
			( pin "C2A15.1"
				( objectStatus "@baseboard_fab2_lib.baseboard_fab2(sch_1):page228_i271:a" )
			)
			( pin "C2A15.2"
				( objectStatus "@baseboard_fab2_lib.baseboard_fab2(sch_1):page228_i271:b" )
			)
			( pin "C3A5.1"
				( objectStatus "@baseboard_fab2_lib.baseboard_fab2(sch_1):page228_i270:a" )
			)
			( pin "C3A5.2"
				( objectStatus "@baseboard_fab2_lib.baseboard_fab2(sch_1):page228_i270:b" )
			)
			( pin "C3A6.1"
				( objectStatus "@baseboard_fab2_lib.baseboard_fab2(sch_1):page228_i269:a" )
			)
			( pin "C3A6.2"
				( objectStatus "@baseboard_fab2_lib.baseboard_fab2(sch_1):page228_i269:b" )
			)
			( pin "C7L5.1"
				( objectStatus "@baseboard_fab2_lib.baseboard_fab2(sch_1):page228_i268:a" )
			)
			( pin "C7L5.2"
				( objectStatus "@baseboard_fab2_lib.baseboard_fab2(sch_1):page228_i268:b" )
			)
			( pin "C8M8.1"
				( objectStatus "@baseboard_fab2_lib.baseboard_fab2(sch_1):page228_i198:a" )
			)
			( pin "C8M8.2"
				( objectStatus "@baseboard_fab2_lib.baseboard_fab2(sch_1):page228_i198:b" )
			)
			( pin "C2A5.1"
				( objectStatus "@baseboard_fab2_lib.baseboard_fab2(sch_1):page228_i199:a" )
			)
			( pin "C2A5.2"
				( objectStatus "@baseboard_fab2_lib.baseboard_fab2(sch_1):page228_i199:b" )
			)
			( pin "C2B1.1"
				( objectStatus "@baseboard_fab2_lib.baseboard_fab2(sch_1):page228_i200:a" )
			)
			( pin "C2B1.2"
				( objectStatus "@baseboard_fab2_lib.baseboard_fab2(sch_1):page228_i200:b" )
			)
			( pin "C8L12.1"
				( objectStatus "@baseboard_fab2_lib.baseboard_fab2(sch_1):page228_i201:a" )
			)
			( pin "C8L12.2"
				( objectStatus "@baseboard_fab2_lib.baseboard_fab2(sch_1):page228_i201:b" )
			)
			( pin "C7M5.1"
				( objectStatus "@baseboard_fab2_lib.baseboard_fab2(sch_1):page228_i202:a" )
			)
			( pin "C7M5.2"
				( objectStatus "@baseboard_fab2_lib.baseboard_fab2(sch_1):page228_i202:b" )
			)
			( pin "C8M10.1"
				( objectStatus "@baseboard_fab2_lib.baseboard_fab2(sch_1):page228_i203:a" )
			)
			( pin "C8M10.2"
				( objectStatus "@baseboard_fab2_lib.baseboard_fab2(sch_1):page228_i203:b" )
			)
			( pin "C2B2.1"
				( objectStatus "@baseboard_fab2_lib.baseboard_fab2(sch_1):page228_i204:a" )
			)
			( pin "C2B2.2"
				( objectStatus "@baseboard_fab2_lib.baseboard_fab2(sch_1):page228_i204:b" )
			)
			( pin "C8M9.1"
				( objectStatus "@baseboard_fab2_lib.baseboard_fab2(sch_1):page228_i205:a" )
			)
			( pin "C8M9.2"
				( objectStatus "@baseboard_fab2_lib.baseboard_fab2(sch_1):page228_i205:b" )
			)
			( pin "C8M2.1"
				( objectStatus "@baseboard_fab2_lib.baseboard_fab2(sch_1):page228_i206:a" )
			)
			( pin "C8M2.2"
				( objectStatus "@baseboard_fab2_lib.baseboard_fab2(sch_1):page228_i206:b" )
			)
			( pin "C8M3.1"
				( objectStatus "@baseboard_fab2_lib.baseboard_fab2(sch_1):page228_i299:a" )
			)
			( pin "C8M3.2"
				( objectStatus "@baseboard_fab2_lib.baseboard_fab2(sch_1):page228_i299:b" )
			)
			( pin "C8M5.1"
				( objectStatus "@baseboard_fab2_lib.baseboard_fab2(sch_1):page228_i298:a" )
			)
			( pin "C8M5.2"
				( objectStatus "@baseboard_fab2_lib.baseboard_fab2(sch_1):page228_i298:b" )
			)
			( pin "C8L10.1"
				( objectStatus "@baseboard_fab2_lib.baseboard_fab2(sch_1):page228_i297:a" )
			)
			( pin "C8L10.2"
				( objectStatus "@baseboard_fab2_lib.baseboard_fab2(sch_1):page228_i297:b" )
			)
			( pin "C2A3.1"
				( objectStatus "@baseboard_fab2_lib.baseboard_fab2(sch_1):page228_i296:a" )
			)
			( pin "C2A3.2"
				( objectStatus "@baseboard_fab2_lib.baseboard_fab2(sch_1):page228_i296:b" )
			)
			( pin "C7M1.1"
				( objectStatus "@baseboard_fab2_lib.baseboard_fab2(sch_1):page228_i295:a" )
			)
			( pin "C7M1.2"
				( objectStatus "@baseboard_fab2_lib.baseboard_fab2(sch_1):page228_i295:b" )
			)
			( pin "C7M2.1"
				( objectStatus "@baseboard_fab2_lib.baseboard_fab2(sch_1):page228_i294:a" )
			)
			( pin "C7M2.2"
				( objectStatus "@baseboard_fab2_lib.baseboard_fab2(sch_1):page228_i294:b" )
			)
			( pin "C8M4.1"
				( objectStatus "@baseboard_fab2_lib.baseboard_fab2(sch_1):page228_i293:a" )
			)
			( pin "C8M4.2"
				( objectStatus "@baseboard_fab2_lib.baseboard_fab2(sch_1):page228_i293:b" )
			)
			( pin "C2A4.1"
				( objectStatus "@baseboard_fab2_lib.baseboard_fab2(sch_1):page228_i292:a" )
			)
			( pin "C2A4.2"
				( objectStatus "@baseboard_fab2_lib.baseboard_fab2(sch_1):page228_i292:b" )
			)
			( pin "C8M6.1"
				( objectStatus "@baseboard_fab2_lib.baseboard_fab2(sch_1):page228_i291:a" )
			)
			( pin "C8M6.2"
				( objectStatus "@baseboard_fab2_lib.baseboard_fab2(sch_1):page228_i291:b" )
			)
			( pin "C8L9.1"
				( objectStatus "@baseboard_fab2_lib.baseboard_fab2(sch_1):page228_i290:a" )
			)
			( pin "C8L9.2"
				( objectStatus "@baseboard_fab2_lib.baseboard_fab2(sch_1):page228_i290:b" )
			)
			( pin "C8L8.1"
				( objectStatus "@baseboard_fab2_lib.baseboard_fab2(sch_1):page228_i289:a" )
			)
			( pin "C8L8.2"
				( objectStatus "@baseboard_fab2_lib.baseboard_fab2(sch_1):page228_i289:b" )
			)
			( pin "C7L4.1"
				( objectStatus "@baseboard_fab2_lib.baseboard_fab2(sch_1):page228_i288:a" )
			)
			( pin "C7L4.2"
				( objectStatus "@baseboard_fab2_lib.baseboard_fab2(sch_1):page228_i288:b" )
			)
			( pin "C8L7.1"
				( objectStatus "@baseboard_fab2_lib.baseboard_fab2(sch_1):page228_i287:a" )
			)
			( pin "C8L7.2"
				( objectStatus "@baseboard_fab2_lib.baseboard_fab2(sch_1):page228_i287:b" )
			)
			( pin "C8L6.1"
				( objectStatus "@baseboard_fab2_lib.baseboard_fab2(sch_1):page228_i286:a" )
			)
			( pin "C8L6.2"
				( objectStatus "@baseboard_fab2_lib.baseboard_fab2(sch_1):page228_i286:b" )
			)
			( pin "C8L5.1"
				( objectStatus "@baseboard_fab2_lib.baseboard_fab2(sch_1):page228_i285:a" )
			)
			( pin "C8L5.2"
				( objectStatus "@baseboard_fab2_lib.baseboard_fab2(sch_1):page228_i285:b" )
			)
			( pin "C8M1.1"
				( objectStatus "@baseboard_fab2_lib.baseboard_fab2(sch_1):page228_i284:a" )
			)
			( pin "C8M1.2"
				( objectStatus "@baseboard_fab2_lib.baseboard_fab2(sch_1):page228_i284:b" )
			)
			( pin "SH7L2.1"
				( objectStatus "@baseboard_fab2_lib.baseboard_fab2(sch_1):page228_i245:a" )
			)
			( pin "SH7L2.2"
				( objectStatus "@baseboard_fab2_lib.baseboard_fab2(sch_1):page228_i245:b" )
			)
			( pin "SH7L1.1"
				( objectStatus "@baseboard_fab2_lib.baseboard_fab2(sch_1):page228_i246:a" )
			)
			( pin "SH7L1.2"
				( objectStatus "@baseboard_fab2_lib.baseboard_fab2(sch_1):page228_i246:b" )
			)
			( pin "C6U11.1"
				( objectStatus "@baseboard_fab2_lib.baseboard_fab2(sch_1):page229_i14:a" )
			)
			( pin "C6U11.2"
				( objectStatus "@baseboard_fab2_lib.baseboard_fab2(sch_1):page229_i14:b" )
			)
			( pin "R1B1.1"
				( objectStatus "@baseboard_fab2_lib.baseboard_fab2(sch_1):page226_i49:a" )
			)
			( pin "R1B1.2"
				( objectStatus "@baseboard_fab2_lib.baseboard_fab2(sch_1):page226_i49:b" )
			)
			( pin "R1B11.1"
				( objectStatus "@baseboard_fab2_lib.baseboard_fab2(sch_1):page226_i48:a" )
			)
			( pin "R1B11.2"
				( objectStatus "@baseboard_fab2_lib.baseboard_fab2(sch_1):page226_i48:b" )
			)
			( pin "C4G21.1"
				( objectStatus "@baseboard_fab2_lib.baseboard_fab2(sch_1):page229_i21:a" )
			)
			( pin "C4G21.2"
				( objectStatus "@baseboard_fab2_lib.baseboard_fab2(sch_1):page229_i21:b" )
			)
			( pin "R4G17.1"
				( objectStatus "@baseboard_fab2_lib.baseboard_fab2(sch_1):page229_i24:a" )
			)
			( pin "R4G17.2"
				( objectStatus "@baseboard_fab2_lib.baseboard_fab2(sch_1):page229_i24:b" )
			)
			( pin "R12W35.1"
				( objectStatus "@baseboard_fab2_lib.baseboard_fab2(sch_1):page226_i46:a" )
			)
			( pin "R12W35.2"
				( objectStatus "@baseboard_fab2_lib.baseboard_fab2(sch_1):page226_i46:b" )
			)
			( pin "C1B3.1"
				( objectStatus "@baseboard_fab2_lib.baseboard_fab2(sch_1):page226_i45:a" )
			)
			( pin "C1B3.2"
				( objectStatus "@baseboard_fab2_lib.baseboard_fab2(sch_1):page226_i45:b" )
			)
			( pin "R4G15.1"
				( objectStatus "@baseboard_fab2_lib.baseboard_fab2(sch_1):page229_i32:a" )
			)
			( pin "R4G15.2"
				( objectStatus "@baseboard_fab2_lib.baseboard_fab2(sch_1):page229_i32:b" )
			)
			( pin "C1B4.1"
				( objectStatus "@baseboard_fab2_lib.baseboard_fab2(sch_1):page226_i40:a" )
			)
			( pin "C1B4.2"
				( objectStatus "@baseboard_fab2_lib.baseboard_fab2(sch_1):page226_i40:b" )
			)
			( pin "C1B6.1"
				( objectStatus "@baseboard_fab2_lib.baseboard_fab2(sch_1):page226_i38:a" )
			)
			( pin "C1B6.2"
				( objectStatus "@baseboard_fab2_lib.baseboard_fab2(sch_1):page226_i38:b" )
			)
			( pin "R9M5.1"
				( objectStatus "@baseboard_fab2_lib.baseboard_fab2(sch_1):page226_i34:a" )
			)
			( pin "R9M5.2"
				( objectStatus "@baseboard_fab2_lib.baseboard_fab2(sch_1):page226_i34:b" )
			)
			( pin "R9U4.1"
				( objectStatus "@baseboard_fab2_lib.baseboard_fab2(sch_1):page223_i70:a" )
			)
			( pin "R9U4.2"
				( objectStatus "@baseboard_fab2_lib.baseboard_fab2(sch_1):page223_i70:b" )
			)
			( pin "R1B8.1"
				( objectStatus "@baseboard_fab2_lib.baseboard_fab2(sch_1):page226_i19:a" )
			)
			( pin "R1B8.2"
				( objectStatus "@baseboard_fab2_lib.baseboard_fab2(sch_1):page226_i19:b" )
			)
			( pin "RF22.1"
				( objectStatus "@baseboard_fab2_lib.baseboard_fab2(sch_1):page226_i18:a" )
			)
			( pin "RF22.2"
				( objectStatus "@baseboard_fab2_lib.baseboard_fab2(sch_1):page226_i18:b" )
			)
			( pin "CF21.1"
				( objectStatus "@baseboard_fab2_lib.baseboard_fab2(sch_1):page226_i15:\1\" )
			)
			( pin "CF21.2"
				( objectStatus "@baseboard_fab2_lib.baseboard_fab2(sch_1):page226_i15:\2\" )
			)
			( pin "C1B12.1"
				( objectStatus "@baseboard_fab2_lib.baseboard_fab2(sch_1):page226_i12:a" )
			)
			( pin "C1B12.2"
				( objectStatus "@baseboard_fab2_lib.baseboard_fab2(sch_1):page226_i12:b" )
			)
			( pin "C4A15.1"
				( objectStatus "@baseboard_fab2_lib.baseboard_fab2(sch_1):page230_i17:a" )
			)
			( pin "C4A15.2"
				( objectStatus "@baseboard_fab2_lib.baseboard_fab2(sch_1):page230_i17:b" )
			)
			( pin "R4A5.1"
				( objectStatus "@baseboard_fab2_lib.baseboard_fab2(sch_1):page230_i21:a" )
			)
			( pin "R4A5.2"
				( objectStatus "@baseboard_fab2_lib.baseboard_fab2(sch_1):page230_i21:b" )
			)
			( pin "SH8L1.1"
				( objectStatus "@baseboard_fab2_lib.baseboard_fab2(sch_1):page230_i30:a" )
			)
			( pin "SH8L1.2"
				( objectStatus "@baseboard_fab2_lib.baseboard_fab2(sch_1):page230_i30:b" )
			)
			( pin "C5U12.1"
				( objectStatus "@baseboard_fab2_lib.baseboard_fab2(sch_1):page221_i45:a" )
			)
			( pin "C5U12.2"
				( objectStatus "@baseboard_fab2_lib.baseboard_fab2(sch_1):page221_i45:b" )
			)
			( pin "EU4A2.3"
				( objectStatus "@baseboard_fab2_lib.baseboard_fab2(sch_1):page230_i37:agnd" )
			)
			( pin "EU4A2.2"
				( objectStatus "@baseboard_fab2_lib.baseboard_fab2(sch_1):page230_i37:bias" )
			)
			( pin "EU4A2.7"
				( objectStatus "@baseboard_fab2_lib.baseboard_fab2(sch_1):page230_i37:en" )
			)
			( pin "EU4A2.5"
				( objectStatus "@baseboard_fab2_lib.baseboard_fab2(sch_1):page230_i37:pg" )
			)
			( pin "EU4A2.8"
				( objectStatus "@baseboard_fab2_lib.baseboard_fab2(sch_1):page230_i37:pgnd" )
			)
			( pin "EU4A2.6"
				( objectStatus "@baseboard_fab2_lib.baseboard_fab2(sch_1):page230_i37:sns" )
			)
			( pin "EU4A2.11"
				( objectStatus "@baseboard_fab2_lib.baseboard_fab2(sch_1):page230_i37:thpad" )
			)
			( pin "EU4A2.4"
				( objectStatus "@baseboard_fab2_lib.baseboard_fab2(sch_1):page230_i37:vddq" )
			)
			( pin "EU4A2.10"
				( objectStatus "@baseboard_fab2_lib.baseboard_fab2(sch_1):page230_i37:vin" )
			)
			( pin "EU4A2.1"
				( objectStatus "@baseboard_fab2_lib.baseboard_fab2(sch_1):page230_i37:vref" )
			)
			( pin "EU4A2.9"
				( objectStatus "@baseboard_fab2_lib.baseboard_fab2(sch_1):page230_i37:vtt" )
			)
			( pin "C6F6.1"
				( objectStatus "@baseboard_fab2_lib.baseboard_fab2(sch_1):page231_i122:a" )
			)
			( pin "C6F6.2"
				( objectStatus "@baseboard_fab2_lib.baseboard_fab2(sch_1):page231_i122:b" )
			)
			( pin "C4T6.1"
				( objectStatus "@baseboard_fab2_lib.baseboard_fab2(sch_1):page231_i124:a" )
			)
			( pin "C4T6.2"
				( objectStatus "@baseboard_fab2_lib.baseboard_fab2(sch_1):page231_i124:b" )
			)
			( pin "C4T5.1"
				( objectStatus "@baseboard_fab2_lib.baseboard_fab2(sch_1):page231_i125:a" )
			)
			( pin "C4T5.2"
				( objectStatus "@baseboard_fab2_lib.baseboard_fab2(sch_1):page231_i125:b" )
			)
			( pin "C6G1.1"
				( objectStatus "@baseboard_fab2_lib.baseboard_fab2(sch_1):page231_i126:a" )
			)
			( pin "C6G1.2"
				( objectStatus "@baseboard_fab2_lib.baseboard_fab2(sch_1):page231_i126:b" )
			)
			( pin "C6G2.1"
				( objectStatus "@baseboard_fab2_lib.baseboard_fab2(sch_1):page231_i128:a" )
			)
			( pin "C6G2.2"
				( objectStatus "@baseboard_fab2_lib.baseboard_fab2(sch_1):page231_i128:b" )
			)
			( pin "C4U2.1"
				( objectStatus "@baseboard_fab2_lib.baseboard_fab2(sch_1):page231_i129:a" )
			)
			( pin "C4U2.2"
				( objectStatus "@baseboard_fab2_lib.baseboard_fab2(sch_1):page231_i129:b" )
			)
			( pin "C4U1.1"
				( objectStatus "@baseboard_fab2_lib.baseboard_fab2(sch_1):page231_i130:a" )
			)
			( pin "C4U1.2"
				( objectStatus "@baseboard_fab2_lib.baseboard_fab2(sch_1):page231_i130:b" )
			)
			( pin "C6G4.1"
				( objectStatus "@baseboard_fab2_lib.baseboard_fab2(sch_1):page231_i131:a" )
			)
			( pin "C6G4.2"
				( objectStatus "@baseboard_fab2_lib.baseboard_fab2(sch_1):page231_i131:b" )
			)
			( pin "R7F15.1"
				( objectStatus "@baseboard_fab2_lib.baseboard_fab2(sch_1):page231_i134:a" )
			)
			( pin "R7F15.2"
				( objectStatus "@baseboard_fab2_lib.baseboard_fab2(sch_1):page231_i134:b" )
			)
			( pin "R7F14.1"
				( objectStatus "@baseboard_fab2_lib.baseboard_fab2(sch_1):page231_i136:a" )
			)
			( pin "R7F14.2"
				( objectStatus "@baseboard_fab2_lib.baseboard_fab2(sch_1):page231_i136:b" )
			)
			( pin "C7F8.1"
				( objectStatus "@baseboard_fab2_lib.baseboard_fab2(sch_1):page231_i140:a" )
			)
			( pin "C7F8.2"
				( objectStatus "@baseboard_fab2_lib.baseboard_fab2(sch_1):page231_i140:b" )
			)
			( pin "C7F11.1"
				( objectStatus "@baseboard_fab2_lib.baseboard_fab2(sch_1):page231_i142:a" )
			)
			( pin "C7F11.2"
				( objectStatus "@baseboard_fab2_lib.baseboard_fab2(sch_1):page231_i142:b" )
			)
			( pin "R7F19.1"
				( objectStatus "@baseboard_fab2_lib.baseboard_fab2(sch_1):page231_i143:a" )
			)
			( pin "R7F19.2"
				( objectStatus "@baseboard_fab2_lib.baseboard_fab2(sch_1):page231_i143:b" )
			)
			( pin "C6G5.1"
				( objectStatus "@baseboard_fab2_lib.baseboard_fab2(sch_1):page231_i145:a" )
			)
			( pin "C6G5.2"
				( objectStatus "@baseboard_fab2_lib.baseboard_fab2(sch_1):page231_i145:b" )
			)
			( pin "C4U4.1"
				( objectStatus "@baseboard_fab2_lib.baseboard_fab2(sch_1):page231_i146:a" )
			)
			( pin "C4U4.2"
				( objectStatus "@baseboard_fab2_lib.baseboard_fab2(sch_1):page231_i146:b" )
			)
			( pin "C4U3.1"
				( objectStatus "@baseboard_fab2_lib.baseboard_fab2(sch_1):page231_i148:a" )
			)
			( pin "C4U3.2"
				( objectStatus "@baseboard_fab2_lib.baseboard_fab2(sch_1):page231_i148:b" )
			)
			( pin "C6F5.1"
				( objectStatus "@baseboard_fab2_lib.baseboard_fab2(sch_1):page231_i149:a" )
			)
			( pin "C6F5.2"
				( objectStatus "@baseboard_fab2_lib.baseboard_fab2(sch_1):page231_i149:b" )
			)
			( pin "C8E11.1"
				( objectStatus "@baseboard_fab2_lib.baseboard_fab2(sch_1):page240_i183:\1\" )
			)
			( pin "C8E11.2"
				( objectStatus "@baseboard_fab2_lib.baseboard_fab2(sch_1):page240_i183:\2\" )
			)
			( pin "R7B19.1"
				( objectStatus "@baseboard_fab2_lib.baseboard_fab2(sch_1):page232_i313:a" )
			)
			( pin "R7B19.2"
				( objectStatus "@baseboard_fab2_lib.baseboard_fab2(sch_1):page232_i313:b" )
			)
			( pin "C7F4.1"
				( objectStatus "@baseboard_fab2_lib.baseboard_fab2(sch_1):page231_i159:a" )
			)
			( pin "C7F4.2"
				( objectStatus "@baseboard_fab2_lib.baseboard_fab2(sch_1):page231_i159:b" )
			)
			( pin "C3T10.1"
				( objectStatus "@baseboard_fab2_lib.baseboard_fab2(sch_1):page231_i161:a" )
			)
			( pin "C3T10.2"
				( objectStatus "@baseboard_fab2_lib.baseboard_fab2(sch_1):page231_i161:b" )
			)
			( pin "FB7F1.1"
				( objectStatus "@baseboard_fab2_lib.baseboard_fab2(sch_1):page231_i162:a" )
			)
			( pin "FB7F1.2"
				( objectStatus "@baseboard_fab2_lib.baseboard_fab2(sch_1):page231_i162:b" )
			)
			( pin "R7B13.1"
				( objectStatus "@baseboard_fab2_lib.baseboard_fab2(sch_1):page232_i314:a" )
			)
			( pin "R7B13.2"
				( objectStatus "@baseboard_fab2_lib.baseboard_fab2(sch_1):page232_i314:b" )
			)
			( pin "R7F13.1"
				( objectStatus "@baseboard_fab2_lib.baseboard_fab2(sch_1):page231_i167:a" )
			)
			( pin "R7F13.2"
				( objectStatus "@baseboard_fab2_lib.baseboard_fab2(sch_1):page231_i167:b" )
			)
			( pin "R7F12.1"
				( objectStatus "@baseboard_fab2_lib.baseboard_fab2(sch_1):page231_i168:a" )
			)
			( pin "R7F12.2"
				( objectStatus "@baseboard_fab2_lib.baseboard_fab2(sch_1):page231_i168:b" )
			)
			( pin "R7F35.1"
				( objectStatus "@baseboard_fab2_lib.baseboard_fab2(sch_1):page231_i170:a" )
			)
			( pin "R7F35.2"
				( objectStatus "@baseboard_fab2_lib.baseboard_fab2(sch_1):page231_i170:b" )
			)
			( pin "R7F7.1"
				( objectStatus "@baseboard_fab2_lib.baseboard_fab2(sch_1):page231_i174:a" )
			)
			( pin "R7F7.2"
				( objectStatus "@baseboard_fab2_lib.baseboard_fab2(sch_1):page231_i174:b" )
			)
			( pin "C7F3.1"
				( objectStatus "@baseboard_fab2_lib.baseboard_fab2(sch_1):page231_i175:a" )
			)
			( pin "C7F3.2"
				( objectStatus "@baseboard_fab2_lib.baseboard_fab2(sch_1):page231_i175:b" )
			)
			( pin "R7F10.1"
				( objectStatus "@baseboard_fab2_lib.baseboard_fab2(sch_1):page231_i177:a" )
			)
			( pin "R7F10.2"
				( objectStatus "@baseboard_fab2_lib.baseboard_fab2(sch_1):page231_i177:b" )
			)
			( pin "L7F1.1"
				( objectStatus "@baseboard_fab2_lib.baseboard_fab2(sch_1):page231_i178:ina" )
			)
			( pin "L7F1.2"
				( objectStatus "@baseboard_fab2_lib.baseboard_fab2(sch_1):page231_i178:inb" )
			)
			( pin "C6F4.1"
				( objectStatus "@baseboard_fab2_lib.baseboard_fab2(sch_1):page231_i180:a" )
			)
			( pin "C6F4.2"
				( objectStatus "@baseboard_fab2_lib.baseboard_fab2(sch_1):page231_i180:b" )
			)
			( pin "C3T7.1"
				( objectStatus "@baseboard_fab2_lib.baseboard_fab2(sch_1):page231_i184:a" )
			)
			( pin "C3T7.2"
				( objectStatus "@baseboard_fab2_lib.baseboard_fab2(sch_1):page231_i184:b" )
			)
			( pin "C3T9.1"
				( objectStatus "@baseboard_fab2_lib.baseboard_fab2(sch_1):page231_i186:a" )
			)
			( pin "C3T9.2"
				( objectStatus "@baseboard_fab2_lib.baseboard_fab2(sch_1):page231_i186:b" )
			)
			( pin "EU7F1.5"
				( objectStatus "@baseboard_fab2_lib.baseboard_fab2(sch_1):page231_i193:agnd" )
			)
			( pin "EU7F1.36"
				( objectStatus "@baseboard_fab2_lib.baseboard_fab2(sch_1):page231_i193:bst" )
			)
			( pin "EU7F1.3"
				( objectStatus "@baseboard_fab2_lib.baseboard_fab2(sch_1):page231_i193:comp" )
			)
			( pin "EU7F1.40"
				( objectStatus "@baseboard_fab2_lib.baseboard_fab2(sch_1):page231_i193:en" )
			)
			( pin "EU7F1.2"
				( objectStatus "@baseboard_fab2_lib.baseboard_fab2(sch_1):page231_i193:fb" )
			)
			( pin "EU7F1.41"
				( objectStatus "@baseboard_fab2_lib.baseboard_fab2(sch_1):page231_i193:gnd" )
			)
			( pin "EU7F1.4"
				( objectStatus "@baseboard_fab2_lib.baseboard_fab2(sch_1):page231_i193:iset" )
			)
			( pin "EU7F1.6"
				( objectStatus "@baseboard_fab2_lib.baseboard_fab2(sch_1):page231_i193:ots" )
			)
			( pin "EU7F1.7"
				( objectStatus "@baseboard_fab2_lib.baseboard_fab2(sch_1):page231_i193:pg" )
			)
			( pin "EU7F1.16"
				( objectStatus "@baseboard_fab2_lib.baseboard_fab2(sch_1):page231_i193:pgnd(0)" )
			)
			( pin "EU7F1.17"
				( objectStatus "@baseboard_fab2_lib.baseboard_fab2(sch_1):page231_i193:pgnd(1)" )
			)
			( pin "EU7F1.18"
				( objectStatus "@baseboard_fab2_lib.baseboard_fab2(sch_1):page231_i193:pgnd(2)" )
			)
			( pin "EU7F1.19"
				( objectStatus "@baseboard_fab2_lib.baseboard_fab2(sch_1):page231_i193:pgnd(3)" )
			)
			( pin "EU7F1.20"
				( objectStatus "@baseboard_fab2_lib.baseboard_fab2(sch_1):page231_i193:pgnd(4)" )
			)
			( pin "EU7F1.21"
				( objectStatus "@baseboard_fab2_lib.baseboard_fab2(sch_1):page231_i193:pgnd(5)" )
			)
			( pin "EU7F1.22"
				( objectStatus "@baseboard_fab2_lib.baseboard_fab2(sch_1):page231_i193:pgnd(6)" )
			)
			( pin "EU7F1.23"
				( objectStatus "@baseboard_fab2_lib.baseboard_fab2(sch_1):page231_i193:pgnd(7)" )
			)
			( pin "EU7F1.24"
				( objectStatus "@baseboard_fab2_lib.baseboard_fab2(sch_1):page231_i193:pgnd(8)" )
			)
			( pin "EU7F1.25"
				( objectStatus "@baseboard_fab2_lib.baseboard_fab2(sch_1):page231_i193:pgnd(9)" )
			)
			( pin "EU7F1.26"
				( objectStatus "@baseboard_fab2_lib.baseboard_fab2(sch_1):page231_i193:pgnd(10)" )
			)
			( pin "EU7F1.27"
				( objectStatus "@baseboard_fab2_lib.baseboard_fab2(sch_1):page231_i193:pgnd(11)" )
			)
			( pin "EU7F1.28"
				( objectStatus "@baseboard_fab2_lib.baseboard_fab2(sch_1):page231_i193:pgnd(12)" )
			)
			( pin "EU7F1.37"
				( objectStatus "@baseboard_fab2_lib.baseboard_fab2(sch_1):page231_i193:pgnd(13)" )
			)
			( pin "EU7F1.1"
				( objectStatus "@baseboard_fab2_lib.baseboard_fab2(sch_1):page231_i193:ss" )
			)
			( pin "EU7F1.38"
				( objectStatus "@baseboard_fab2_lib.baseboard_fab2(sch_1):page231_i193:vb" )
			)
			( pin "EU7F1.39"
				( objectStatus "@baseboard_fab2_lib.baseboard_fab2(sch_1):page231_i193:vcc" )
			)
			( pin "EU7F1.8"
				( objectStatus "@baseboard_fab2_lib.baseboard_fab2(sch_1):page231_i193:vin(0)" )
			)
			( pin "EU7F1.9"
				( objectStatus "@baseboard_fab2_lib.baseboard_fab2(sch_1):page231_i193:vin(1)" )
			)
			( pin "EU7F1.10"
				( objectStatus "@baseboard_fab2_lib.baseboard_fab2(sch_1):page231_i193:vin(2)" )
			)
			( pin "EU7F1.11"
				( objectStatus "@baseboard_fab2_lib.baseboard_fab2(sch_1):page231_i193:vin(3)" )
			)
			( pin "EU7F1.12"
				( objectStatus "@baseboard_fab2_lib.baseboard_fab2(sch_1):page231_i193:vin(4)" )
			)
			( pin "EU7F1.13"
				( objectStatus "@baseboard_fab2_lib.baseboard_fab2(sch_1):page231_i193:vin(5)" )
			)
			( pin "EU7F1.14"
				( objectStatus "@baseboard_fab2_lib.baseboard_fab2(sch_1):page231_i193:vin(6)" )
			)
			( pin "EU7F1.42"
				( objectStatus "@baseboard_fab2_lib.baseboard_fab2(sch_1):page231_i193:vin(7)" )
			)
			( pin "EU7F1.35"
				( objectStatus "@baseboard_fab2_lib.baseboard_fab2(sch_1):page231_i193:vsw" )
			)
			( pin "EU7F1.15"
				( objectStatus "@baseboard_fab2_lib.baseboard_fab2(sch_1):page231_i193:vswh(0)" )
			)
			( pin "EU7F1.29"
				( objectStatus "@baseboard_fab2_lib.baseboard_fab2(sch_1):page231_i193:vswh(1)" )
			)
			( pin "EU7F1.30"
				( objectStatus "@baseboard_fab2_lib.baseboard_fab2(sch_1):page231_i193:vswh(2)" )
			)
			( pin "EU7F1.31"
				( objectStatus "@baseboard_fab2_lib.baseboard_fab2(sch_1):page231_i193:vswh(3)" )
			)
			( pin "EU7F1.32"
				( objectStatus "@baseboard_fab2_lib.baseboard_fab2(sch_1):page231_i193:vswh(4)" )
			)
			( pin "EU7F1.33"
				( objectStatus "@baseboard_fab2_lib.baseboard_fab2(sch_1):page231_i193:vswh(5)" )
			)
			( pin "EU7F1.34"
				( objectStatus "@baseboard_fab2_lib.baseboard_fab2(sch_1):page231_i193:vswh(6)" )
			)
			( pin "EU7F1.43"
				( objectStatus "@baseboard_fab2_lib.baseboard_fab2(sch_1):page231_i193:vswh(7)" )
			)
			( pin "C7F10.1"
				( objectStatus "@baseboard_fab2_lib.baseboard_fab2(sch_1):page231_i194:a" )
			)
			( pin "C7F10.2"
				( objectStatus "@baseboard_fab2_lib.baseboard_fab2(sch_1):page231_i194:b" )
			)
			( pin "C7F9.1"
				( objectStatus "@baseboard_fab2_lib.baseboard_fab2(sch_1):page231_i199:a" )
			)
			( pin "C7F9.2"
				( objectStatus "@baseboard_fab2_lib.baseboard_fab2(sch_1):page231_i199:b" )
			)
			( pin "C7F12.1"
				( objectStatus "@baseboard_fab2_lib.baseboard_fab2(sch_1):page231_i200:a" )
			)
			( pin "C7F12.2"
				( objectStatus "@baseboard_fab2_lib.baseboard_fab2(sch_1):page231_i200:b" )
			)
			( pin "R7F18.1"
				( objectStatus "@baseboard_fab2_lib.baseboard_fab2(sch_1):page231_i201:a" )
			)
			( pin "R7F18.2"
				( objectStatus "@baseboard_fab2_lib.baseboard_fab2(sch_1):page231_i201:b" )
			)
			( pin "C3T11.1"
				( objectStatus "@baseboard_fab2_lib.baseboard_fab2(sch_1):page231_i202:a" )
			)
			( pin "C3T11.2"
				( objectStatus "@baseboard_fab2_lib.baseboard_fab2(sch_1):page231_i202:b" )
			)
			( pin "C7F6.1"
				( objectStatus "@baseboard_fab2_lib.baseboard_fab2(sch_1):page231_i205:a" )
			)
			( pin "C7F6.2"
				( objectStatus "@baseboard_fab2_lib.baseboard_fab2(sch_1):page231_i205:b" )
			)
			( pin "R7F16.1"
				( objectStatus "@baseboard_fab2_lib.baseboard_fab2(sch_1):page231_i208:a" )
			)
			( pin "R7F16.2"
				( objectStatus "@baseboard_fab2_lib.baseboard_fab2(sch_1):page231_i208:b" )
			)
			( pin "C7F5.1"
				( objectStatus "@baseboard_fab2_lib.baseboard_fab2(sch_1):page231_i209:a" )
			)
			( pin "C7F5.2"
				( objectStatus "@baseboard_fab2_lib.baseboard_fab2(sch_1):page231_i209:b" )
			)
			( pin "C3T8.1"
				( objectStatus "@baseboard_fab2_lib.baseboard_fab2(sch_1):page231_i210:a" )
			)
			( pin "C3T8.2"
				( objectStatus "@baseboard_fab2_lib.baseboard_fab2(sch_1):page231_i210:b" )
			)
			( pin "C3T14.1"
				( objectStatus "@baseboard_fab2_lib.baseboard_fab2(sch_1):page231_i211:a" )
			)
			( pin "C3T14.2"
				( objectStatus "@baseboard_fab2_lib.baseboard_fab2(sch_1):page231_i211:b" )
			)
			( pin "C3T12.1"
				( objectStatus "@baseboard_fab2_lib.baseboard_fab2(sch_1):page231_i215:a" )
			)
			( pin "C3T12.2"
				( objectStatus "@baseboard_fab2_lib.baseboard_fab2(sch_1):page231_i215:b" )
			)
			( pin "C4T3.1"
				( objectStatus "@baseboard_fab2_lib.baseboard_fab2(sch_1):page231_i217:a" )
			)
			( pin "C4T3.2"
				( objectStatus "@baseboard_fab2_lib.baseboard_fab2(sch_1):page231_i217:b" )
			)
			( pin "R7F17.1"
				( objectStatus "@baseboard_fab2_lib.baseboard_fab2(sch_1):page231_i218:a" )
			)
			( pin "R7F17.2"
				( objectStatus "@baseboard_fab2_lib.baseboard_fab2(sch_1):page231_i218:b" )
			)
			( pin "C7F13.1"
				( objectStatus "@baseboard_fab2_lib.baseboard_fab2(sch_1):page231_i219:a" )
			)
			( pin "C7F13.2"
				( objectStatus "@baseboard_fab2_lib.baseboard_fab2(sch_1):page231_i219:b" )
			)
			( pin "R7F9.1"
				( objectStatus "@baseboard_fab2_lib.baseboard_fab2(sch_1):page231_i220:a" )
			)
			( pin "R7F9.2"
				( objectStatus "@baseboard_fab2_lib.baseboard_fab2(sch_1):page231_i220:b" )
			)
			( pin "C4L2.1"
				( objectStatus "@baseboard_fab2_lib.baseboard_fab2(sch_1):page232_i102:a" )
			)
			( pin "C4L2.2"
				( objectStatus "@baseboard_fab2_lib.baseboard_fab2(sch_1):page232_i102:b" )
			)
			( pin "C6A3.1"
				( objectStatus "@baseboard_fab2_lib.baseboard_fab2(sch_1):page232_i104:a" )
			)
			( pin "C6A3.2"
				( objectStatus "@baseboard_fab2_lib.baseboard_fab2(sch_1):page232_i104:b" )
			)
			( pin "C6A2.1"
				( objectStatus "@baseboard_fab2_lib.baseboard_fab2(sch_1):page232_i105:a" )
			)
			( pin "C6A2.2"
				( objectStatus "@baseboard_fab2_lib.baseboard_fab2(sch_1):page232_i105:b" )
			)
			( pin "C4L3.1"
				( objectStatus "@baseboard_fab2_lib.baseboard_fab2(sch_1):page232_i106:a" )
			)
			( pin "C4L3.2"
				( objectStatus "@baseboard_fab2_lib.baseboard_fab2(sch_1):page232_i106:b" )
			)
			( pin "C4L4.1"
				( objectStatus "@baseboard_fab2_lib.baseboard_fab2(sch_1):page232_i108:a" )
			)
			( pin "C4L4.2"
				( objectStatus "@baseboard_fab2_lib.baseboard_fab2(sch_1):page232_i108:b" )
			)
			( pin "C6A7.1"
				( objectStatus "@baseboard_fab2_lib.baseboard_fab2(sch_1):page232_i109:a" )
			)
			( pin "C6A7.2"
				( objectStatus "@baseboard_fab2_lib.baseboard_fab2(sch_1):page232_i109:b" )
			)
			( pin "C6A6.1"
				( objectStatus "@baseboard_fab2_lib.baseboard_fab2(sch_1):page232_i110:a" )
			)
			( pin "C6A6.2"
				( objectStatus "@baseboard_fab2_lib.baseboard_fab2(sch_1):page232_i110:b" )
			)
			( pin "C4M3.1"
				( objectStatus "@baseboard_fab2_lib.baseboard_fab2(sch_1):page232_i111:a" )
			)
			( pin "C4M3.2"
				( objectStatus "@baseboard_fab2_lib.baseboard_fab2(sch_1):page232_i111:b" )
			)
			( pin "C4M4.1"
				( objectStatus "@baseboard_fab2_lib.baseboard_fab2(sch_1):page232_i125:a" )
			)
			( pin "C4M4.2"
				( objectStatus "@baseboard_fab2_lib.baseboard_fab2(sch_1):page232_i125:b" )
			)
			( pin "C6B2.1"
				( objectStatus "@baseboard_fab2_lib.baseboard_fab2(sch_1):page232_i126:a" )
			)
			( pin "C6B2.2"
				( objectStatus "@baseboard_fab2_lib.baseboard_fab2(sch_1):page232_i126:b" )
			)
			( pin "C6B1.1"
				( objectStatus "@baseboard_fab2_lib.baseboard_fab2(sch_1):page232_i128:a" )
			)
			( pin "C6B1.2"
				( objectStatus "@baseboard_fab2_lib.baseboard_fab2(sch_1):page232_i128:b" )
			)
			( pin "C4L1.1"
				( objectStatus "@baseboard_fab2_lib.baseboard_fab2(sch_1):page232_i129:a" )
			)
			( pin "C4L1.2"
				( objectStatus "@baseboard_fab2_lib.baseboard_fab2(sch_1):page232_i129:b" )
			)
			( pin "R7B20.1"
				( objectStatus "@baseboard_fab2_lib.baseboard_fab2(sch_1):page232_i150:a" )
			)
			( pin "R7B20.2"
				( objectStatus "@baseboard_fab2_lib.baseboard_fab2(sch_1):page232_i150:b" )
			)
			( pin "C7B9.1"
				( objectStatus "@baseboard_fab2_lib.baseboard_fab2(sch_1):page232_i185:a" )
			)
			( pin "C7B9.2"
				( objectStatus "@baseboard_fab2_lib.baseboard_fab2(sch_1):page232_i185:b" )
			)
			( pin "R4G11.1"
				( objectStatus "@baseboard_fab2_lib.baseboard_fab2(sch_1):page233_i284:a" )
			)
			( pin "R4G11.2"
				( objectStatus "@baseboard_fab2_lib.baseboard_fab2(sch_1):page233_i284:b" )
			)
			( pin "C7B11.1"
				( objectStatus "@baseboard_fab2_lib.baseboard_fab2(sch_1):page232_i197:a" )
			)
			( pin "C7B11.2"
				( objectStatus "@baseboard_fab2_lib.baseboard_fab2(sch_1):page232_i197:b" )
			)
			( pin "FB7B1.1"
				( objectStatus "@baseboard_fab2_lib.baseboard_fab2(sch_1):page232_i200:a" )
			)
			( pin "FB7B1.2"
				( objectStatus "@baseboard_fab2_lib.baseboard_fab2(sch_1):page232_i200:b" )
			)
			( pin "C7E13.1"
				( objectStatus "@baseboard_fab2_lib.baseboard_fab2(sch_1):page241_i92:\1\" )
			)
			( pin "C7E13.2"
				( objectStatus "@baseboard_fab2_lib.baseboard_fab2(sch_1):page241_i92:\2\" )
			)
			( pin "C3M9.1"
				( objectStatus "@baseboard_fab2_lib.baseboard_fab2(sch_1):page232_i207:a" )
			)
			( pin "C3M9.2"
				( objectStatus "@baseboard_fab2_lib.baseboard_fab2(sch_1):page232_i207:b" )
			)
			( pin "C7B12.1"
				( objectStatus "@baseboard_fab2_lib.baseboard_fab2(sch_1):page232_i209:a" )
			)
			( pin "C7B12.2"
				( objectStatus "@baseboard_fab2_lib.baseboard_fab2(sch_1):page232_i209:b" )
			)
			( pin "R7B17.1"
				( objectStatus "@baseboard_fab2_lib.baseboard_fab2(sch_1):page232_i210:a" )
			)
			( pin "R7B17.2"
				( objectStatus "@baseboard_fab2_lib.baseboard_fab2(sch_1):page232_i210:b" )
			)
			( pin "EU7B1.5"
				( objectStatus "@baseboard_fab2_lib.baseboard_fab2(sch_1):page232_i214:agnd" )
			)
			( pin "EU7B1.36"
				( objectStatus "@baseboard_fab2_lib.baseboard_fab2(sch_1):page232_i214:bst" )
			)
			( pin "EU7B1.3"
				( objectStatus "@baseboard_fab2_lib.baseboard_fab2(sch_1):page232_i214:comp" )
			)
			( pin "EU7B1.40"
				( objectStatus "@baseboard_fab2_lib.baseboard_fab2(sch_1):page232_i214:en" )
			)
			( pin "EU7B1.2"
				( objectStatus "@baseboard_fab2_lib.baseboard_fab2(sch_1):page232_i214:fb" )
			)
			( pin "EU7B1.41"
				( objectStatus "@baseboard_fab2_lib.baseboard_fab2(sch_1):page232_i214:gnd" )
			)
			( pin "EU7B1.4"
				( objectStatus "@baseboard_fab2_lib.baseboard_fab2(sch_1):page232_i214:iset" )
			)
			( pin "EU7B1.6"
				( objectStatus "@baseboard_fab2_lib.baseboard_fab2(sch_1):page232_i214:ots" )
			)
			( pin "EU7B1.7"
				( objectStatus "@baseboard_fab2_lib.baseboard_fab2(sch_1):page232_i214:pg" )
			)
			( pin "EU7B1.16"
				( objectStatus "@baseboard_fab2_lib.baseboard_fab2(sch_1):page232_i214:pgnd(0)" )
			)
			( pin "EU7B1.17"
				( objectStatus "@baseboard_fab2_lib.baseboard_fab2(sch_1):page232_i214:pgnd(1)" )
			)
			( pin "EU7B1.18"
				( objectStatus "@baseboard_fab2_lib.baseboard_fab2(sch_1):page232_i214:pgnd(2)" )
			)
			( pin "EU7B1.19"
				( objectStatus "@baseboard_fab2_lib.baseboard_fab2(sch_1):page232_i214:pgnd(3)" )
			)
			( pin "EU7B1.20"
				( objectStatus "@baseboard_fab2_lib.baseboard_fab2(sch_1):page232_i214:pgnd(4)" )
			)
			( pin "EU7B1.21"
				( objectStatus "@baseboard_fab2_lib.baseboard_fab2(sch_1):page232_i214:pgnd(5)" )
			)
			( pin "EU7B1.22"
				( objectStatus "@baseboard_fab2_lib.baseboard_fab2(sch_1):page232_i214:pgnd(6)" )
			)
			( pin "EU7B1.23"
				( objectStatus "@baseboard_fab2_lib.baseboard_fab2(sch_1):page232_i214:pgnd(7)" )
			)
			( pin "EU7B1.24"
				( objectStatus "@baseboard_fab2_lib.baseboard_fab2(sch_1):page232_i214:pgnd(8)" )
			)
			( pin "EU7B1.25"
				( objectStatus "@baseboard_fab2_lib.baseboard_fab2(sch_1):page232_i214:pgnd(9)" )
			)
			( pin "EU7B1.26"
				( objectStatus "@baseboard_fab2_lib.baseboard_fab2(sch_1):page232_i214:pgnd(10)" )
			)
			( pin "EU7B1.27"
				( objectStatus "@baseboard_fab2_lib.baseboard_fab2(sch_1):page232_i214:pgnd(11)" )
			)
			( pin "EU7B1.28"
				( objectStatus "@baseboard_fab2_lib.baseboard_fab2(sch_1):page232_i214:pgnd(12)" )
			)
			( pin "EU7B1.37"
				( objectStatus "@baseboard_fab2_lib.baseboard_fab2(sch_1):page232_i214:pgnd(13)" )
			)
			( pin "EU7B1.1"
				( objectStatus "@baseboard_fab2_lib.baseboard_fab2(sch_1):page232_i214:ss" )
			)
			( pin "EU7B1.38"
				( objectStatus "@baseboard_fab2_lib.baseboard_fab2(sch_1):page232_i214:vb" )
			)
			( pin "EU7B1.39"
				( objectStatus "@baseboard_fab2_lib.baseboard_fab2(sch_1):page232_i214:vcc" )
			)
			( pin "EU7B1.8"
				( objectStatus "@baseboard_fab2_lib.baseboard_fab2(sch_1):page232_i214:vin(0)" )
			)
			( pin "EU7B1.9"
				( objectStatus "@baseboard_fab2_lib.baseboard_fab2(sch_1):page232_i214:vin(1)" )
			)
			( pin "EU7B1.10"
				( objectStatus "@baseboard_fab2_lib.baseboard_fab2(sch_1):page232_i214:vin(2)" )
			)
			( pin "EU7B1.11"
				( objectStatus "@baseboard_fab2_lib.baseboard_fab2(sch_1):page232_i214:vin(3)" )
			)
			( pin "EU7B1.12"
				( objectStatus "@baseboard_fab2_lib.baseboard_fab2(sch_1):page232_i214:vin(4)" )
			)
			( pin "EU7B1.13"
				( objectStatus "@baseboard_fab2_lib.baseboard_fab2(sch_1):page232_i214:vin(5)" )
			)
			( pin "EU7B1.14"
				( objectStatus "@baseboard_fab2_lib.baseboard_fab2(sch_1):page232_i214:vin(6)" )
			)
			( pin "EU7B1.42"
				( objectStatus "@baseboard_fab2_lib.baseboard_fab2(sch_1):page232_i214:vin(7)" )
			)
			( pin "EU7B1.35"
				( objectStatus "@baseboard_fab2_lib.baseboard_fab2(sch_1):page232_i214:vsw" )
			)
			( pin "EU7B1.15"
				( objectStatus "@baseboard_fab2_lib.baseboard_fab2(sch_1):page232_i214:vswh(0)" )
			)
			( pin "EU7B1.29"
				( objectStatus "@baseboard_fab2_lib.baseboard_fab2(sch_1):page232_i214:vswh(1)" )
			)
			( pin "EU7B1.30"
				( objectStatus "@baseboard_fab2_lib.baseboard_fab2(sch_1):page232_i214:vswh(2)" )
			)
			( pin "EU7B1.31"
				( objectStatus "@baseboard_fab2_lib.baseboard_fab2(sch_1):page232_i214:vswh(3)" )
			)
			( pin "EU7B1.32"
				( objectStatus "@baseboard_fab2_lib.baseboard_fab2(sch_1):page232_i214:vswh(4)" )
			)
			( pin "EU7B1.33"
				( objectStatus "@baseboard_fab2_lib.baseboard_fab2(sch_1):page232_i214:vswh(5)" )
			)
			( pin "EU7B1.34"
				( objectStatus "@baseboard_fab2_lib.baseboard_fab2(sch_1):page232_i214:vswh(6)" )
			)
			( pin "EU7B1.43"
				( objectStatus "@baseboard_fab2_lib.baseboard_fab2(sch_1):page232_i214:vswh(7)" )
			)
			( pin "R7A15.1"
				( objectStatus "@baseboard_fab2_lib.baseboard_fab2(sch_1):page232_i218:a" )
			)
			( pin "R7A15.2"
				( objectStatus "@baseboard_fab2_lib.baseboard_fab2(sch_1):page232_i218:b" )
			)
			( pin "C7A34.1"
				( objectStatus "@baseboard_fab2_lib.baseboard_fab2(sch_1):page232_i220:a" )
			)
			( pin "C7A34.2"
				( objectStatus "@baseboard_fab2_lib.baseboard_fab2(sch_1):page232_i220:b" )
			)
			( pin "R7B10.1"
				( objectStatus "@baseboard_fab2_lib.baseboard_fab2(sch_1):page232_i227:a" )
			)
			( pin "R7B10.2"
				( objectStatus "@baseboard_fab2_lib.baseboard_fab2(sch_1):page232_i227:b" )
			)
			( pin "C6B7.1"
				( objectStatus "@baseboard_fab2_lib.baseboard_fab2(sch_1):page232_i229:a" )
			)
			( pin "C6B7.2"
				( objectStatus "@baseboard_fab2_lib.baseboard_fab2(sch_1):page232_i229:b" )
			)
			( pin "C6B3.1"
				( objectStatus "@baseboard_fab2_lib.baseboard_fab2(sch_1):page232_i236:a" )
			)
			( pin "C6B3.2"
				( objectStatus "@baseboard_fab2_lib.baseboard_fab2(sch_1):page232_i236:b" )
			)
			( pin "C7B7.1"
				( objectStatus "@baseboard_fab2_lib.baseboard_fab2(sch_1):page232_i238:a" )
			)
			( pin "C7B7.2"
				( objectStatus "@baseboard_fab2_lib.baseboard_fab2(sch_1):page232_i238:b" )
			)
			( pin "L7B1.1"
				( objectStatus "@baseboard_fab2_lib.baseboard_fab2(sch_1):page232_i239:ina" )
			)
			( pin "L7B1.2"
				( objectStatus "@baseboard_fab2_lib.baseboard_fab2(sch_1):page232_i239:inb" )
			)
			( pin "R4B13.1"
				( objectStatus "@baseboard_fab2_lib.baseboard_fab2(sch_1):page234_i226:a" )
			)
			( pin "R4B13.2"
				( objectStatus "@baseboard_fab2_lib.baseboard_fab2(sch_1):page234_i226:b" )
			)
			( pin "C7B30.1"
				( objectStatus "@baseboard_fab2_lib.baseboard_fab2(sch_1):page232_i241:a" )
			)
			( pin "C7B30.2"
				( objectStatus "@baseboard_fab2_lib.baseboard_fab2(sch_1):page232_i241:b" )
			)
			( pin "C7B6.1"
				( objectStatus "@baseboard_fab2_lib.baseboard_fab2(sch_1):page232_i252:a" )
			)
			( pin "C7B6.2"
				( objectStatus "@baseboard_fab2_lib.baseboard_fab2(sch_1):page232_i252:b" )
			)
			( pin "C3M10.1"
				( objectStatus "@baseboard_fab2_lib.baseboard_fab2(sch_1):page232_i253:a" )
			)
			( pin "C3M10.2"
				( objectStatus "@baseboard_fab2_lib.baseboard_fab2(sch_1):page232_i253:b" )
			)
			( pin "R7B12.1"
				( objectStatus "@baseboard_fab2_lib.baseboard_fab2(sch_1):page232_i257:a" )
			)
			( pin "R7B12.2"
				( objectStatus "@baseboard_fab2_lib.baseboard_fab2(sch_1):page232_i257:b" )
			)
			( pin "C3M8.1"
				( objectStatus "@baseboard_fab2_lib.baseboard_fab2(sch_1):page232_i259:a" )
			)
			( pin "C3M8.2"
				( objectStatus "@baseboard_fab2_lib.baseboard_fab2(sch_1):page232_i259:b" )
			)
			( pin "C3M15.1"
				( objectStatus "@baseboard_fab2_lib.baseboard_fab2(sch_1):page232_i260:a" )
			)
			( pin "C3M15.2"
				( objectStatus "@baseboard_fab2_lib.baseboard_fab2(sch_1):page232_i260:b" )
			)
			( pin "C3M16.1"
				( objectStatus "@baseboard_fab2_lib.baseboard_fab2(sch_1):page232_i261:a" )
			)
			( pin "C3M16.2"
				( objectStatus "@baseboard_fab2_lib.baseboard_fab2(sch_1):page232_i261:b" )
			)
			( pin "C7B5.1"
				( objectStatus "@baseboard_fab2_lib.baseboard_fab2(sch_1):page232_i262:a" )
			)
			( pin "C7B5.2"
				( objectStatus "@baseboard_fab2_lib.baseboard_fab2(sch_1):page232_i262:b" )
			)
			( pin "C4M1.1"
				( objectStatus "@baseboard_fab2_lib.baseboard_fab2(sch_1):page232_i267:a" )
			)
			( pin "C4M1.2"
				( objectStatus "@baseboard_fab2_lib.baseboard_fab2(sch_1):page232_i267:b" )
			)
			( pin "R7B18.1"
				( objectStatus "@baseboard_fab2_lib.baseboard_fab2(sch_1):page232_i298:a" )
			)
			( pin "R7B18.2"
				( objectStatus "@baseboard_fab2_lib.baseboard_fab2(sch_1):page232_i298:b" )
			)
			( pin "R7B11.1"
				( objectStatus "@baseboard_fab2_lib.baseboard_fab2(sch_1):page232_i299:a" )
			)
			( pin "R7B11.2"
				( objectStatus "@baseboard_fab2_lib.baseboard_fab2(sch_1):page232_i299:b" )
			)
			( pin "R7B16.1"
				( objectStatus "@baseboard_fab2_lib.baseboard_fab2(sch_1):page232_i300:a" )
			)
			( pin "R7B16.2"
				( objectStatus "@baseboard_fab2_lib.baseboard_fab2(sch_1):page232_i300:b" )
			)
			( pin "C7B10.1"
				( objectStatus "@baseboard_fab2_lib.baseboard_fab2(sch_1):page232_i301:a" )
			)
			( pin "C7B10.2"
				( objectStatus "@baseboard_fab2_lib.baseboard_fab2(sch_1):page232_i301:b" )
			)
			( pin "C7B13.1"
				( objectStatus "@baseboard_fab2_lib.baseboard_fab2(sch_1):page232_i302:a" )
			)
			( pin "C7B13.2"
				( objectStatus "@baseboard_fab2_lib.baseboard_fab2(sch_1):page232_i302:b" )
			)
			( pin "R7B15.1"
				( objectStatus "@baseboard_fab2_lib.baseboard_fab2(sch_1):page232_i303:a" )
			)
			( pin "R7B15.2"
				( objectStatus "@baseboard_fab2_lib.baseboard_fab2(sch_1):page232_i303:b" )
			)
			( pin "R4G9.1"
				( objectStatus "@baseboard_fab2_lib.baseboard_fab2(sch_1):page233_i283:a" )
			)
			( pin "R4G9.2"
				( objectStatus "@baseboard_fab2_lib.baseboard_fab2(sch_1):page233_i283:b" )
			)
			( pin "C7B14.1"
				( objectStatus "@baseboard_fab2_lib.baseboard_fab2(sch_1):page232_i306:a" )
			)
			( pin "C7B14.2"
				( objectStatus "@baseboard_fab2_lib.baseboard_fab2(sch_1):page232_i306:b" )
			)
			( pin "R7B9.1"
				( objectStatus "@baseboard_fab2_lib.baseboard_fab2(sch_1):page232_i307:a" )
			)
			( pin "R7B9.2"
				( objectStatus "@baseboard_fab2_lib.baseboard_fab2(sch_1):page232_i307:b" )
			)
			( pin "C7U4.1"
				( objectStatus "@baseboard_fab2_lib.baseboard_fab2(sch_1):page233_i109:a" )
			)
			( pin "C7U4.2"
				( objectStatus "@baseboard_fab2_lib.baseboard_fab2(sch_1):page233_i109:b" )
			)
			( pin "C7U5.1"
				( objectStatus "@baseboard_fab2_lib.baseboard_fab2(sch_1):page233_i111:a" )
			)
			( pin "C7U5.2"
				( objectStatus "@baseboard_fab2_lib.baseboard_fab2(sch_1):page233_i111:b" )
			)
			( pin "C7T2.1"
				( objectStatus "@baseboard_fab2_lib.baseboard_fab2(sch_1):page233_i112:a" )
			)
			( pin "C7T2.2"
				( objectStatus "@baseboard_fab2_lib.baseboard_fab2(sch_1):page233_i112:b" )
			)
			( pin "C7T3.1"
				( objectStatus "@baseboard_fab2_lib.baseboard_fab2(sch_1):page233_i113:a" )
			)
			( pin "C7T3.2"
				( objectStatus "@baseboard_fab2_lib.baseboard_fab2(sch_1):page233_i113:b" )
			)
			( pin "C7U6.1"
				( objectStatus "@baseboard_fab2_lib.baseboard_fab2(sch_1):page233_i115:a" )
			)
			( pin "C7U6.2"
				( objectStatus "@baseboard_fab2_lib.baseboard_fab2(sch_1):page233_i115:b" )
			)
			( pin "C3F3.1"
				( objectStatus "@baseboard_fab2_lib.baseboard_fab2(sch_1):page233_i116:a" )
			)
			( pin "C3F3.2"
				( objectStatus "@baseboard_fab2_lib.baseboard_fab2(sch_1):page233_i116:b" )
			)
			( pin "C3F4.1"
				( objectStatus "@baseboard_fab2_lib.baseboard_fab2(sch_1):page233_i117:a" )
			)
			( pin "C3F4.2"
				( objectStatus "@baseboard_fab2_lib.baseboard_fab2(sch_1):page233_i117:b" )
			)
			( pin "C3G3.1"
				( objectStatus "@baseboard_fab2_lib.baseboard_fab2(sch_1):page233_i118:a" )
			)
			( pin "C3G3.2"
				( objectStatus "@baseboard_fab2_lib.baseboard_fab2(sch_1):page233_i118:b" )
			)
			( pin "C3G7.1"
				( objectStatus "@baseboard_fab2_lib.baseboard_fab2(sch_1):page233_i132:a" )
			)
			( pin "C3G7.2"
				( objectStatus "@baseboard_fab2_lib.baseboard_fab2(sch_1):page233_i132:b" )
			)
			( pin "C3G4.1"
				( objectStatus "@baseboard_fab2_lib.baseboard_fab2(sch_1):page233_i133:a" )
			)
			( pin "C3G4.2"
				( objectStatus "@baseboard_fab2_lib.baseboard_fab2(sch_1):page233_i133:b" )
			)
			( pin "C3G8.1"
				( objectStatus "@baseboard_fab2_lib.baseboard_fab2(sch_1):page233_i135:a" )
			)
			( pin "C3G8.2"
				( objectStatus "@baseboard_fab2_lib.baseboard_fab2(sch_1):page233_i135:b" )
			)
			( pin "C7U3.1"
				( objectStatus "@baseboard_fab2_lib.baseboard_fab2(sch_1):page233_i136:a" )
			)
			( pin "C7U3.2"
				( objectStatus "@baseboard_fab2_lib.baseboard_fab2(sch_1):page233_i136:b" )
			)
			( pin "R4G25.1"
				( objectStatus "@baseboard_fab2_lib.baseboard_fab2(sch_1):page233_i157:a" )
			)
			( pin "R4G25.2"
				( objectStatus "@baseboard_fab2_lib.baseboard_fab2(sch_1):page233_i157:b" )
			)
			( pin "R4G5.1"
				( objectStatus "@baseboard_fab2_lib.baseboard_fab2(sch_1):page233_i182:a" )
			)
			( pin "R4G5.2"
				( objectStatus "@baseboard_fab2_lib.baseboard_fab2(sch_1):page233_i182:b" )
			)
			( pin "C4G7.1"
				( objectStatus "@baseboard_fab2_lib.baseboard_fab2(sch_1):page233_i183:a" )
			)
			( pin "C4G7.2"
				( objectStatus "@baseboard_fab2_lib.baseboard_fab2(sch_1):page233_i183:b" )
			)
			( pin "R4B6.1"
				( objectStatus "@baseboard_fab2_lib.baseboard_fab2(sch_1):page234_i228:a" )
			)
			( pin "R4B6.2"
				( objectStatus "@baseboard_fab2_lib.baseboard_fab2(sch_1):page234_i228:b" )
			)
			( pin "R4G14.1"
				( objectStatus "@baseboard_fab2_lib.baseboard_fab2(sch_1):page233_i185:a" )
			)
			( pin "R4G14.2"
				( objectStatus "@baseboard_fab2_lib.baseboard_fab2(sch_1):page233_i185:b" )
			)
			( pin "C6U6.1"
				( objectStatus "@baseboard_fab2_lib.baseboard_fab2(sch_1):page233_i187:a" )
			)
			( pin "C6U6.2"
				( objectStatus "@baseboard_fab2_lib.baseboard_fab2(sch_1):page233_i187:b" )
			)
			( pin "C7B8.1"
				( objectStatus "@baseboard_fab2_lib.baseboard_fab2(sch_1):page232_i309:\1\" )
			)
			( pin "C7B8.2"
				( objectStatus "@baseboard_fab2_lib.baseboard_fab2(sch_1):page232_i309:\2\" )
			)
			( pin "C4G8.1"
				( objectStatus "@baseboard_fab2_lib.baseboard_fab2(sch_1):page233_i194:a" )
			)
			( pin "C4G8.2"
				( objectStatus "@baseboard_fab2_lib.baseboard_fab2(sch_1):page233_i194:b" )
			)
			( pin "C4G4.1"
				( objectStatus "@baseboard_fab2_lib.baseboard_fab2(sch_1):page233_i196:a" )
			)
			( pin "C4G4.2"
				( objectStatus "@baseboard_fab2_lib.baseboard_fab2(sch_1):page233_i196:b" )
			)
			( pin "FB4G1.1"
				( objectStatus "@baseboard_fab2_lib.baseboard_fab2(sch_1):page233_i198:a" )
			)
			( pin "FB4G1.2"
				( objectStatus "@baseboard_fab2_lib.baseboard_fab2(sch_1):page233_i198:b" )
			)
			( pin "C4G9.1"
				( objectStatus "@baseboard_fab2_lib.baseboard_fab2(sch_1):page233_i201:a" )
			)
			( pin "C4G9.2"
				( objectStatus "@baseboard_fab2_lib.baseboard_fab2(sch_1):page233_i201:b" )
			)
			( pin "R4F6.1"
				( objectStatus "@baseboard_fab2_lib.baseboard_fab2(sch_1):page233_i208:a" )
			)
			( pin "R4F6.2"
				( objectStatus "@baseboard_fab2_lib.baseboard_fab2(sch_1):page233_i208:b" )
			)
			( pin "C4F12.1"
				( objectStatus "@baseboard_fab2_lib.baseboard_fab2(sch_1):page233_i209:a" )
			)
			( pin "C4F12.2"
				( objectStatus "@baseboard_fab2_lib.baseboard_fab2(sch_1):page233_i209:b" )
			)
			( pin "R4G6.1"
				( objectStatus "@baseboard_fab2_lib.baseboard_fab2(sch_1):page233_i211:a" )
			)
			( pin "R4G6.2"
				( objectStatus "@baseboard_fab2_lib.baseboard_fab2(sch_1):page233_i211:b" )
			)
			( pin "C4F7.1"
				( objectStatus "@baseboard_fab2_lib.baseboard_fab2(sch_1):page233_i217:a" )
			)
			( pin "C4F7.2"
				( objectStatus "@baseboard_fab2_lib.baseboard_fab2(sch_1):page233_i217:b" )
			)
			( pin "C6U3.1"
				( objectStatus "@baseboard_fab2_lib.baseboard_fab2(sch_1):page233_i221:a" )
			)
			( pin "C6U3.2"
				( objectStatus "@baseboard_fab2_lib.baseboard_fab2(sch_1):page233_i221:b" )
			)
			( pin "C6U2.1"
				( objectStatus "@baseboard_fab2_lib.baseboard_fab2(sch_1):page233_i223:a" )
			)
			( pin "C6U2.2"
				( objectStatus "@baseboard_fab2_lib.baseboard_fab2(sch_1):page233_i223:b" )
			)
			( pin "C4G26.1"
				( objectStatus "@baseboard_fab2_lib.baseboard_fab2(sch_1):page233_i224:a" )
			)
			( pin "C4G26.2"
				( objectStatus "@baseboard_fab2_lib.baseboard_fab2(sch_1):page233_i224:b" )
			)
			( pin "EU4G1.5"
				( objectStatus "@baseboard_fab2_lib.baseboard_fab2(sch_1):page233_i225:agnd" )
			)
			( pin "EU4G1.36"
				( objectStatus "@baseboard_fab2_lib.baseboard_fab2(sch_1):page233_i225:bst" )
			)
			( pin "EU4G1.3"
				( objectStatus "@baseboard_fab2_lib.baseboard_fab2(sch_1):page233_i225:comp" )
			)
			( pin "EU4G1.40"
				( objectStatus "@baseboard_fab2_lib.baseboard_fab2(sch_1):page233_i225:en" )
			)
			( pin "EU4G1.2"
				( objectStatus "@baseboard_fab2_lib.baseboard_fab2(sch_1):page233_i225:fb" )
			)
			( pin "EU4G1.41"
				( objectStatus "@baseboard_fab2_lib.baseboard_fab2(sch_1):page233_i225:gnd" )
			)
			( pin "EU4G1.4"
				( objectStatus "@baseboard_fab2_lib.baseboard_fab2(sch_1):page233_i225:iset" )
			)
			( pin "EU4G1.6"
				( objectStatus "@baseboard_fab2_lib.baseboard_fab2(sch_1):page233_i225:ots" )
			)
			( pin "EU4G1.7"
				( objectStatus "@baseboard_fab2_lib.baseboard_fab2(sch_1):page233_i225:pg" )
			)
			( pin "EU4G1.16"
				( objectStatus "@baseboard_fab2_lib.baseboard_fab2(sch_1):page233_i225:pgnd(0)" )
			)
			( pin "EU4G1.17"
				( objectStatus "@baseboard_fab2_lib.baseboard_fab2(sch_1):page233_i225:pgnd(1)" )
			)
			( pin "EU4G1.18"
				( objectStatus "@baseboard_fab2_lib.baseboard_fab2(sch_1):page233_i225:pgnd(2)" )
			)
			( pin "EU4G1.19"
				( objectStatus "@baseboard_fab2_lib.baseboard_fab2(sch_1):page233_i225:pgnd(3)" )
			)
			( pin "EU4G1.20"
				( objectStatus "@baseboard_fab2_lib.baseboard_fab2(sch_1):page233_i225:pgnd(4)" )
			)
			( pin "EU4G1.21"
				( objectStatus "@baseboard_fab2_lib.baseboard_fab2(sch_1):page233_i225:pgnd(5)" )
			)
			( pin "EU4G1.22"
				( objectStatus "@baseboard_fab2_lib.baseboard_fab2(sch_1):page233_i225:pgnd(6)" )
			)
			( pin "EU4G1.23"
				( objectStatus "@baseboard_fab2_lib.baseboard_fab2(sch_1):page233_i225:pgnd(7)" )
			)
			( pin "EU4G1.24"
				( objectStatus "@baseboard_fab2_lib.baseboard_fab2(sch_1):page233_i225:pgnd(8)" )
			)
			( pin "EU4G1.25"
				( objectStatus "@baseboard_fab2_lib.baseboard_fab2(sch_1):page233_i225:pgnd(9)" )
			)
			( pin "EU4G1.26"
				( objectStatus "@baseboard_fab2_lib.baseboard_fab2(sch_1):page233_i225:pgnd(10)" )
			)
			( pin "EU4G1.27"
				( objectStatus "@baseboard_fab2_lib.baseboard_fab2(sch_1):page233_i225:pgnd(11)" )
			)
			( pin "EU4G1.28"
				( objectStatus "@baseboard_fab2_lib.baseboard_fab2(sch_1):page233_i225:pgnd(12)" )
			)
			( pin "EU4G1.37"
				( objectStatus "@baseboard_fab2_lib.baseboard_fab2(sch_1):page233_i225:pgnd(13)" )
			)
			( pin "EU4G1.1"
				( objectStatus "@baseboard_fab2_lib.baseboard_fab2(sch_1):page233_i225:ss" )
			)
			( pin "EU4G1.38"
				( objectStatus "@baseboard_fab2_lib.baseboard_fab2(sch_1):page233_i225:vb" )
			)
			( pin "EU4G1.39"
				( objectStatus "@baseboard_fab2_lib.baseboard_fab2(sch_1):page233_i225:vcc" )
			)
			( pin "EU4G1.8"
				( objectStatus "@baseboard_fab2_lib.baseboard_fab2(sch_1):page233_i225:vin(0)" )
			)
			( pin "EU4G1.9"
				( objectStatus "@baseboard_fab2_lib.baseboard_fab2(sch_1):page233_i225:vin(1)" )
			)
			( pin "EU4G1.10"
				( objectStatus "@baseboard_fab2_lib.baseboard_fab2(sch_1):page233_i225:vin(2)" )
			)
			( pin "EU4G1.11"
				( objectStatus "@baseboard_fab2_lib.baseboard_fab2(sch_1):page233_i225:vin(3)" )
			)
			( pin "EU4G1.12"
				( objectStatus "@baseboard_fab2_lib.baseboard_fab2(sch_1):page233_i225:vin(4)" )
			)
			( pin "EU4G1.13"
				( objectStatus "@baseboard_fab2_lib.baseboard_fab2(sch_1):page233_i225:vin(5)" )
			)
			( pin "EU4G1.14"
				( objectStatus "@baseboard_fab2_lib.baseboard_fab2(sch_1):page233_i225:vin(6)" )
			)
			( pin "EU4G1.42"
				( objectStatus "@baseboard_fab2_lib.baseboard_fab2(sch_1):page233_i225:vin(7)" )
			)
			( pin "EU4G1.35"
				( objectStatus "@baseboard_fab2_lib.baseboard_fab2(sch_1):page233_i225:vsw" )
			)
			( pin "EU4G1.15"
				( objectStatus "@baseboard_fab2_lib.baseboard_fab2(sch_1):page233_i225:vswh(0)" )
			)
			( pin "EU4G1.29"
				( objectStatus "@baseboard_fab2_lib.baseboard_fab2(sch_1):page233_i225:vswh(1)" )
			)
			( pin "EU4G1.30"
				( objectStatus "@baseboard_fab2_lib.baseboard_fab2(sch_1):page233_i225:vswh(2)" )
			)
			( pin "EU4G1.31"
				( objectStatus "@baseboard_fab2_lib.baseboard_fab2(sch_1):page233_i225:vswh(3)" )
			)
			( pin "EU4G1.32"
				( objectStatus "@baseboard_fab2_lib.baseboard_fab2(sch_1):page233_i225:vswh(4)" )
			)
			( pin "EU4G1.33"
				( objectStatus "@baseboard_fab2_lib.baseboard_fab2(sch_1):page233_i225:vswh(5)" )
			)
			( pin "EU4G1.34"
				( objectStatus "@baseboard_fab2_lib.baseboard_fab2(sch_1):page233_i225:vswh(6)" )
			)
			( pin "EU4G1.43"
				( objectStatus "@baseboard_fab2_lib.baseboard_fab2(sch_1):page233_i225:vswh(7)" )
			)
			( pin "C6U5.1"
				( objectStatus "@baseboard_fab2_lib.baseboard_fab2(sch_1):page233_i242:a" )
			)
			( pin "C6U5.2"
				( objectStatus "@baseboard_fab2_lib.baseboard_fab2(sch_1):page233_i242:b" )
			)
			( pin "R4G12.1"
				( objectStatus "@baseboard_fab2_lib.baseboard_fab2(sch_1):page233_i247:a" )
			)
			( pin "R4G12.2"
				( objectStatus "@baseboard_fab2_lib.baseboard_fab2(sch_1):page233_i247:b" )
			)
			( pin "C6U4.1"
				( objectStatus "@baseboard_fab2_lib.baseboard_fab2(sch_1):page233_i248:a" )
			)
			( pin "C6U4.2"
				( objectStatus "@baseboard_fab2_lib.baseboard_fab2(sch_1):page233_i248:b" )
			)
			( pin "C4G2.1"
				( objectStatus "@baseboard_fab2_lib.baseboard_fab2(sch_1):page233_i253:a" )
			)
			( pin "C4G2.2"
				( objectStatus "@baseboard_fab2_lib.baseboard_fab2(sch_1):page233_i253:b" )
			)
			( pin "C6U7.1"
				( objectStatus "@baseboard_fab2_lib.baseboard_fab2(sch_1):page233_i254:a" )
			)
			( pin "C6U7.2"
				( objectStatus "@baseboard_fab2_lib.baseboard_fab2(sch_1):page233_i254:b" )
			)
			( pin "C6U8.1"
				( objectStatus "@baseboard_fab2_lib.baseboard_fab2(sch_1):page233_i255:a" )
			)
			( pin "C6U8.2"
				( objectStatus "@baseboard_fab2_lib.baseboard_fab2(sch_1):page233_i255:b" )
			)
			( pin "C4F11.1"
				( objectStatus "@baseboard_fab2_lib.baseboard_fab2(sch_1):page233_i256:a" )
			)
			( pin "C4F11.2"
				( objectStatus "@baseboard_fab2_lib.baseboard_fab2(sch_1):page233_i256:b" )
			)
			( pin "R4G10.1"
				( objectStatus "@baseboard_fab2_lib.baseboard_fab2(sch_1):page233_i266:a" )
			)
			( pin "R4G10.2"
				( objectStatus "@baseboard_fab2_lib.baseboard_fab2(sch_1):page233_i266:b" )
			)
			( pin "C4G11.1"
				( objectStatus "@baseboard_fab2_lib.baseboard_fab2(sch_1):page233_i267:a" )
			)
			( pin "C4G11.2"
				( objectStatus "@baseboard_fab2_lib.baseboard_fab2(sch_1):page233_i267:b" )
			)
			( pin "R4B4.1"
				( objectStatus "@baseboard_fab2_lib.baseboard_fab2(sch_1):page234_i227:a" )
			)
			( pin "R4B4.2"
				( objectStatus "@baseboard_fab2_lib.baseboard_fab2(sch_1):page234_i227:b" )
			)
			( pin "R4G7.1"
				( objectStatus "@baseboard_fab2_lib.baseboard_fab2(sch_1):page233_i270:a" )
			)
			( pin "R4G7.2"
				( objectStatus "@baseboard_fab2_lib.baseboard_fab2(sch_1):page233_i270:b" )
			)
			( pin "R4G8.1"
				( objectStatus "@baseboard_fab2_lib.baseboard_fab2(sch_1):page233_i271:a" )
			)
			( pin "R4G8.2"
				( objectStatus "@baseboard_fab2_lib.baseboard_fab2(sch_1):page233_i271:b" )
			)
			( pin "R4G13.1"
				( objectStatus "@baseboard_fab2_lib.baseboard_fab2(sch_1):page233_i272:a" )
			)
			( pin "R4G13.2"
				( objectStatus "@baseboard_fab2_lib.baseboard_fab2(sch_1):page233_i272:b" )
			)
			( pin "C4G6.1"
				( objectStatus "@baseboard_fab2_lib.baseboard_fab2(sch_1):page233_i273:a" )
			)
			( pin "C4G6.2"
				( objectStatus "@baseboard_fab2_lib.baseboard_fab2(sch_1):page233_i273:b" )
			)
			( pin "C4G10.1"
				( objectStatus "@baseboard_fab2_lib.baseboard_fab2(sch_1):page233_i274:a" )
			)
			( pin "C4G10.2"
				( objectStatus "@baseboard_fab2_lib.baseboard_fab2(sch_1):page233_i274:b" )
			)
			( pin "R4G4.1"
				( objectStatus "@baseboard_fab2_lib.baseboard_fab2(sch_1):page233_i275:a" )
			)
			( pin "R4G4.2"
				( objectStatus "@baseboard_fab2_lib.baseboard_fab2(sch_1):page233_i275:b" )
			)
			( pin "L4G1.1"
				( objectStatus "@baseboard_fab2_lib.baseboard_fab2(sch_1):page233_i277:ina" )
			)
			( pin "L4G1.2"
				( objectStatus "@baseboard_fab2_lib.baseboard_fab2(sch_1):page233_i277:inb" )
			)
			( pin "R4B14.1"
				( objectStatus "@baseboard_fab2_lib.baseboard_fab2(sch_1):page234_i29:a" )
			)
			( pin "R4B14.2"
				( objectStatus "@baseboard_fab2_lib.baseboard_fab2(sch_1):page234_i29:b" )
			)
			( pin "C3B2.1"
				( objectStatus "@baseboard_fab2_lib.baseboard_fab2(sch_1):page234_i84:a" )
			)
			( pin "C3B2.2"
				( objectStatus "@baseboard_fab2_lib.baseboard_fab2(sch_1):page234_i84:b" )
			)
			( pin "C3A8.1"
				( objectStatus "@baseboard_fab2_lib.baseboard_fab2(sch_1):page234_i86:a" )
			)
			( pin "C3A8.2"
				( objectStatus "@baseboard_fab2_lib.baseboard_fab2(sch_1):page234_i86:b" )
			)
			( pin "C7L3.1"
				( objectStatus "@baseboard_fab2_lib.baseboard_fab2(sch_1):page234_i87:a" )
			)
			( pin "C7L3.2"
				( objectStatus "@baseboard_fab2_lib.baseboard_fab2(sch_1):page234_i87:b" )
			)
			( pin "C7L2.1"
				( objectStatus "@baseboard_fab2_lib.baseboard_fab2(sch_1):page234_i88:a" )
			)
			( pin "C7L2.2"
				( objectStatus "@baseboard_fab2_lib.baseboard_fab2(sch_1):page234_i88:b" )
			)
			( pin "C7L7.1"
				( objectStatus "@baseboard_fab2_lib.baseboard_fab2(sch_1):page234_i89:a" )
			)
			( pin "C7L7.2"
				( objectStatus "@baseboard_fab2_lib.baseboard_fab2(sch_1):page234_i89:b" )
			)
			( pin "C7L6.1"
				( objectStatus "@baseboard_fab2_lib.baseboard_fab2(sch_1):page234_i90:a" )
			)
			( pin "C7L6.2"
				( objectStatus "@baseboard_fab2_lib.baseboard_fab2(sch_1):page234_i90:b" )
			)
			( pin "C7M4.1"
				( objectStatus "@baseboard_fab2_lib.baseboard_fab2(sch_1):page234_i91:a" )
			)
			( pin "C7M4.2"
				( objectStatus "@baseboard_fab2_lib.baseboard_fab2(sch_1):page234_i91:b" )
			)
			( pin "C7M3.1"
				( objectStatus "@baseboard_fab2_lib.baseboard_fab2(sch_1):page234_i92:a" )
			)
			( pin "C7M3.2"
				( objectStatus "@baseboard_fab2_lib.baseboard_fab2(sch_1):page234_i92:b" )
			)
			( pin "C3A4.1"
				( objectStatus "@baseboard_fab2_lib.baseboard_fab2(sch_1):page234_i93:a" )
			)
			( pin "C3A4.2"
				( objectStatus "@baseboard_fab2_lib.baseboard_fab2(sch_1):page234_i93:b" )
			)
			( pin "C3B1.1"
				( objectStatus "@baseboard_fab2_lib.baseboard_fab2(sch_1):page234_i94:a" )
			)
			( pin "C3B1.2"
				( objectStatus "@baseboard_fab2_lib.baseboard_fab2(sch_1):page234_i94:b" )
			)
			( pin "C3A7.1"
				( objectStatus "@baseboard_fab2_lib.baseboard_fab2(sch_1):page234_i95:a" )
			)
			( pin "C3A7.2"
				( objectStatus "@baseboard_fab2_lib.baseboard_fab2(sch_1):page234_i95:b" )
			)
			( pin "C3A3.1"
				( objectStatus "@baseboard_fab2_lib.baseboard_fab2(sch_1):page234_i97:a" )
			)
			( pin "C3A3.2"
				( objectStatus "@baseboard_fab2_lib.baseboard_fab2(sch_1):page234_i97:b" )
			)
			( pin "C4B5.1"
				( objectStatus "@baseboard_fab2_lib.baseboard_fab2(sch_1):page234_i129:a" )
			)
			( pin "C4B5.2"
				( objectStatus "@baseboard_fab2_lib.baseboard_fab2(sch_1):page234_i129:b" )
			)
			( pin "C22W6.1"
				( objectStatus "@baseboard_fab2_lib.baseboard_fab2(sch_1):page233_i278:\1\" )
			)
			( pin "C22W6.2"
				( objectStatus "@baseboard_fab2_lib.baseboard_fab2(sch_1):page233_i278:\2\" )
			)
			( pin "C4B8.1"
				( objectStatus "@baseboard_fab2_lib.baseboard_fab2(sch_1):page234_i139:a" )
			)
			( pin "C4B8.2"
				( objectStatus "@baseboard_fab2_lib.baseboard_fab2(sch_1):page234_i139:b" )
			)
			( pin "R4B10.1"
				( objectStatus "@baseboard_fab2_lib.baseboard_fab2(sch_1):page234_i143:a" )
			)
			( pin "R4B10.2"
				( objectStatus "@baseboard_fab2_lib.baseboard_fab2(sch_1):page234_i143:b" )
			)
			( pin "C6L12.1"
				( objectStatus "@baseboard_fab2_lib.baseboard_fab2(sch_1):page234_i144:a" )
			)
			( pin "C6L12.2"
				( objectStatus "@baseboard_fab2_lib.baseboard_fab2(sch_1):page234_i144:b" )
			)
			( pin "C4B6.1"
				( objectStatus "@baseboard_fab2_lib.baseboard_fab2(sch_1):page234_i146:a" )
			)
			( pin "C4B6.2"
				( objectStatus "@baseboard_fab2_lib.baseboard_fab2(sch_1):page234_i146:b" )
			)
			( pin "C6L11.1"
				( objectStatus "@baseboard_fab2_lib.baseboard_fab2(sch_1):page234_i152:a" )
			)
			( pin "C6L11.2"
				( objectStatus "@baseboard_fab2_lib.baseboard_fab2(sch_1):page234_i152:b" )
			)
			( pin "FB4A1.1"
				( objectStatus "@baseboard_fab2_lib.baseboard_fab2(sch_1):page234_i154:a" )
			)
			( pin "FB4A1.2"
				( objectStatus "@baseboard_fab2_lib.baseboard_fab2(sch_1):page234_i154:b" )
			)
			( pin "R4G24.1"
				( objectStatus "@baseboard_fab2_lib.baseboard_fab2(sch_1):page233_i282:a" )
			)
			( pin "R4G24.2"
				( objectStatus "@baseboard_fab2_lib.baseboard_fab2(sch_1):page233_i282:b" )
			)
			( pin "R4A7.1"
				( objectStatus "@baseboard_fab2_lib.baseboard_fab2(sch_1):page234_i162:a" )
			)
			( pin "R4A7.2"
				( objectStatus "@baseboard_fab2_lib.baseboard_fab2(sch_1):page234_i162:b" )
			)
			( pin "C4A16.1"
				( objectStatus "@baseboard_fab2_lib.baseboard_fab2(sch_1):page234_i163:a" )
			)
			( pin "C4A16.2"
				( objectStatus "@baseboard_fab2_lib.baseboard_fab2(sch_1):page234_i163:b" )
			)
			( pin "L4A1.1"
				( objectStatus "@baseboard_fab2_lib.baseboard_fab2(sch_1):page234_i164:ina" )
			)
			( pin "L4A1.2"
				( objectStatus "@baseboard_fab2_lib.baseboard_fab2(sch_1):page234_i164:inb" )
			)
			( pin "C3B3.1"
				( objectStatus "@baseboard_fab2_lib.baseboard_fab2(sch_1):page234_i167:a" )
			)
			( pin "C3B3.2"
				( objectStatus "@baseboard_fab2_lib.baseboard_fab2(sch_1):page234_i167:b" )
			)
			( pin "C4B3.1"
				( objectStatus "@baseboard_fab2_lib.baseboard_fab2(sch_1):page234_i177:a" )
			)
			( pin "C4B3.2"
				( objectStatus "@baseboard_fab2_lib.baseboard_fab2(sch_1):page234_i177:b" )
			)
			( pin "C4B2.1"
				( objectStatus "@baseboard_fab2_lib.baseboard_fab2(sch_1):page234_i180:a" )
			)
			( pin "C4B2.2"
				( objectStatus "@baseboard_fab2_lib.baseboard_fab2(sch_1):page234_i180:b" )
			)
			( pin "C4B15.1"
				( objectStatus "@baseboard_fab2_lib.baseboard_fab2(sch_1):page234_i182:a" )
			)
			( pin "C4B15.2"
				( objectStatus "@baseboard_fab2_lib.baseboard_fab2(sch_1):page234_i182:b" )
			)
			( pin "R4B2.1"
				( objectStatus "@baseboard_fab2_lib.baseboard_fab2(sch_1):page234_i183:a" )
			)
			( pin "R4B2.2"
				( objectStatus "@baseboard_fab2_lib.baseboard_fab2(sch_1):page234_i183:b" )
			)
			( pin "EU4A3.5"
				( objectStatus "@baseboard_fab2_lib.baseboard_fab2(sch_1):page234_i184:agnd" )
			)
			( pin "EU4A3.36"
				( objectStatus "@baseboard_fab2_lib.baseboard_fab2(sch_1):page234_i184:bst" )
			)
			( pin "EU4A3.3"
				( objectStatus "@baseboard_fab2_lib.baseboard_fab2(sch_1):page234_i184:comp" )
			)
			( pin "EU4A3.40"
				( objectStatus "@baseboard_fab2_lib.baseboard_fab2(sch_1):page234_i184:en" )
			)
			( pin "EU4A3.2"
				( objectStatus "@baseboard_fab2_lib.baseboard_fab2(sch_1):page234_i184:fb" )
			)
			( pin "EU4A3.41"
				( objectStatus "@baseboard_fab2_lib.baseboard_fab2(sch_1):page234_i184:gnd" )
			)
			( pin "EU4A3.4"
				( objectStatus "@baseboard_fab2_lib.baseboard_fab2(sch_1):page234_i184:iset" )
			)
			( pin "EU4A3.6"
				( objectStatus "@baseboard_fab2_lib.baseboard_fab2(sch_1):page234_i184:ots" )
			)
			( pin "EU4A3.7"
				( objectStatus "@baseboard_fab2_lib.baseboard_fab2(sch_1):page234_i184:pg" )
			)
			( pin "EU4A3.16"
				( objectStatus "@baseboard_fab2_lib.baseboard_fab2(sch_1):page234_i184:pgnd(0)" )
			)
			( pin "EU4A3.17"
				( objectStatus "@baseboard_fab2_lib.baseboard_fab2(sch_1):page234_i184:pgnd(1)" )
			)
			( pin "EU4A3.18"
				( objectStatus "@baseboard_fab2_lib.baseboard_fab2(sch_1):page234_i184:pgnd(2)" )
			)
			( pin "EU4A3.19"
				( objectStatus "@baseboard_fab2_lib.baseboard_fab2(sch_1):page234_i184:pgnd(3)" )
			)
			( pin "EU4A3.20"
				( objectStatus "@baseboard_fab2_lib.baseboard_fab2(sch_1):page234_i184:pgnd(4)" )
			)
			( pin "EU4A3.21"
				( objectStatus "@baseboard_fab2_lib.baseboard_fab2(sch_1):page234_i184:pgnd(5)" )
			)
			( pin "EU4A3.22"
				( objectStatus "@baseboard_fab2_lib.baseboard_fab2(sch_1):page234_i184:pgnd(6)" )
			)
			( pin "EU4A3.23"
				( objectStatus "@baseboard_fab2_lib.baseboard_fab2(sch_1):page234_i184:pgnd(7)" )
			)
			( pin "EU4A3.24"
				( objectStatus "@baseboard_fab2_lib.baseboard_fab2(sch_1):page234_i184:pgnd(8)" )
			)
			( pin "EU4A3.25"
				( objectStatus "@baseboard_fab2_lib.baseboard_fab2(sch_1):page234_i184:pgnd(9)" )
			)
			( pin "EU4A3.26"
				( objectStatus "@baseboard_fab2_lib.baseboard_fab2(sch_1):page234_i184:pgnd(10)" )
			)
			( pin "EU4A3.27"
				( objectStatus "@baseboard_fab2_lib.baseboard_fab2(sch_1):page234_i184:pgnd(11)" )
			)
			( pin "EU4A3.28"
				( objectStatus "@baseboard_fab2_lib.baseboard_fab2(sch_1):page234_i184:pgnd(12)" )
			)
			( pin "EU4A3.37"
				( objectStatus "@baseboard_fab2_lib.baseboard_fab2(sch_1):page234_i184:pgnd(13)" )
			)
			( pin "EU4A3.1"
				( objectStatus "@baseboard_fab2_lib.baseboard_fab2(sch_1):page234_i184:ss" )
			)
			( pin "EU4A3.38"
				( objectStatus "@baseboard_fab2_lib.baseboard_fab2(sch_1):page234_i184:vb" )
			)
			( pin "EU4A3.39"
				( objectStatus "@baseboard_fab2_lib.baseboard_fab2(sch_1):page234_i184:vcc" )
			)
			( pin "EU4A3.8"
				( objectStatus "@baseboard_fab2_lib.baseboard_fab2(sch_1):page234_i184:vin(0)" )
			)
			( pin "EU4A3.9"
				( objectStatus "@baseboard_fab2_lib.baseboard_fab2(sch_1):page234_i184:vin(1)" )
			)
			( pin "EU4A3.10"
				( objectStatus "@baseboard_fab2_lib.baseboard_fab2(sch_1):page234_i184:vin(2)" )
			)
			( pin "EU4A3.11"
				( objectStatus "@baseboard_fab2_lib.baseboard_fab2(sch_1):page234_i184:vin(3)" )
			)
			( pin "EU4A3.12"
				( objectStatus "@baseboard_fab2_lib.baseboard_fab2(sch_1):page234_i184:vin(4)" )
			)
			( pin "EU4A3.13"
				( objectStatus "@baseboard_fab2_lib.baseboard_fab2(sch_1):page234_i184:vin(5)" )
			)
			( pin "EU4A3.14"
				( objectStatus "@baseboard_fab2_lib.baseboard_fab2(sch_1):page234_i184:vin(6)" )
			)
			( pin "EU4A3.42"
				( objectStatus "@baseboard_fab2_lib.baseboard_fab2(sch_1):page234_i184:vin(7)" )
			)
			( pin "EU4A3.35"
				( objectStatus "@baseboard_fab2_lib.baseboard_fab2(sch_1):page234_i184:vsw" )
			)
			( pin "EU4A3.15"
				( objectStatus "@baseboard_fab2_lib.baseboard_fab2(sch_1):page234_i184:vswh(0)" )
			)
			( pin "EU4A3.29"
				( objectStatus "@baseboard_fab2_lib.baseboard_fab2(sch_1):page234_i184:vswh(1)" )
			)
			( pin "EU4A3.30"
				( objectStatus "@baseboard_fab2_lib.baseboard_fab2(sch_1):page234_i184:vswh(2)" )
			)
			( pin "EU4A3.31"
				( objectStatus "@baseboard_fab2_lib.baseboard_fab2(sch_1):page234_i184:vswh(3)" )
			)
			( pin "EU4A3.32"
				( objectStatus "@baseboard_fab2_lib.baseboard_fab2(sch_1):page234_i184:vswh(4)" )
			)
			( pin "EU4A3.33"
				( objectStatus "@baseboard_fab2_lib.baseboard_fab2(sch_1):page234_i184:vswh(5)" )
			)
			( pin "EU4A3.34"
				( objectStatus "@baseboard_fab2_lib.baseboard_fab2(sch_1):page234_i184:vswh(6)" )
			)
			( pin "EU4A3.43"
				( objectStatus "@baseboard_fab2_lib.baseboard_fab2(sch_1):page234_i184:vswh(7)" )
			)
			( pin "C4A20.1"
				( objectStatus "@baseboard_fab2_lib.baseboard_fab2(sch_1):page234_i199:a" )
			)
			( pin "C4A20.2"
				( objectStatus "@baseboard_fab2_lib.baseboard_fab2(sch_1):page234_i199:b" )
			)
			( pin "R4B7.1"
				( objectStatus "@baseboard_fab2_lib.baseboard_fab2(sch_1):page234_i201:a" )
			)
			( pin "R4B7.2"
				( objectStatus "@baseboard_fab2_lib.baseboard_fab2(sch_1):page234_i201:b" )
			)
			( pin "C6L10.1"
				( objectStatus "@baseboard_fab2_lib.baseboard_fab2(sch_1):page234_i202:a" )
			)
			( pin "C6L10.2"
				( objectStatus "@baseboard_fab2_lib.baseboard_fab2(sch_1):page234_i202:b" )
			)
			( pin "C6M3.1"
				( objectStatus "@baseboard_fab2_lib.baseboard_fab2(sch_1):page234_i203:a" )
			)
			( pin "C6M3.2"
				( objectStatus "@baseboard_fab2_lib.baseboard_fab2(sch_1):page234_i203:b" )
			)
			( pin "C6M5.1"
				( objectStatus "@baseboard_fab2_lib.baseboard_fab2(sch_1):page234_i204:a" )
			)
			( pin "C6M5.2"
				( objectStatus "@baseboard_fab2_lib.baseboard_fab2(sch_1):page234_i204:b" )
			)
			( pin "C4A19.1"
				( objectStatus "@baseboard_fab2_lib.baseboard_fab2(sch_1):page234_i205:a" )
			)
			( pin "C4A19.2"
				( objectStatus "@baseboard_fab2_lib.baseboard_fab2(sch_1):page234_i205:b" )
			)
			( pin "C6L8.1"
				( objectStatus "@baseboard_fab2_lib.baseboard_fab2(sch_1):page234_i210:a" )
			)
			( pin "C6L8.2"
				( objectStatus "@baseboard_fab2_lib.baseboard_fab2(sch_1):page234_i210:b" )
			)
			( pin "C4B9.1"
				( objectStatus "@baseboard_fab2_lib.baseboard_fab2(sch_1):page234_i211:a" )
			)
			( pin "C4B9.2"
				( objectStatus "@baseboard_fab2_lib.baseboard_fab2(sch_1):page234_i211:b" )
			)
			( pin "C4B4.1"
				( objectStatus "@baseboard_fab2_lib.baseboard_fab2(sch_1):page234_i212:a" )
			)
			( pin "C4B4.2"
				( objectStatus "@baseboard_fab2_lib.baseboard_fab2(sch_1):page234_i212:b" )
			)
			( pin "R4B8.1"
				( objectStatus "@baseboard_fab2_lib.baseboard_fab2(sch_1):page234_i213:a" )
			)
			( pin "R4B8.2"
				( objectStatus "@baseboard_fab2_lib.baseboard_fab2(sch_1):page234_i213:b" )
			)
			( pin "R4B3.1"
				( objectStatus "@baseboard_fab2_lib.baseboard_fab2(sch_1):page234_i214:a" )
			)
			( pin "R4B3.2"
				( objectStatus "@baseboard_fab2_lib.baseboard_fab2(sch_1):page234_i214:b" )
			)
			( pin "R4B5.1"
				( objectStatus "@baseboard_fab2_lib.baseboard_fab2(sch_1):page234_i215:a" )
			)
			( pin "R4B5.2"
				( objectStatus "@baseboard_fab2_lib.baseboard_fab2(sch_1):page234_i215:b" )
			)
			( pin "C4B7.1"
				( objectStatus "@baseboard_fab2_lib.baseboard_fab2(sch_1):page234_i218:a" )
			)
			( pin "C4B7.2"
				( objectStatus "@baseboard_fab2_lib.baseboard_fab2(sch_1):page234_i218:b" )
			)
			( pin "R4B9.1"
				( objectStatus "@baseboard_fab2_lib.baseboard_fab2(sch_1):page234_i219:a" )
			)
			( pin "R4B9.2"
				( objectStatus "@baseboard_fab2_lib.baseboard_fab2(sch_1):page234_i219:b" )
			)
			( pin "R4B1.1"
				( objectStatus "@baseboard_fab2_lib.baseboard_fab2(sch_1):page234_i220:a" )
			)
			( pin "R4B1.2"
				( objectStatus "@baseboard_fab2_lib.baseboard_fab2(sch_1):page234_i220:b" )
			)
			( pin "C8A7.1"
				( objectStatus "@baseboard_fab2_lib.baseboard_fab2(sch_1):page235_i143:a" )
			)
			( pin "C8A7.2"
				( objectStatus "@baseboard_fab2_lib.baseboard_fab2(sch_1):page235_i143:b" )
			)
			( pin "C8A8.1"
				( objectStatus "@baseboard_fab2_lib.baseboard_fab2(sch_1):page235_i145:a" )
			)
			( pin "C8A8.2"
				( objectStatus "@baseboard_fab2_lib.baseboard_fab2(sch_1):page235_i145:b" )
			)
			( pin "R2L16.1"
				( objectStatus "@baseboard_fab2_lib.baseboard_fab2(sch_1):page235_i147:a" )
			)
			( pin "R2L16.2"
				( objectStatus "@baseboard_fab2_lib.baseboard_fab2(sch_1):page235_i147:b" )
			)
			( pin "R2L24.1"
				( objectStatus "@baseboard_fab2_lib.baseboard_fab2(sch_1):page235_i148:a" )
			)
			( pin "R2L24.2"
				( objectStatus "@baseboard_fab2_lib.baseboard_fab2(sch_1):page235_i148:b" )
			)
			( pin "R8A6.1"
				( objectStatus "@baseboard_fab2_lib.baseboard_fab2(sch_1):page235_i149:a" )
			)
			( pin "R8A6.2"
				( objectStatus "@baseboard_fab2_lib.baseboard_fab2(sch_1):page235_i149:b" )
			)
			( pin "C2L8.1"
				( objectStatus "@baseboard_fab2_lib.baseboard_fab2(sch_1):page235_i151:a" )
			)
			( pin "C2L8.2"
				( objectStatus "@baseboard_fab2_lib.baseboard_fab2(sch_1):page235_i151:b" )
			)
			( pin "C2L2.1"
				( objectStatus "@baseboard_fab2_lib.baseboard_fab2(sch_1):page235_i153:a" )
			)
			( pin "C2L2.2"
				( objectStatus "@baseboard_fab2_lib.baseboard_fab2(sch_1):page235_i153:b" )
			)
			( pin "R2L8.1"
				( objectStatus "@baseboard_fab2_lib.baseboard_fab2(sch_1):page235_i154:a" )
			)
			( pin "R2L8.2"
				( objectStatus "@baseboard_fab2_lib.baseboard_fab2(sch_1):page235_i154:b" )
			)
			( pin "R2L14.1"
				( objectStatus "@baseboard_fab2_lib.baseboard_fab2(sch_1):page235_i159:a" )
			)
			( pin "R2L14.2"
				( objectStatus "@baseboard_fab2_lib.baseboard_fab2(sch_1):page235_i159:b" )
			)
			( pin "R8A4.1"
				( objectStatus "@baseboard_fab2_lib.baseboard_fab2(sch_1):page235_i165:a" )
			)
			( pin "R8A4.2"
				( objectStatus "@baseboard_fab2_lib.baseboard_fab2(sch_1):page235_i165:b" )
			)
			( pin "R2L10.1"
				( objectStatus "@baseboard_fab2_lib.baseboard_fab2(sch_1):page235_i166:a" )
			)
			( pin "R2L10.2"
				( objectStatus "@baseboard_fab2_lib.baseboard_fab2(sch_1):page235_i166:b" )
			)
			( pin "C2L11.1"
				( objectStatus "@baseboard_fab2_lib.baseboard_fab2(sch_1):page235_i169:a" )
			)
			( pin "C2L11.2"
				( objectStatus "@baseboard_fab2_lib.baseboard_fab2(sch_1):page235_i169:b" )
			)
			( pin "C8A2.1"
				( objectStatus "@baseboard_fab2_lib.baseboard_fab2(sch_1):page235_i209:a" )
			)
			( pin "C8A2.2"
				( objectStatus "@baseboard_fab2_lib.baseboard_fab2(sch_1):page235_i209:b" )
			)
			( pin "R8A1.1"
				( objectStatus "@baseboard_fab2_lib.baseboard_fab2(sch_1):page235_i210:a" )
			)
			( pin "R8A1.2"
				( objectStatus "@baseboard_fab2_lib.baseboard_fab2(sch_1):page235_i210:b" )
			)
			( pin "R8A5.1"
				( objectStatus "@baseboard_fab2_lib.baseboard_fab2(sch_1):page235_i216:a" )
			)
			( pin "R8A5.2"
				( objectStatus "@baseboard_fab2_lib.baseboard_fab2(sch_1):page235_i216:b" )
			)
			( pin "R8A2.1"
				( objectStatus "@baseboard_fab2_lib.baseboard_fab2(sch_1):page235_i217:a" )
			)
			( pin "R8A2.2"
				( objectStatus "@baseboard_fab2_lib.baseboard_fab2(sch_1):page235_i217:b" )
			)
			( pin "C8A9.1"
				( objectStatus "@baseboard_fab2_lib.baseboard_fab2(sch_1):page235_i218:a" )
			)
			( pin "C8A9.2"
				( objectStatus "@baseboard_fab2_lib.baseboard_fab2(sch_1):page235_i218:b" )
			)
			( pin "R2L17.1"
				( objectStatus "@baseboard_fab2_lib.baseboard_fab2(sch_1):page235_i221:a" )
			)
			( pin "R2L17.2"
				( objectStatus "@baseboard_fab2_lib.baseboard_fab2(sch_1):page235_i221:b" )
			)
			( pin "R8A7.1"
				( objectStatus "@baseboard_fab2_lib.baseboard_fab2(sch_1):page235_i222:a" )
			)
			( pin "R8A7.2"
				( objectStatus "@baseboard_fab2_lib.baseboard_fab2(sch_1):page235_i222:b" )
			)
			( pin "EU8A1.21"
				( objectStatus "@baseboard_fab2_lib.baseboard_fab2(sch_1):page235_i229:airef1" )
			)
			( pin "EU8A1.22"
				( objectStatus "@baseboard_fab2_lib.baseboard_fab2(sch_1):page235_i229:aisen1" )
			)
			( pin "EU8A1.5"
				( objectStatus "@baseboard_fab2_lib.baseboard_fab2(sch_1):page235_i229:apwm1" )
			)
			( pin "EU8A1.35"
				( objectStatus "@baseboard_fab2_lib.baseboard_fab2(sch_1):page235_i229:atsen" )
			)
			( pin "EU8A1.20"
				( objectStatus "@baseboard_fab2_lib.baseboard_fab2(sch_1):page235_i229:avref" )
			)
			( pin "EU8A1.10"
				( objectStatus "@baseboard_fab2_lib.baseboard_fab2(sch_1):page235_i229:avren" )
			)
			( pin "EU8A1.9"
				( objectStatus "@baseboard_fab2_lib.baseboard_fab2(sch_1):page235_i229:avrrdy" )
			)
			( pin "EU8A1.19"
				( objectStatus "@baseboard_fab2_lib.baseboard_fab2(sch_1):page235_i229:avsen" )
			)
			( pin "EU8A1.25"
				( objectStatus "@baseboard_fab2_lib.baseboard_fab2(sch_1):page235_i229:biref1" )
			)
			( pin "EU8A1.26"
				( objectStatus "@baseboard_fab2_lib.baseboard_fab2(sch_1):page235_i229:bisen1" )
			)
			( pin "EU8A1.3"
				( objectStatus "@baseboard_fab2_lib.baseboard_fab2(sch_1):page235_i229:bpwm1" )
			)
			( pin "EU8A1.34"
				( objectStatus "@baseboard_fab2_lib.baseboard_fab2(sch_1):page235_i229:btsen" )
			)
			( pin "EU8A1.30"
				( objectStatus "@baseboard_fab2_lib.baseboard_fab2(sch_1):page235_i229:bvref" )
			)
			( pin "EU8A1.29"
				( objectStatus "@baseboard_fab2_lib.baseboard_fab2(sch_1):page235_i229:bvsen" )
			)
			( pin "EU8A1.1"
				( objectStatus "@baseboard_fab2_lib.baseboard_fab2(sch_1):page235_i229:dnc(0)" )
			)
			( pin "EU8A1.2"
				( objectStatus "@baseboard_fab2_lib.baseboard_fab2(sch_1):page235_i229:dnc(1)" )
			)
			( pin "EU8A1.4"
				( objectStatus "@baseboard_fab2_lib.baseboard_fab2(sch_1):page235_i229:dnc(2)" )
			)
			( pin "EU8A1.24"
				( objectStatus "@baseboard_fab2_lib.baseboard_fab2(sch_1):page235_i229:dnc(3)" )
			)
			( pin "EU8A1.28"
				( objectStatus "@baseboard_fab2_lib.baseboard_fab2(sch_1):page235_i229:dnc(4)" )
			)
			( pin "EU8A1.27"
				( objectStatus "@baseboard_fab2_lib.baseboard_fab2(sch_1):page235_i229:gnd(0)" )
			)
			( pin "EU8A1.23"
				( objectStatus "@baseboard_fab2_lib.baseboard_fab2(sch_1):page235_i229:gnd(1)" )
			)
			( pin "EU8A1.38"
				( objectStatus "@baseboard_fab2_lib.baseboard_fab2(sch_1):page235_i229:iinsen" )
			)
			( pin "EU8A1.13"
				( objectStatus "@baseboard_fab2_lib.baseboard_fab2(sch_1):page235_i229:mp0" )
			)
			( pin "EU8A1.14"
				( objectStatus "@baseboard_fab2_lib.baseboard_fab2(sch_1):page235_i229:mp1" )
			)
			( pin "EU8A1.18"
				( objectStatus "@baseboard_fab2_lib.baseboard_fab2(sch_1):page235_i229:mp2" )
			)
			( pin "EU8A1.31"
				( objectStatus "@baseboard_fab2_lib.baseboard_fab2(sch_1):page235_i229:mp3" )
			)
			( pin "EU8A1.32"
				( objectStatus "@baseboard_fab2_lib.baseboard_fab2(sch_1):page235_i229:mp4" )
			)
			( pin "EU8A1.12"
				( objectStatus "@baseboard_fab2_lib.baseboard_fab2(sch_1):page235_i229:pinalrt_n" )
			)
			( pin "EU8A1.8"
				( objectStatus "@baseboard_fab2_lib.baseboard_fab2(sch_1):page235_i229:reset_n" )
			)
			( pin "EU8A1.7"
				( objectStatus "@baseboard_fab2_lib.baseboard_fab2(sch_1):page235_i229:scl" )
			)
			( pin "EU8A1.6"
				( objectStatus "@baseboard_fab2_lib.baseboard_fab2(sch_1):page235_i229:sda" )
			)
			( pin "EU8A1.41"
				( objectStatus "@baseboard_fab2_lib.baseboard_fab2(sch_1):page235_i229:thpad" )
			)
			( pin "EU8A1.17"
				( objectStatus "@baseboard_fab2_lib.baseboard_fab2(sch_1):page235_i229:valrt_n" )
			)
			( pin "EU8A1.15"
				( objectStatus "@baseboard_fab2_lib.baseboard_fab2(sch_1):page235_i229:vclk" )
			)
			( pin "EU8A1.40"
				( objectStatus "@baseboard_fab2_lib.baseboard_fab2(sch_1):page235_i229:vd12" )
			)
			( pin "EU8A1.39"
				( objectStatus "@baseboard_fab2_lib.baseboard_fab2(sch_1):page235_i229:vdd" )
			)
			( pin "EU8A1.16"
				( objectStatus "@baseboard_fab2_lib.baseboard_fab2(sch_1):page235_i229:vdio" )
			)
			( pin "EU8A1.37"
				( objectStatus "@baseboard_fab2_lib.baseboard_fab2(sch_1):page235_i229:vinsen" )
			)
			( pin "EU8A1.11"
				( objectStatus "@baseboard_fab2_lib.baseboard_fab2(sch_1):page235_i229:vrhot_n" )
			)
			( pin "EU8A1.36"
				( objectStatus "@baseboard_fab2_lib.baseboard_fab2(sch_1):page235_i229:xaddr1" )
			)
			( pin "EU8A1.33"
				( objectStatus "@baseboard_fab2_lib.baseboard_fab2(sch_1):page235_i229:xaddr2" )
			)
			( pin "R2P8.1"
				( objectStatus "@baseboard_fab2_lib.baseboard_fab2(sch_1):page170_i75:a" )
			)
			( pin "R2P8.2"
				( objectStatus "@baseboard_fab2_lib.baseboard_fab2(sch_1):page170_i75:b" )
			)
			( pin "C7A30.1"
				( objectStatus "@baseboard_fab2_lib.baseboard_fab2(sch_1):page236_i9:a" )
			)
			( pin "C7A30.2"
				( objectStatus "@baseboard_fab2_lib.baseboard_fab2(sch_1):page236_i9:b" )
			)
			( pin "C7A8.1"
				( objectStatus "@baseboard_fab2_lib.baseboard_fab2(sch_1):page236_i16:a" )
			)
			( pin "C7A8.2"
				( objectStatus "@baseboard_fab2_lib.baseboard_fab2(sch_1):page236_i16:b" )
			)
			( pin "C4D6.1"
				( objectStatus "@baseboard_fab2_lib.baseboard_fab2(sch_1):page203_i133:\1\" )
			)
			( pin "C4D6.2"
				( objectStatus "@baseboard_fab2_lib.baseboard_fab2(sch_1):page203_i133:\2\" )
			)
			( pin "C7A6.1"
				( objectStatus "@baseboard_fab2_lib.baseboard_fab2(sch_1):page236_i19:a" )
			)
			( pin "C7A6.2"
				( objectStatus "@baseboard_fab2_lib.baseboard_fab2(sch_1):page236_i19:b" )
			)
			( pin "C7A39.1"
				( objectStatus "@baseboard_fab2_lib.baseboard_fab2(sch_1):page236_i20:a" )
			)
			( pin "C7A39.2"
				( objectStatus "@baseboard_fab2_lib.baseboard_fab2(sch_1):page236_i20:b" )
			)
			( pin "C7A43.1"
				( objectStatus "@baseboard_fab2_lib.baseboard_fab2(sch_1):page236_i21:a" )
			)
			( pin "C7A43.2"
				( objectStatus "@baseboard_fab2_lib.baseboard_fab2(sch_1):page236_i21:b" )
			)
			( pin "C7A7.1"
				( objectStatus "@baseboard_fab2_lib.baseboard_fab2(sch_1):page236_i22:a" )
			)
			( pin "C7A7.2"
				( objectStatus "@baseboard_fab2_lib.baseboard_fab2(sch_1):page236_i22:b" )
			)
			( pin "C3L12.1"
				( objectStatus "@baseboard_fab2_lib.baseboard_fab2(sch_1):page236_i23:a" )
			)
			( pin "C3L12.2"
				( objectStatus "@baseboard_fab2_lib.baseboard_fab2(sch_1):page236_i23:b" )
			)
			( pin "C3L11.1"
				( objectStatus "@baseboard_fab2_lib.baseboard_fab2(sch_1):page236_i24:a" )
			)
			( pin "C3L11.2"
				( objectStatus "@baseboard_fab2_lib.baseboard_fab2(sch_1):page236_i24:b" )
			)
			( pin "C3L8.1"
				( objectStatus "@baseboard_fab2_lib.baseboard_fab2(sch_1):page236_i26:a" )
			)
			( pin "C3L8.2"
				( objectStatus "@baseboard_fab2_lib.baseboard_fab2(sch_1):page236_i26:b" )
			)
			( pin "C3L9.1"
				( objectStatus "@baseboard_fab2_lib.baseboard_fab2(sch_1):page236_i29:a" )
			)
			( pin "C3L9.2"
				( objectStatus "@baseboard_fab2_lib.baseboard_fab2(sch_1):page236_i29:b" )
			)
			( pin "C3L7.1"
				( objectStatus "@baseboard_fab2_lib.baseboard_fab2(sch_1):page236_i31:a" )
			)
			( pin "C3L7.2"
				( objectStatus "@baseboard_fab2_lib.baseboard_fab2(sch_1):page236_i31:b" )
			)
			( pin "C3L10.1"
				( objectStatus "@baseboard_fab2_lib.baseboard_fab2(sch_1):page236_i32:a" )
			)
			( pin "C3L10.2"
				( objectStatus "@baseboard_fab2_lib.baseboard_fab2(sch_1):page236_i32:b" )
			)
			( pin "C7A9.1"
				( objectStatus "@baseboard_fab2_lib.baseboard_fab2(sch_1):page236_i33:a" )
			)
			( pin "C7A9.2"
				( objectStatus "@baseboard_fab2_lib.baseboard_fab2(sch_1):page236_i33:b" )
			)
			( pin "C7A44.1"
				( objectStatus "@baseboard_fab2_lib.baseboard_fab2(sch_1):page236_i34:a" )
			)
			( pin "C7A44.2"
				( objectStatus "@baseboard_fab2_lib.baseboard_fab2(sch_1):page236_i34:b" )
			)
			( pin "C7A40.1"
				( objectStatus "@baseboard_fab2_lib.baseboard_fab2(sch_1):page236_i35:a" )
			)
			( pin "C7A40.2"
				( objectStatus "@baseboard_fab2_lib.baseboard_fab2(sch_1):page236_i35:b" )
			)
			( pin "C7A10.1"
				( objectStatus "@baseboard_fab2_lib.baseboard_fab2(sch_1):page236_i36:a" )
			)
			( pin "C7A10.2"
				( objectStatus "@baseboard_fab2_lib.baseboard_fab2(sch_1):page236_i36:b" )
			)
			( pin "C4C4.1"
				( objectStatus "@baseboard_fab2_lib.baseboard_fab2(sch_1):page205_i83:\1\" )
			)
			( pin "C4C4.2"
				( objectStatus "@baseboard_fab2_lib.baseboard_fab2(sch_1):page205_i83:\2\" )
			)
			( pin "C7A41.1"
				( objectStatus "@baseboard_fab2_lib.baseboard_fab2(sch_1):page236_i39:a" )
			)
			( pin "C7A41.2"
				( objectStatus "@baseboard_fab2_lib.baseboard_fab2(sch_1):page236_i39:b" )
			)
			( pin "L4C1.2"
				( objectStatus "@baseboard_fab2_lib.baseboard_fab2(sch_1):page204_i105:f" )
			)
			( pin "L4C1.1"
				( objectStatus "@baseboard_fab2_lib.baseboard_fab2(sch_1):page204_i105:s" )
			)
			( pin "C7A42.1"
				( objectStatus "@baseboard_fab2_lib.baseboard_fab2(sch_1):page236_i46:a" )
			)
			( pin "C7A42.2"
				( objectStatus "@baseboard_fab2_lib.baseboard_fab2(sch_1):page236_i46:b" )
			)
			( pin "R8B14.1"
				( objectStatus "@baseboard_fab2_lib.baseboard_fab2(sch_1):page236_i56:a" )
			)
			( pin "R8B14.2"
				( objectStatus "@baseboard_fab2_lib.baseboard_fab2(sch_1):page236_i56:b" )
			)
			( pin "R8B15.1"
				( objectStatus "@baseboard_fab2_lib.baseboard_fab2(sch_1):page236_i57:a" )
			)
			( pin "R8B15.2"
				( objectStatus "@baseboard_fab2_lib.baseboard_fab2(sch_1):page236_i57:b" )
			)
			( pin "R8B12.1"
				( objectStatus "@baseboard_fab2_lib.baseboard_fab2(sch_1):page236_i59:a" )
			)
			( pin "R8B12.2"
				( objectStatus "@baseboard_fab2_lib.baseboard_fab2(sch_1):page236_i59:b" )
			)
			( pin "C22W32.1"
				( objectStatus "@baseboard_fab2_lib.baseboard_fab2(sch_1):page212_i126:\1\" )
			)
			( pin "C22W32.2"
				( objectStatus "@baseboard_fab2_lib.baseboard_fab2(sch_1):page212_i126:\2\" )
			)
			( pin "C22W33.1"
				( objectStatus "@baseboard_fab2_lib.baseboard_fab2(sch_1):page212_i124:\1\" )
			)
			( pin "C22W33.2"
				( objectStatus "@baseboard_fab2_lib.baseboard_fab2(sch_1):page212_i124:\2\" )
			)
			( pin "C3L18.1"
				( objectStatus "@baseboard_fab2_lib.baseboard_fab2(sch_1):page236_i71:a" )
			)
			( pin "C3L18.2"
				( objectStatus "@baseboard_fab2_lib.baseboard_fab2(sch_1):page236_i71:b" )
			)
			( pin "C3L20.1"
				( objectStatus "@baseboard_fab2_lib.baseboard_fab2(sch_1):page236_i73:a" )
			)
			( pin "C3L20.2"
				( objectStatus "@baseboard_fab2_lib.baseboard_fab2(sch_1):page236_i73:b" )
			)
			( pin "C3L21.1"
				( objectStatus "@baseboard_fab2_lib.baseboard_fab2(sch_1):page236_i74:a" )
			)
			( pin "C3L21.2"
				( objectStatus "@baseboard_fab2_lib.baseboard_fab2(sch_1):page236_i74:b" )
			)
			( pin "C7A27.1"
				( objectStatus "@baseboard_fab2_lib.baseboard_fab2(sch_1):page236_i75:a" )
			)
			( pin "C7A27.2"
				( objectStatus "@baseboard_fab2_lib.baseboard_fab2(sch_1):page236_i75:b" )
			)
			( pin "C3L19.1"
				( objectStatus "@baseboard_fab2_lib.baseboard_fab2(sch_1):page236_i76:a" )
			)
			( pin "C3L19.2"
				( objectStatus "@baseboard_fab2_lib.baseboard_fab2(sch_1):page236_i76:b" )
			)
			( pin "C2L46.1"
				( objectStatus "@baseboard_fab2_lib.baseboard_fab2(sch_1):page236_i77:a" )
			)
			( pin "C2L46.2"
				( objectStatus "@baseboard_fab2_lib.baseboard_fab2(sch_1):page236_i77:b" )
			)
			( pin "C8A15.1"
				( objectStatus "@baseboard_fab2_lib.baseboard_fab2(sch_1):page236_i78:a" )
			)
			( pin "C8A15.2"
				( objectStatus "@baseboard_fab2_lib.baseboard_fab2(sch_1):page236_i78:b" )
			)
			( pin "C2L25.1"
				( objectStatus "@baseboard_fab2_lib.baseboard_fab2(sch_1):page236_i79:a" )
			)
			( pin "C2L25.2"
				( objectStatus "@baseboard_fab2_lib.baseboard_fab2(sch_1):page236_i79:b" )
			)
			( pin "R7A13.1"
				( objectStatus "@baseboard_fab2_lib.baseboard_fab2(sch_1):page236_i90:a" )
			)
			( pin "R7A13.2"
				( objectStatus "@baseboard_fab2_lib.baseboard_fab2(sch_1):page236_i90:b" )
			)
			( pin "R7A18.1"
				( objectStatus "@baseboard_fab2_lib.baseboard_fab2(sch_1):page236_i92:a" )
			)
			( pin "R7A18.2"
				( objectStatus "@baseboard_fab2_lib.baseboard_fab2(sch_1):page236_i92:b" )
			)
			( pin "R7A19.1"
				( objectStatus "@baseboard_fab2_lib.baseboard_fab2(sch_1):page236_i93:a" )
			)
			( pin "R7A19.2"
				( objectStatus "@baseboard_fab2_lib.baseboard_fab2(sch_1):page236_i93:b" )
			)
			( pin "R7A14.1"
				( objectStatus "@baseboard_fab2_lib.baseboard_fab2(sch_1):page236_i94:a" )
			)
			( pin "R7A14.2"
				( objectStatus "@baseboard_fab2_lib.baseboard_fab2(sch_1):page236_i94:b" )
			)
			( pin "EU7A3.33"
				( objectStatus "@baseboard_fab2_lib.baseboard_fab2(sch_1):page236_i116:boost" )
			)
			( pin "EU7A3.35"
				( objectStatus "@baseboard_fab2_lib.baseboard_fab2(sch_1):page236_i116:en" )
			)
			( pin "EU7A3.6"
				( objectStatus "@baseboard_fab2_lib.baseboard_fab2(sch_1):page236_i116:gl(0)" )
			)
			( pin "EU7A3.41"
				( objectStatus "@baseboard_fab2_lib.baseboard_fab2(sch_1):page236_i116:gl(1)" )
			)
			( pin "EU7A3.38"
				( objectStatus "@baseboard_fab2_lib.baseboard_fab2(sch_1):page236_i116:iout" )
			)
			( pin "EU7A3.2"
				( objectStatus "@baseboard_fab2_lib.baseboard_fab2(sch_1):page236_i116:lgnd" )
			)
			( pin "EU7A3.31"
				( objectStatus "@baseboard_fab2_lib.baseboard_fab2(sch_1):page236_i116:nc" )
			)
			( pin "EU7A3.37"
				( objectStatus "@baseboard_fab2_lib.baseboard_fab2(sch_1):page236_i116:ocset" )
			)
			( pin "EU7A3.5"
				( objectStatus "@baseboard_fab2_lib.baseboard_fab2(sch_1):page236_i116:pgnd(0)" )
			)
			( pin "EU7A3.7"
				( objectStatus "@baseboard_fab2_lib.baseboard_fab2(sch_1):page236_i116:pgnd(1)" )
			)
			( pin "EU7A3.40"
				( objectStatus "@baseboard_fab2_lib.baseboard_fab2(sch_1):page236_i116:pgnd(2)" )
			)
			( pin "EU7A3.32"
				( objectStatus "@baseboard_fab2_lib.baseboard_fab2(sch_1):page236_i116:phase" )
			)
			( pin "EU7A3.34"
				( objectStatus "@baseboard_fab2_lib.baseboard_fab2(sch_1):page236_i116:pwm" )
			)
			( pin "EU7A3.39"
				( objectStatus "@baseboard_fab2_lib.baseboard_fab2(sch_1):page236_i116:refin" )
			)
			( pin "EU7A3.10"
				( objectStatus "@baseboard_fab2_lib.baseboard_fab2(sch_1):page236_i116:sw" )
			)
			( pin "EU7A3.36"
				( objectStatus "@baseboard_fab2_lib.baseboard_fab2(sch_1):page236_i116:tout_flt" )
			)
			( pin "EU7A3.3"
				( objectStatus "@baseboard_fab2_lib.baseboard_fab2(sch_1):page236_i116:vcc" )
			)
			( pin "EU7A3.4"
				( objectStatus "@baseboard_fab2_lib.baseboard_fab2(sch_1):page236_i116:vdrv" )
			)
			( pin "EU7A3.25"
				( objectStatus "@baseboard_fab2_lib.baseboard_fab2(sch_1):page236_i116:vin(0)" )
			)
			( pin "EU7A3.30"
				( objectStatus "@baseboard_fab2_lib.baseboard_fab2(sch_1):page236_i116:vin(1)" )
			)
			( pin "EU7A3.1"
				( objectStatus "@baseboard_fab2_lib.baseboard_fab2(sch_1):page236_i116:vos" )
			)
			( pin "EU7A2.33"
				( objectStatus "@baseboard_fab2_lib.baseboard_fab2(sch_1):page236_i117:boost" )
			)
			( pin "EU7A2.35"
				( objectStatus "@baseboard_fab2_lib.baseboard_fab2(sch_1):page236_i117:en" )
			)
			( pin "EU7A2.6"
				( objectStatus "@baseboard_fab2_lib.baseboard_fab2(sch_1):page236_i117:gl(0)" )
			)
			( pin "EU7A2.41"
				( objectStatus "@baseboard_fab2_lib.baseboard_fab2(sch_1):page236_i117:gl(1)" )
			)
			( pin "EU7A2.38"
				( objectStatus "@baseboard_fab2_lib.baseboard_fab2(sch_1):page236_i117:iout" )
			)
			( pin "EU7A2.2"
				( objectStatus "@baseboard_fab2_lib.baseboard_fab2(sch_1):page236_i117:lgnd" )
			)
			( pin "EU7A2.31"
				( objectStatus "@baseboard_fab2_lib.baseboard_fab2(sch_1):page236_i117:nc" )
			)
			( pin "EU7A2.37"
				( objectStatus "@baseboard_fab2_lib.baseboard_fab2(sch_1):page236_i117:ocset" )
			)
			( pin "EU7A2.5"
				( objectStatus "@baseboard_fab2_lib.baseboard_fab2(sch_1):page236_i117:pgnd(0)" )
			)
			( pin "EU7A2.7"
				( objectStatus "@baseboard_fab2_lib.baseboard_fab2(sch_1):page236_i117:pgnd(1)" )
			)
			( pin "EU7A2.40"
				( objectStatus "@baseboard_fab2_lib.baseboard_fab2(sch_1):page236_i117:pgnd(2)" )
			)
			( pin "EU7A2.32"
				( objectStatus "@baseboard_fab2_lib.baseboard_fab2(sch_1):page236_i117:phase" )
			)
			( pin "EU7A2.34"
				( objectStatus "@baseboard_fab2_lib.baseboard_fab2(sch_1):page236_i117:pwm" )
			)
			( pin "EU7A2.39"
				( objectStatus "@baseboard_fab2_lib.baseboard_fab2(sch_1):page236_i117:refin" )
			)
			( pin "EU7A2.10"
				( objectStatus "@baseboard_fab2_lib.baseboard_fab2(sch_1):page236_i117:sw" )
			)
			( pin "EU7A2.36"
				( objectStatus "@baseboard_fab2_lib.baseboard_fab2(sch_1):page236_i117:tout_flt" )
			)
			( pin "EU7A2.3"
				( objectStatus "@baseboard_fab2_lib.baseboard_fab2(sch_1):page236_i117:vcc" )
			)
			( pin "EU7A2.4"
				( objectStatus "@baseboard_fab2_lib.baseboard_fab2(sch_1):page236_i117:vdrv" )
			)
			( pin "EU7A2.25"
				( objectStatus "@baseboard_fab2_lib.baseboard_fab2(sch_1):page236_i117:vin(0)" )
			)
			( pin "EU7A2.30"
				( objectStatus "@baseboard_fab2_lib.baseboard_fab2(sch_1):page236_i117:vin(1)" )
			)
			( pin "EU7A2.1"
				( objectStatus "@baseboard_fab2_lib.baseboard_fab2(sch_1):page236_i117:vos" )
			)
			( pin "R3L15.1"
				( objectStatus "@baseboard_fab2_lib.baseboard_fab2(sch_1):page236_i118:a" )
			)
			( pin "R3L15.2"
				( objectStatus "@baseboard_fab2_lib.baseboard_fab2(sch_1):page236_i118:b" )
			)
			( pin "R3L14.1"
				( objectStatus "@baseboard_fab2_lib.baseboard_fab2(sch_1):page236_i120:a" )
			)
			( pin "R3L14.2"
				( objectStatus "@baseboard_fab2_lib.baseboard_fab2(sch_1):page236_i120:b" )
			)
			( pin "R8A10.1"
				( objectStatus "@baseboard_fab2_lib.baseboard_fab2(sch_1):page237_i3:a" )
			)
			( pin "R8A10.2"
				( objectStatus "@baseboard_fab2_lib.baseboard_fab2(sch_1):page237_i3:b" )
			)
			( pin "C8A11.1"
				( objectStatus "@baseboard_fab2_lib.baseboard_fab2(sch_1):page237_i5:a" )
			)
			( pin "C8A11.2"
				( objectStatus "@baseboard_fab2_lib.baseboard_fab2(sch_1):page237_i5:b" )
			)
			( pin "C2L45.1"
				( objectStatus "@baseboard_fab2_lib.baseboard_fab2(sch_1):page237_i12:a" )
			)
			( pin "C2L45.2"
				( objectStatus "@baseboard_fab2_lib.baseboard_fab2(sch_1):page237_i12:b" )
			)
			( pin "C8A14.1"
				( objectStatus "@baseboard_fab2_lib.baseboard_fab2(sch_1):page237_i13:a" )
			)
			( pin "C8A14.2"
				( objectStatus "@baseboard_fab2_lib.baseboard_fab2(sch_1):page237_i13:b" )
			)
			( pin "R8A12.1"
				( objectStatus "@baseboard_fab2_lib.baseboard_fab2(sch_1):page237_i15:a" )
			)
			( pin "R8A12.2"
				( objectStatus "@baseboard_fab2_lib.baseboard_fab2(sch_1):page237_i15:b" )
			)
			( pin "C8A6.1"
				( objectStatus "@baseboard_fab2_lib.baseboard_fab2(sch_1):page237_i29:a" )
			)
			( pin "C8A6.2"
				( objectStatus "@baseboard_fab2_lib.baseboard_fab2(sch_1):page237_i29:b" )
			)
			( pin "C8A4.1"
				( objectStatus "@baseboard_fab2_lib.baseboard_fab2(sch_1):page237_i31:a" )
			)
			( pin "C8A4.2"
				( objectStatus "@baseboard_fab2_lib.baseboard_fab2(sch_1):page237_i31:b" )
			)
			( pin "C8A10.1"
				( objectStatus "@baseboard_fab2_lib.baseboard_fab2(sch_1):page237_i55:a" )
			)
			( pin "C8A10.2"
				( objectStatus "@baseboard_fab2_lib.baseboard_fab2(sch_1):page237_i55:b" )
			)
			( pin "C8A12.1"
				( objectStatus "@baseboard_fab2_lib.baseboard_fab2(sch_1):page237_i77:a" )
			)
			( pin "C8A12.2"
				( objectStatus "@baseboard_fab2_lib.baseboard_fab2(sch_1):page237_i77:b" )
			)
			( pin "C2L32.1"
				( objectStatus "@baseboard_fab2_lib.baseboard_fab2(sch_1):page237_i79:a" )
			)
			( pin "C2L32.2"
				( objectStatus "@baseboard_fab2_lib.baseboard_fab2(sch_1):page237_i79:b" )
			)
			( pin "R2L19.1"
				( objectStatus "@baseboard_fab2_lib.baseboard_fab2(sch_1):page237_i80:a" )
			)
			( pin "R2L19.2"
				( objectStatus "@baseboard_fab2_lib.baseboard_fab2(sch_1):page237_i80:b" )
			)
			( pin "R2L20.1"
				( objectStatus "@baseboard_fab2_lib.baseboard_fab2(sch_1):page237_i81:a" )
			)
			( pin "R2L20.2"
				( objectStatus "@baseboard_fab2_lib.baseboard_fab2(sch_1):page237_i81:b" )
			)
			( pin "EU8A2.4"
				( objectStatus "@baseboard_fab2_lib.baseboard_fab2(sch_1):page237_i86:adj_nc" )
			)
			( pin "EU8A2.6"
				( objectStatus "@baseboard_fab2_lib.baseboard_fab2(sch_1):page237_i86:en" )
			)
			( pin "EU8A2.11"
				( objectStatus "@baseboard_fab2_lib.baseboard_fab2(sch_1):page237_i86:gnd" )
			)
			( pin "EU8A2.5"
				( objectStatus "@baseboard_fab2_lib.baseboard_fab2(sch_1):page237_i86:pgood" )
			)
			( pin "EU8A2.10"
				( objectStatus "@baseboard_fab2_lib.baseboard_fab2(sch_1):page237_i86:vdd" )
			)
			( pin "EU8A2.7"
				( objectStatus "@baseboard_fab2_lib.baseboard_fab2(sch_1):page237_i86:vin(0)" )
			)
			( pin "EU8A2.8"
				( objectStatus "@baseboard_fab2_lib.baseboard_fab2(sch_1):page237_i86:vin(1)" )
			)
			( pin "EU8A2.9"
				( objectStatus "@baseboard_fab2_lib.baseboard_fab2(sch_1):page237_i86:vin(2)" )
			)
			( pin "EU8A2.1"
				( objectStatus "@baseboard_fab2_lib.baseboard_fab2(sch_1):page237_i86:vout(0)" )
			)
			( pin "EU8A2.2"
				( objectStatus "@baseboard_fab2_lib.baseboard_fab2(sch_1):page237_i86:vout(1)" )
			)
			( pin "EU8A2.3"
				( objectStatus "@baseboard_fab2_lib.baseboard_fab2(sch_1):page237_i86:vout(2)" )
			)
			( pin "R8A11.1"
				( objectStatus "@baseboard_fab2_lib.baseboard_fab2(sch_1):page237_i90:a" )
			)
			( pin "R8A11.2"
				( objectStatus "@baseboard_fab2_lib.baseboard_fab2(sch_1):page237_i90:b" )
			)
			( pin "C9F9.1"
				( objectStatus "@baseboard_fab2_lib.baseboard_fab2(sch_1):page238_i5:a" )
			)
			( pin "C9F9.2"
				( objectStatus "@baseboard_fab2_lib.baseboard_fab2(sch_1):page238_i5:b" )
			)
			( pin "C9F3.1"
				( objectStatus "@baseboard_fab2_lib.baseboard_fab2(sch_1):page238_i7:a" )
			)
			( pin "C9F3.2"
				( objectStatus "@baseboard_fab2_lib.baseboard_fab2(sch_1):page238_i7:b" )
			)
			( pin "R9F8.1"
				( objectStatus "@baseboard_fab2_lib.baseboard_fab2(sch_1):page238_i14:a" )
			)
			( pin "R9F8.2"
				( objectStatus "@baseboard_fab2_lib.baseboard_fab2(sch_1):page238_i14:b" )
			)
			( pin "C9F8.1"
				( objectStatus "@baseboard_fab2_lib.baseboard_fab2(sch_1):page238_i19:a" )
			)
			( pin "C9F8.2"
				( objectStatus "@baseboard_fab2_lib.baseboard_fab2(sch_1):page238_i19:b" )
			)
			( pin "R9F13.1"
				( objectStatus "@baseboard_fab2_lib.baseboard_fab2(sch_1):page238_i21:a" )
			)
			( pin "R9F13.2"
				( objectStatus "@baseboard_fab2_lib.baseboard_fab2(sch_1):page238_i21:b" )
			)
			( pin "C9E10.1"
				( objectStatus "@baseboard_fab2_lib.baseboard_fab2(sch_1):page238_i23:a" )
			)
			( pin "C9E10.2"
				( objectStatus "@baseboard_fab2_lib.baseboard_fab2(sch_1):page238_i23:b" )
			)
			( pin "C9F4.1"
				( objectStatus "@baseboard_fab2_lib.baseboard_fab2(sch_1):page238_i30:a" )
			)
			( pin "C9F4.2"
				( objectStatus "@baseboard_fab2_lib.baseboard_fab2(sch_1):page238_i30:b" )
			)
			( pin "C9E11.1"
				( objectStatus "@baseboard_fab2_lib.baseboard_fab2(sch_1):page238_i39:a" )
			)
			( pin "C9E11.2"
				( objectStatus "@baseboard_fab2_lib.baseboard_fab2(sch_1):page238_i39:b" )
			)
			( pin "EU9F1.4"
				( objectStatus "@baseboard_fab2_lib.baseboard_fab2(sch_1):page238_i40:adj_nc" )
			)
			( pin "EU9F1.6"
				( objectStatus "@baseboard_fab2_lib.baseboard_fab2(sch_1):page238_i40:en" )
			)
			( pin "EU9F1.11"
				( objectStatus "@baseboard_fab2_lib.baseboard_fab2(sch_1):page238_i40:gnd" )
			)
			( pin "EU9F1.5"
				( objectStatus "@baseboard_fab2_lib.baseboard_fab2(sch_1):page238_i40:pgood" )
			)
			( pin "EU9F1.10"
				( objectStatus "@baseboard_fab2_lib.baseboard_fab2(sch_1):page238_i40:vdd" )
			)
			( pin "EU9F1.7"
				( objectStatus "@baseboard_fab2_lib.baseboard_fab2(sch_1):page238_i40:vin(0)" )
			)
			( pin "EU9F1.8"
				( objectStatus "@baseboard_fab2_lib.baseboard_fab2(sch_1):page238_i40:vin(1)" )
			)
			( pin "EU9F1.9"
				( objectStatus "@baseboard_fab2_lib.baseboard_fab2(sch_1):page238_i40:vin(2)" )
			)
			( pin "EU9F1.1"
				( objectStatus "@baseboard_fab2_lib.baseboard_fab2(sch_1):page238_i40:vout(0)" )
			)
			( pin "EU9F1.2"
				( objectStatus "@baseboard_fab2_lib.baseboard_fab2(sch_1):page238_i40:vout(1)" )
			)
			( pin "EU9F1.3"
				( objectStatus "@baseboard_fab2_lib.baseboard_fab2(sch_1):page238_i40:vout(2)" )
			)
			( pin "R9F11.1"
				( objectStatus "@baseboard_fab2_lib.baseboard_fab2(sch_1):page238_i41:a" )
			)
			( pin "R9F11.2"
				( objectStatus "@baseboard_fab2_lib.baseboard_fab2(sch_1):page238_i41:b" )
			)
			( pin "C9F10.1"
				( objectStatus "@baseboard_fab2_lib.baseboard_fab2(sch_1):page239_i4:a" )
			)
			( pin "C9F10.2"
				( objectStatus "@baseboard_fab2_lib.baseboard_fab2(sch_1):page239_i4:b" )
			)
			( pin "R9F12.1"
				( objectStatus "@baseboard_fab2_lib.baseboard_fab2(sch_1):page239_i6:a" )
			)
			( pin "R9F12.2"
				( objectStatus "@baseboard_fab2_lib.baseboard_fab2(sch_1):page239_i6:b" )
			)
			( pin "C9F13.1"
				( objectStatus "@baseboard_fab2_lib.baseboard_fab2(sch_1):page239_i7:a" )
			)
			( pin "C9F13.2"
				( objectStatus "@baseboard_fab2_lib.baseboard_fab2(sch_1):page239_i7:b" )
			)
			( pin "C1T15.1"
				( objectStatus "@baseboard_fab2_lib.baseboard_fab2(sch_1):page239_i12:a" )
			)
			( pin "C1T15.2"
				( objectStatus "@baseboard_fab2_lib.baseboard_fab2(sch_1):page239_i12:b" )
			)
			( pin "R9F6.1"
				( objectStatus "@baseboard_fab2_lib.baseboard_fab2(sch_1):page238_i45:\1\" )
			)
			( pin "R9F6.2"
				( objectStatus "@baseboard_fab2_lib.baseboard_fab2(sch_1):page238_i45:\2\" )
			)
			( pin "C1T7.1"
				( objectStatus "@baseboard_fab2_lib.baseboard_fab2(sch_1):page239_i22:a" )
			)
			( pin "C1T7.2"
				( objectStatus "@baseboard_fab2_lib.baseboard_fab2(sch_1):page239_i22:b" )
			)
			( pin "C9F6.1"
				( objectStatus "@baseboard_fab2_lib.baseboard_fab2(sch_1):page239_i30:a" )
			)
			( pin "C9F6.2"
				( objectStatus "@baseboard_fab2_lib.baseboard_fab2(sch_1):page239_i30:b" )
			)
			( pin "EU9F2.4"
				( objectStatus "@baseboard_fab2_lib.baseboard_fab2(sch_1):page239_i70:adj_nc" )
			)
			( pin "EU9F2.6"
				( objectStatus "@baseboard_fab2_lib.baseboard_fab2(sch_1):page239_i70:en" )
			)
			( pin "EU9F2.11"
				( objectStatus "@baseboard_fab2_lib.baseboard_fab2(sch_1):page239_i70:gnd" )
			)
			( pin "EU9F2.5"
				( objectStatus "@baseboard_fab2_lib.baseboard_fab2(sch_1):page239_i70:pgood" )
			)
			( pin "EU9F2.10"
				( objectStatus "@baseboard_fab2_lib.baseboard_fab2(sch_1):page239_i70:vdd" )
			)
			( pin "EU9F2.7"
				( objectStatus "@baseboard_fab2_lib.baseboard_fab2(sch_1):page239_i70:vin(0)" )
			)
			( pin "EU9F2.8"
				( objectStatus "@baseboard_fab2_lib.baseboard_fab2(sch_1):page239_i70:vin(1)" )
			)
			( pin "EU9F2.9"
				( objectStatus "@baseboard_fab2_lib.baseboard_fab2(sch_1):page239_i70:vin(2)" )
			)
			( pin "EU9F2.1"
				( objectStatus "@baseboard_fab2_lib.baseboard_fab2(sch_1):page239_i70:vout(0)" )
			)
			( pin "EU9F2.2"
				( objectStatus "@baseboard_fab2_lib.baseboard_fab2(sch_1):page239_i70:vout(1)" )
			)
			( pin "EU9F2.3"
				( objectStatus "@baseboard_fab2_lib.baseboard_fab2(sch_1):page239_i70:vout(2)" )
			)
			( pin "C9F5.1"
				( objectStatus "@baseboard_fab2_lib.baseboard_fab2(sch_1):page239_i71:a" )
			)
			( pin "C9F5.2"
				( objectStatus "@baseboard_fab2_lib.baseboard_fab2(sch_1):page239_i71:b" )
			)
			( pin "R1T9.1"
				( objectStatus "@baseboard_fab2_lib.baseboard_fab2(sch_1):page239_i72:a" )
			)
			( pin "R1T9.2"
				( objectStatus "@baseboard_fab2_lib.baseboard_fab2(sch_1):page239_i72:b" )
			)
			( pin "R7B14.1"
				( objectStatus "@baseboard_fab2_lib.baseboard_fab2(sch_1):page232_i315:a" )
			)
			( pin "R7B14.2"
				( objectStatus "@baseboard_fab2_lib.baseboard_fab2(sch_1):page232_i315:b" )
			)
			( pin "C9B9.1"
				( objectStatus "@baseboard_fab2_lib.baseboard_fab2(sch_1):page186_i357:\1\" )
			)
			( pin "C9B9.2"
				( objectStatus "@baseboard_fab2_lib.baseboard_fab2(sch_1):page186_i357:\2\" )
			)
			( pin "R8F1.1"
				( objectStatus "@baseboard_fab2_lib.baseboard_fab2(sch_1):page240_i111:a" )
			)
			( pin "R8F1.2"
				( objectStatus "@baseboard_fab2_lib.baseboard_fab2(sch_1):page240_i111:b" )
			)
			( pin "C8E17.1"
				( objectStatus "@baseboard_fab2_lib.baseboard_fab2(sch_1):page240_i113:a" )
			)
			( pin "C8E17.2"
				( objectStatus "@baseboard_fab2_lib.baseboard_fab2(sch_1):page240_i113:b" )
			)
			( pin "C8F2.1"
				( objectStatus "@baseboard_fab2_lib.baseboard_fab2(sch_1):page240_i116:a" )
			)
			( pin "C8F2.2"
				( objectStatus "@baseboard_fab2_lib.baseboard_fab2(sch_1):page240_i116:b" )
			)
			( pin "R8F5.1"
				( objectStatus "@baseboard_fab2_lib.baseboard_fab2(sch_1):page240_i117:a" )
			)
			( pin "R8F5.2"
				( objectStatus "@baseboard_fab2_lib.baseboard_fab2(sch_1):page240_i117:b" )
			)
			( pin "EU8F1.4"
				( objectStatus "@baseboard_fab2_lib.baseboard_fab2(sch_1):page240_i125:boot" )
			)
			( pin "EU8F1.10"
				( objectStatus "@baseboard_fab2_lib.baseboard_fab2(sch_1):page240_i125:cs" )
			)
			( pin "EU8F1.8"
				( objectStatus "@baseboard_fab2_lib.baseboard_fab2(sch_1):page240_i125:en" )
			)
			( pin "EU8F1.11"
				( objectStatus "@baseboard_fab2_lib.baseboard_fab2(sch_1):page240_i125:g0" )
			)
			( pin "EU8F1.12"
				( objectStatus "@baseboard_fab2_lib.baseboard_fab2(sch_1):page240_i125:gnd(0)" )
			)
			( pin "EU8F1.13"
				( objectStatus "@baseboard_fab2_lib.baseboard_fab2(sch_1):page240_i125:gnd(1)" )
			)
			( pin "EU8F1.1"
				( objectStatus "@baseboard_fab2_lib.baseboard_fab2(sch_1):page240_i125:lgate" )
			)
			( pin "EU8F1.9"
				( objectStatus "@baseboard_fab2_lib.baseboard_fab2(sch_1):page240_i125:pgood" )
			)
			( pin "EU8F1.2"
				( objectStatus "@baseboard_fab2_lib.baseboard_fab2(sch_1):page240_i125:phase" )
			)
			( pin "EU8F1.7"
				( objectStatus "@baseboard_fab2_lib.baseboard_fab2(sch_1):page240_i125:rgnd" )
			)
			( pin "EU8F1.3"
				( objectStatus "@baseboard_fab2_lib.baseboard_fab2(sch_1):page240_i125:ugate" )
			)
			( pin "EU8F1.5"
				( objectStatus "@baseboard_fab2_lib.baseboard_fab2(sch_1):page240_i125:vcc" )
			)
			( pin "EU8F1.6"
				( objectStatus "@baseboard_fab2_lib.baseboard_fab2(sch_1):page240_i125:vout" )
			)
			( pin "R8E35.1"
				( objectStatus "@baseboard_fab2_lib.baseboard_fab2(sch_1):page240_i127:a" )
			)
			( pin "R8E35.2"
				( objectStatus "@baseboard_fab2_lib.baseboard_fab2(sch_1):page240_i127:b" )
			)
			( pin "C8E12.1"
				( objectStatus "@baseboard_fab2_lib.baseboard_fab2(sch_1):page240_i129:a" )
			)
			( pin "C8E12.2"
				( objectStatus "@baseboard_fab2_lib.baseboard_fab2(sch_1):page240_i129:b" )
			)
			( pin "U1W3.5"
				( objectStatus "@baseboard_fab2_lib.baseboard_fab2(sch_1):page176_i162:en" )
			)
			( pin "U1W3.2"
				( objectStatus "@baseboard_fab2_lib.baseboard_fab2(sch_1):page176_i162:scla" )
			)
			( pin "U1W3.7"
				( objectStatus "@baseboard_fab2_lib.baseboard_fab2(sch_1):page176_i162:sclb" )
			)
			( pin "U1W3.3"
				( objectStatus "@baseboard_fab2_lib.baseboard_fab2(sch_1):page176_i162:sdaa" )
			)
			( pin "U1W3.6"
				( objectStatus "@baseboard_fab2_lib.baseboard_fab2(sch_1):page176_i162:sdab" )
			)
			( pin "U1W3.1"
				( objectStatus "@baseboard_fab2_lib.baseboard_fab2(sch_1):page176_i162:vcca" )
			)
			( pin "U1W3.8"
				( objectStatus "@baseboard_fab2_lib.baseboard_fab2(sch_1):page176_i162:vccb" )
			)
			( pin "C22W13.1"
				( objectStatus "@baseboard_fab2_lib.baseboard_fab2(sch_1):page214_i149:\1\" )
			)
			( pin "C22W13.2"
				( objectStatus "@baseboard_fab2_lib.baseboard_fab2(sch_1):page214_i149:\2\" )
			)
			( pin "C4E14.1"
				( objectStatus "@baseboard_fab2_lib.baseboard_fab2(sch_1):page214_i148:\1\" )
			)
			( pin "C4E14.2"
				( objectStatus "@baseboard_fab2_lib.baseboard_fab2(sch_1):page214_i148:\2\" )
			)
			( pin "C8E10.1"
				( objectStatus "@baseboard_fab2_lib.baseboard_fab2(sch_1):page240_i137:a" )
			)
			( pin "C8E10.2"
				( objectStatus "@baseboard_fab2_lib.baseboard_fab2(sch_1):page240_i137:b" )
			)
			( pin "C8E14.1"
				( objectStatus "@baseboard_fab2_lib.baseboard_fab2(sch_1):page240_i139:a" )
			)
			( pin "C8E14.2"
				( objectStatus "@baseboard_fab2_lib.baseboard_fab2(sch_1):page240_i139:b" )
			)
			( pin "R8E38.1"
				( objectStatus "@baseboard_fab2_lib.baseboard_fab2(sch_1):page240_i140:a" )
			)
			( pin "R8E38.2"
				( objectStatus "@baseboard_fab2_lib.baseboard_fab2(sch_1):page240_i140:b" )
			)
			( pin "R8E34.1"
				( objectStatus "@baseboard_fab2_lib.baseboard_fab2(sch_1):page240_i142:a" )
			)
			( pin "R8E34.2"
				( objectStatus "@baseboard_fab2_lib.baseboard_fab2(sch_1):page240_i142:b" )
			)
			( pin "R8E31.1"
				( objectStatus "@baseboard_fab2_lib.baseboard_fab2(sch_1):page240_i143:a" )
			)
			( pin "R8E31.2"
				( objectStatus "@baseboard_fab2_lib.baseboard_fab2(sch_1):page240_i143:b" )
			)
			( pin "R8E25.1"
				( objectStatus "@baseboard_fab2_lib.baseboard_fab2(sch_1):page240_i144:a" )
			)
			( pin "R8E25.2"
				( objectStatus "@baseboard_fab2_lib.baseboard_fab2(sch_1):page240_i144:b" )
			)
			( pin "R8F11.1"
				( objectStatus "@baseboard_fab2_lib.baseboard_fab2(sch_1):page240_i146:a" )
			)
			( pin "R8F11.2"
				( objectStatus "@baseboard_fab2_lib.baseboard_fab2(sch_1):page240_i146:b" )
			)
			( pin "R8F3.1"
				( objectStatus "@baseboard_fab2_lib.baseboard_fab2(sch_1):page240_i148:a" )
			)
			( pin "R8F3.2"
				( objectStatus "@baseboard_fab2_lib.baseboard_fab2(sch_1):page240_i148:b" )
			)
			( pin "R2T4.1"
				( objectStatus "@baseboard_fab2_lib.baseboard_fab2(sch_1):page240_i152:a" )
			)
			( pin "R2T4.2"
				( objectStatus "@baseboard_fab2_lib.baseboard_fab2(sch_1):page240_i152:b" )
			)
			( pin "C2T7.1"
				( objectStatus "@baseboard_fab2_lib.baseboard_fab2(sch_1):page240_i158:a" )
			)
			( pin "C2T7.2"
				( objectStatus "@baseboard_fab2_lib.baseboard_fab2(sch_1):page240_i158:b" )
			)
			( pin "C2T6.1"
				( objectStatus "@baseboard_fab2_lib.baseboard_fab2(sch_1):page240_i160:a" )
			)
			( pin "C2T6.2"
				( objectStatus "@baseboard_fab2_lib.baseboard_fab2(sch_1):page240_i160:b" )
			)
			( pin "C8F3.1"
				( objectStatus "@baseboard_fab2_lib.baseboard_fab2(sch_1):page240_i163:a" )
			)
			( pin "C8F3.2"
				( objectStatus "@baseboard_fab2_lib.baseboard_fab2(sch_1):page240_i163:b" )
			)
			( pin "EU8E1.4"
				( objectStatus "@baseboard_fab2_lib.baseboard_fab2(sch_1):page240_i170:bg" )
			)
			( pin "EU8E1.3"
				( objectStatus "@baseboard_fab2_lib.baseboard_fab2(sch_1):page240_i170:pgnd" )
			)
			( pin "EU8E1.1"
				( objectStatus "@baseboard_fab2_lib.baseboard_fab2(sch_1):page240_i170:tg" )
			)
			( pin "EU8E1.2"
				( objectStatus "@baseboard_fab2_lib.baseboard_fab2(sch_1):page240_i170:vin" )
			)
			( pin "EU8E1.5"
				( objectStatus "@baseboard_fab2_lib.baseboard_fab2(sch_1):page240_i170:vsw" )
			)
			( pin "R8F10.1"
				( objectStatus "@baseboard_fab2_lib.baseboard_fab2(sch_1):page240_i171:a" )
			)
			( pin "R8F10.2"
				( objectStatus "@baseboard_fab2_lib.baseboard_fab2(sch_1):page240_i171:b" )
			)
			( pin "R1L19.1"
				( objectStatus "@baseboard_fab2_lib.baseboard_fab2(sch_1):page175_i99:a" )
			)
			( pin "R1L19.2"
				( objectStatus "@baseboard_fab2_lib.baseboard_fab2(sch_1):page175_i99:b" )
			)
			( pin "C2T9.1"
				( objectStatus "@baseboard_fab2_lib.baseboard_fab2(sch_1):page240_i174:a" )
			)
			( pin "C2T9.2"
				( objectStatus "@baseboard_fab2_lib.baseboard_fab2(sch_1):page240_i174:b" )
			)
			( pin "R8F2.1"
				( objectStatus "@baseboard_fab2_lib.baseboard_fab2(sch_1):page240_i176:a" )
			)
			( pin "R8F2.2"
				( objectStatus "@baseboard_fab2_lib.baseboard_fab2(sch_1):page240_i176:b" )
			)
			( pin "R8E40.1"
				( objectStatus "@baseboard_fab2_lib.baseboard_fab2(sch_1):page240_i177:a" )
			)
			( pin "R8E40.2"
				( objectStatus "@baseboard_fab2_lib.baseboard_fab2(sch_1):page240_i177:b" )
			)
			( pin "C1A2.1"
				( objectStatus "@baseboard_fab2_lib.baseboard_fab2(sch_1):page227_i148:\1\" )
			)
			( pin "C1A2.2"
				( objectStatus "@baseboard_fab2_lib.baseboard_fab2(sch_1):page227_i148:\2\" )
			)
			( pin "C2R11.1"
				( objectStatus "@baseboard_fab2_lib.baseboard_fab2(sch_1):page240_i191:\1\" )
			)
			( pin "C2R11.2"
				( objectStatus "@baseboard_fab2_lib.baseboard_fab2(sch_1):page240_i191:\2\" )
			)
			( pin "R8E18.1"
				( objectStatus "@baseboard_fab2_lib.baseboard_fab2(sch_1):page241_i9:a" )
			)
			( pin "R8E18.2"
				( objectStatus "@baseboard_fab2_lib.baseboard_fab2(sch_1):page241_i9:b" )
			)
			( pin "R7E12.1"
				( objectStatus "@baseboard_fab2_lib.baseboard_fab2(sch_1):page241_i11:a" )
			)
			( pin "R7E12.2"
				( objectStatus "@baseboard_fab2_lib.baseboard_fab2(sch_1):page241_i11:b" )
			)
			( pin "C8E6.1"
				( objectStatus "@baseboard_fab2_lib.baseboard_fab2(sch_1):page241_i12:a" )
			)
			( pin "C8E6.2"
				( objectStatus "@baseboard_fab2_lib.baseboard_fab2(sch_1):page241_i12:b" )
			)
			( pin "C7E10.1"
				( objectStatus "@baseboard_fab2_lib.baseboard_fab2(sch_1):page241_i14:a" )
			)
			( pin "C7E10.2"
				( objectStatus "@baseboard_fab2_lib.baseboard_fab2(sch_1):page241_i14:b" )
			)
			( pin "R7E14.1"
				( objectStatus "@baseboard_fab2_lib.baseboard_fab2(sch_1):page241_i18:a" )
			)
			( pin "R7E14.2"
				( objectStatus "@baseboard_fab2_lib.baseboard_fab2(sch_1):page241_i18:b" )
			)
			( pin "C7E14.1"
				( objectStatus "@baseboard_fab2_lib.baseboard_fab2(sch_1):page241_i30:a" )
			)
			( pin "C7E14.2"
				( objectStatus "@baseboard_fab2_lib.baseboard_fab2(sch_1):page241_i30:b" )
			)
			( pin "R7E17.1"
				( objectStatus "@baseboard_fab2_lib.baseboard_fab2(sch_1):page241_i37:a" )
			)
			( pin "R7E17.2"
				( objectStatus "@baseboard_fab2_lib.baseboard_fab2(sch_1):page241_i37:b" )
			)
			( pin "C7E11.1"
				( objectStatus "@baseboard_fab2_lib.baseboard_fab2(sch_1):page241_i39:a" )
			)
			( pin "C7E11.2"
				( objectStatus "@baseboard_fab2_lib.baseboard_fab2(sch_1):page241_i39:b" )
			)
			( pin "C8E13.1"
				( objectStatus "@baseboard_fab2_lib.baseboard_fab2(sch_1):page241_i41:a" )
			)
			( pin "C8E13.2"
				( objectStatus "@baseboard_fab2_lib.baseboard_fab2(sch_1):page241_i41:b" )
			)
			( pin "C22W11.1"
				( objectStatus "@baseboard_fab2_lib.baseboard_fab2(sch_1):page240_i182:\1\" )
			)
			( pin "C22W11.2"
				( objectStatus "@baseboard_fab2_lib.baseboard_fab2(sch_1):page240_i182:\2\" )
			)
			( pin "R7F1.1"
				( objectStatus "@baseboard_fab2_lib.baseboard_fab2(sch_1):page241_i50:a" )
			)
			( pin "R7F1.2"
				( objectStatus "@baseboard_fab2_lib.baseboard_fab2(sch_1):page241_i50:b" )
			)
			( pin "R7E16.1"
				( objectStatus "@baseboard_fab2_lib.baseboard_fab2(sch_1):page241_i51:a" )
			)
			( pin "R7E16.2"
				( objectStatus "@baseboard_fab2_lib.baseboard_fab2(sch_1):page241_i51:b" )
			)
			( pin "C8E16.1"
				( objectStatus "@baseboard_fab2_lib.baseboard_fab2(sch_1):page241_i53:a" )
			)
			( pin "C8E16.2"
				( objectStatus "@baseboard_fab2_lib.baseboard_fab2(sch_1):page241_i53:b" )
			)
			( pin "R8E39.1"
				( objectStatus "@baseboard_fab2_lib.baseboard_fab2(sch_1):page241_i54:a" )
			)
			( pin "R8E39.2"
				( objectStatus "@baseboard_fab2_lib.baseboard_fab2(sch_1):page241_i54:b" )
			)
			( pin "C8F1.1"
				( objectStatus "@baseboard_fab2_lib.baseboard_fab2(sch_1):page241_i57:a" )
			)
			( pin "C8F1.2"
				( objectStatus "@baseboard_fab2_lib.baseboard_fab2(sch_1):page241_i57:b" )
			)
			( pin "R7E13.1"
				( objectStatus "@baseboard_fab2_lib.baseboard_fab2(sch_1):page241_i58:a" )
			)
			( pin "R7E13.2"
				( objectStatus "@baseboard_fab2_lib.baseboard_fab2(sch_1):page241_i58:b" )
			)
			( pin "C8E15.1"
				( objectStatus "@baseboard_fab2_lib.baseboard_fab2(sch_1):page241_i63:a" )
			)
			( pin "C8E15.2"
				( objectStatus "@baseboard_fab2_lib.baseboard_fab2(sch_1):page241_i63:b" )
			)
			( pin "R8E37.1"
				( objectStatus "@baseboard_fab2_lib.baseboard_fab2(sch_1):page241_i78:a" )
			)
			( pin "R8E37.2"
				( objectStatus "@baseboard_fab2_lib.baseboard_fab2(sch_1):page241_i78:b" )
			)
			( pin "FB7E1.1"
				( objectStatus "@baseboard_fab2_lib.baseboard_fab2(sch_1):page241_i82:a" )
			)
			( pin "FB7E1.2"
				( objectStatus "@baseboard_fab2_lib.baseboard_fab2(sch_1):page241_i82:b" )
			)
			( pin "EU7E2.13"
				( objectStatus "@baseboard_fab2_lib.baseboard_fab2(sch_1):page241_i83:boot" )
			)
			( pin "EU7E2.8"
				( objectStatus "@baseboard_fab2_lib.baseboard_fab2(sch_1):page241_i83:comp" )
			)
			( pin "EU7E2.10"
				( objectStatus "@baseboard_fab2_lib.baseboard_fab2(sch_1):page241_i83:en" )
			)
			( pin "EU7E2.2"
				( objectStatus "@baseboard_fab2_lib.baseboard_fab2(sch_1):page241_i83:gnd(0)" )
			)
			( pin "EU7E2.3"
				( objectStatus "@baseboard_fab2_lib.baseboard_fab2(sch_1):page241_i83:gnd(1)" )
			)
			( pin "EU7E2.11"
				( objectStatus "@baseboard_fab2_lib.baseboard_fab2(sch_1):page241_i83:ph(0)" )
			)
			( pin "EU7E2.12"
				( objectStatus "@baseboard_fab2_lib.baseboard_fab2(sch_1):page241_i83:ph(1)" )
			)
			( pin "EU7E2.4"
				( objectStatus "@baseboard_fab2_lib.baseboard_fab2(sch_1):page241_i83:pvin(0)" )
			)
			( pin "EU7E2.5"
				( objectStatus "@baseboard_fab2_lib.baseboard_fab2(sch_1):page241_i83:pvin(1)" )
			)
			( pin "EU7E2.14"
				( objectStatus "@baseboard_fab2_lib.baseboard_fab2(sch_1):page241_i83:pwrgd" )
			)
			( pin "EU7E2.1"
				( objectStatus "@baseboard_fab2_lib.baseboard_fab2(sch_1):page241_i83:rt_clk" )
			)
			( pin "EU7E2.9"
				( objectStatus "@baseboard_fab2_lib.baseboard_fab2(sch_1):page241_i83:ss_tr" )
			)
			( pin "EU7E2.15"
				( objectStatus "@baseboard_fab2_lib.baseboard_fab2(sch_1):page241_i83:thpad" )
			)
			( pin "EU7E2.6"
				( objectStatus "@baseboard_fab2_lib.baseboard_fab2(sch_1):page241_i83:vin" )
			)
			( pin "EU7E2.7"
				( objectStatus "@baseboard_fab2_lib.baseboard_fab2(sch_1):page241_i83:vsense" )
			)
			( pin "R7E15.1"
				( objectStatus "@baseboard_fab2_lib.baseboard_fab2(sch_1):page241_i89:a" )
			)
			( pin "R7E15.2"
				( objectStatus "@baseboard_fab2_lib.baseboard_fab2(sch_1):page241_i89:b" )
			)
			( pin "L8E1.1"
				( objectStatus "@baseboard_fab2_lib.baseboard_fab2(sch_1):page241_i90:ina" )
			)
			( pin "L8E1.2"
				( objectStatus "@baseboard_fab2_lib.baseboard_fab2(sch_1):page241_i90:inb" )
			)
			( pin "R8E33.1"
				( objectStatus "@baseboard_fab2_lib.baseboard_fab2(sch_1):page241_i91:a" )
			)
			( pin "R8E33.2"
				( objectStatus "@baseboard_fab2_lib.baseboard_fab2(sch_1):page241_i91:b" )
			)
			( pin "C5G106.1"
				( objectStatus "@baseboard_fab2_lib.baseboard_fab2(sch_1):page243_i88:a" )
			)
			( pin "C5G106.2"
				( objectStatus "@baseboard_fab2_lib.baseboard_fab2(sch_1):page243_i88:b" )
			)
			( pin "C5G107.1"
				( objectStatus "@baseboard_fab2_lib.baseboard_fab2(sch_1):page243_i87:a" )
			)
			( pin "C5G107.2"
				( objectStatus "@baseboard_fab2_lib.baseboard_fab2(sch_1):page243_i87:b" )
			)
			( pin "C5G108.1"
				( objectStatus "@baseboard_fab2_lib.baseboard_fab2(sch_1):page243_i86:a" )
			)
			( pin "C5G108.2"
				( objectStatus "@baseboard_fab2_lib.baseboard_fab2(sch_1):page243_i86:b" )
			)
			( pin "C5G109.1"
				( objectStatus "@baseboard_fab2_lib.baseboard_fab2(sch_1):page243_i85:a" )
			)
			( pin "C5G109.2"
				( objectStatus "@baseboard_fab2_lib.baseboard_fab2(sch_1):page243_i85:b" )
			)
			( pin "C5G110.1"
				( objectStatus "@baseboard_fab2_lib.baseboard_fab2(sch_1):page243_i84:a" )
			)
			( pin "C5G110.2"
				( objectStatus "@baseboard_fab2_lib.baseboard_fab2(sch_1):page243_i84:b" )
			)
			( pin "C5G111.1"
				( objectStatus "@baseboard_fab2_lib.baseboard_fab2(sch_1):page243_i83:a" )
			)
			( pin "C5G111.2"
				( objectStatus "@baseboard_fab2_lib.baseboard_fab2(sch_1):page243_i83:b" )
			)
			( pin "C5G112.1"
				( objectStatus "@baseboard_fab2_lib.baseboard_fab2(sch_1):page243_i82:a" )
			)
			( pin "C5G112.2"
				( objectStatus "@baseboard_fab2_lib.baseboard_fab2(sch_1):page243_i82:b" )
			)
			( pin "C5G113.1"
				( objectStatus "@baseboard_fab2_lib.baseboard_fab2(sch_1):page243_i81:a" )
			)
			( pin "C5G113.2"
				( objectStatus "@baseboard_fab2_lib.baseboard_fab2(sch_1):page243_i81:b" )
			)
			( pin "C5G117.1"
				( objectStatus "@baseboard_fab2_lib.baseboard_fab2(sch_1):page243_i92:a" )
			)
			( pin "C5G117.2"
				( objectStatus "@baseboard_fab2_lib.baseboard_fab2(sch_1):page243_i92:b" )
			)
			( pin "C5G114.1"
				( objectStatus "@baseboard_fab2_lib.baseboard_fab2(sch_1):page243_i80:a" )
			)
			( pin "C5G114.2"
				( objectStatus "@baseboard_fab2_lib.baseboard_fab2(sch_1):page243_i80:b" )
			)
			( pin "C5G97.1"
				( objectStatus "@baseboard_fab2_lib.baseboard_fab2(sch_1):page243_i79:a" )
			)
			( pin "C5G97.2"
				( objectStatus "@baseboard_fab2_lib.baseboard_fab2(sch_1):page243_i79:b" )
			)
			( pin "C5G98.1"
				( objectStatus "@baseboard_fab2_lib.baseboard_fab2(sch_1):page243_i78:a" )
			)
			( pin "C5G98.2"
				( objectStatus "@baseboard_fab2_lib.baseboard_fab2(sch_1):page243_i78:b" )
			)
			( pin "C5G99.1"
				( objectStatus "@baseboard_fab2_lib.baseboard_fab2(sch_1):page243_i77:a" )
			)
			( pin "C5G99.2"
				( objectStatus "@baseboard_fab2_lib.baseboard_fab2(sch_1):page243_i77:b" )
			)
			( pin "C5G100.1"
				( objectStatus "@baseboard_fab2_lib.baseboard_fab2(sch_1):page243_i76:a" )
			)
			( pin "C5G100.2"
				( objectStatus "@baseboard_fab2_lib.baseboard_fab2(sch_1):page243_i76:b" )
			)
			( pin "C5G101.1"
				( objectStatus "@baseboard_fab2_lib.baseboard_fab2(sch_1):page243_i75:a" )
			)
			( pin "C5G101.2"
				( objectStatus "@baseboard_fab2_lib.baseboard_fab2(sch_1):page243_i75:b" )
			)
			( pin "C5G102.1"
				( objectStatus "@baseboard_fab2_lib.baseboard_fab2(sch_1):page243_i74:a" )
			)
			( pin "C5G102.2"
				( objectStatus "@baseboard_fab2_lib.baseboard_fab2(sch_1):page243_i74:b" )
			)
			( pin "C5G105.1"
				( objectStatus "@baseboard_fab2_lib.baseboard_fab2(sch_1):page243_i73:a" )
			)
			( pin "C5G105.2"
				( objectStatus "@baseboard_fab2_lib.baseboard_fab2(sch_1):page243_i73:b" )
			)
			( pin "C5G104.1"
				( objectStatus "@baseboard_fab2_lib.baseboard_fab2(sch_1):page243_i72:a" )
			)
			( pin "C5G104.2"
				( objectStatus "@baseboard_fab2_lib.baseboard_fab2(sch_1):page243_i72:b" )
			)
			( pin "C5G103.1"
				( objectStatus "@baseboard_fab2_lib.baseboard_fab2(sch_1):page243_i71:a" )
			)
			( pin "C5G103.2"
				( objectStatus "@baseboard_fab2_lib.baseboard_fab2(sch_1):page243_i71:b" )
			)
			( pin "C5G88.1"
				( objectStatus "@baseboard_fab2_lib.baseboard_fab2(sch_1):page243_i70:a" )
			)
			( pin "C5G88.2"
				( objectStatus "@baseboard_fab2_lib.baseboard_fab2(sch_1):page243_i70:b" )
			)
			( pin "C5G89.1"
				( objectStatus "@baseboard_fab2_lib.baseboard_fab2(sch_1):page243_i69:a" )
			)
			( pin "C5G89.2"
				( objectStatus "@baseboard_fab2_lib.baseboard_fab2(sch_1):page243_i69:b" )
			)
			( pin "C5G90.1"
				( objectStatus "@baseboard_fab2_lib.baseboard_fab2(sch_1):page243_i68:a" )
			)
			( pin "C5G90.2"
				( objectStatus "@baseboard_fab2_lib.baseboard_fab2(sch_1):page243_i68:b" )
			)
			( pin "C5G91.1"
				( objectStatus "@baseboard_fab2_lib.baseboard_fab2(sch_1):page243_i67:a" )
			)
			( pin "C5G91.2"
				( objectStatus "@baseboard_fab2_lib.baseboard_fab2(sch_1):page243_i67:b" )
			)
			( pin "C5G92.1"
				( objectStatus "@baseboard_fab2_lib.baseboard_fab2(sch_1):page243_i66:a" )
			)
			( pin "C5G92.2"
				( objectStatus "@baseboard_fab2_lib.baseboard_fab2(sch_1):page243_i66:b" )
			)
			( pin "C5G118.1"
				( objectStatus "@baseboard_fab2_lib.baseboard_fab2(sch_1):page243_i91:a" )
			)
			( pin "C5G118.2"
				( objectStatus "@baseboard_fab2_lib.baseboard_fab2(sch_1):page243_i91:b" )
			)
			( pin "C5G93.1"
				( objectStatus "@baseboard_fab2_lib.baseboard_fab2(sch_1):page243_i65:a" )
			)
			( pin "C5G93.2"
				( objectStatus "@baseboard_fab2_lib.baseboard_fab2(sch_1):page243_i65:b" )
			)
			( pin "C5G94.1"
				( objectStatus "@baseboard_fab2_lib.baseboard_fab2(sch_1):page243_i64:a" )
			)
			( pin "C5G94.2"
				( objectStatus "@baseboard_fab2_lib.baseboard_fab2(sch_1):page243_i64:b" )
			)
			( pin "C5G95.1"
				( objectStatus "@baseboard_fab2_lib.baseboard_fab2(sch_1):page243_i63:a" )
			)
			( pin "C5G95.2"
				( objectStatus "@baseboard_fab2_lib.baseboard_fab2(sch_1):page243_i63:b" )
			)
			( pin "C5G116.1"
				( objectStatus "@baseboard_fab2_lib.baseboard_fab2(sch_1):page243_i90:a" )
			)
			( pin "C5G116.2"
				( objectStatus "@baseboard_fab2_lib.baseboard_fab2(sch_1):page243_i90:b" )
			)
			( pin "C5G96.1"
				( objectStatus "@baseboard_fab2_lib.baseboard_fab2(sch_1):page243_i62:a" )
			)
			( pin "C5G96.2"
				( objectStatus "@baseboard_fab2_lib.baseboard_fab2(sch_1):page243_i62:b" )
			)
			( pin "C5G80.1"
				( objectStatus "@baseboard_fab2_lib.baseboard_fab2(sch_1):page243_i61:a" )
			)
			( pin "C5G80.2"
				( objectStatus "@baseboard_fab2_lib.baseboard_fab2(sch_1):page243_i61:b" )
			)
			( pin "C5G81.1"
				( objectStatus "@baseboard_fab2_lib.baseboard_fab2(sch_1):page243_i60:a" )
			)
			( pin "C5G81.2"
				( objectStatus "@baseboard_fab2_lib.baseboard_fab2(sch_1):page243_i60:b" )
			)
			( pin "C5G82.1"
				( objectStatus "@baseboard_fab2_lib.baseboard_fab2(sch_1):page243_i59:a" )
			)
			( pin "C5G82.2"
				( objectStatus "@baseboard_fab2_lib.baseboard_fab2(sch_1):page243_i59:b" )
			)
			( pin "C5G83.1"
				( objectStatus "@baseboard_fab2_lib.baseboard_fab2(sch_1):page243_i58:a" )
			)
			( pin "C5G83.2"
				( objectStatus "@baseboard_fab2_lib.baseboard_fab2(sch_1):page243_i58:b" )
			)
			( pin "C5G84.1"
				( objectStatus "@baseboard_fab2_lib.baseboard_fab2(sch_1):page243_i57:a" )
			)
			( pin "C5G84.2"
				( objectStatus "@baseboard_fab2_lib.baseboard_fab2(sch_1):page243_i57:b" )
			)
			( pin "C5G85.1"
				( objectStatus "@baseboard_fab2_lib.baseboard_fab2(sch_1):page243_i56:a" )
			)
			( pin "C5G85.2"
				( objectStatus "@baseboard_fab2_lib.baseboard_fab2(sch_1):page243_i56:b" )
			)
			( pin "C5G86.1"
				( objectStatus "@baseboard_fab2_lib.baseboard_fab2(sch_1):page243_i55:a" )
			)
			( pin "C5G86.2"
				( objectStatus "@baseboard_fab2_lib.baseboard_fab2(sch_1):page243_i55:b" )
			)
			( pin "C5G87.1"
				( objectStatus "@baseboard_fab2_lib.baseboard_fab2(sch_1):page243_i54:a" )
			)
			( pin "C5G87.2"
				( objectStatus "@baseboard_fab2_lib.baseboard_fab2(sch_1):page243_i54:b" )
			)
			( pin "C5G79.1"
				( objectStatus "@baseboard_fab2_lib.baseboard_fab2(sch_1):page243_i53:a" )
			)
			( pin "C5G79.2"
				( objectStatus "@baseboard_fab2_lib.baseboard_fab2(sch_1):page243_i53:b" )
			)
			( pin "CT47.1"
				( objectStatus "@baseboard_fab2_lib.baseboard_fab2(sch_1):page219_i138:a" )
			)
			( pin "CT47.2"
				( objectStatus "@baseboard_fab2_lib.baseboard_fab2(sch_1):page219_i138:b" )
			)
			( pin "CT41.1"
				( objectStatus "@baseboard_fab2_lib.baseboard_fab2(sch_1):page203_i119:a" )
			)
			( pin "CT41.2"
				( objectStatus "@baseboard_fab2_lib.baseboard_fab2(sch_1):page203_i119:b" )
			)
			( pin "CT38.1"
				( objectStatus "@baseboard_fab2_lib.baseboard_fab2(sch_1):page203_i118:a" )
			)
			( pin "CT38.2"
				( objectStatus "@baseboard_fab2_lib.baseboard_fab2(sch_1):page203_i118:b" )
			)
			( pin "C5G41.1"
				( objectStatus "@baseboard_fab2_lib.baseboard_fab2(sch_1):page242_i53:a" )
			)
			( pin "C5G41.2"
				( objectStatus "@baseboard_fab2_lib.baseboard_fab2(sch_1):page242_i53:b" )
			)
			( pin "C5G42.1"
				( objectStatus "@baseboard_fab2_lib.baseboard_fab2(sch_1):page242_i54:a" )
			)
			( pin "C5G42.2"
				( objectStatus "@baseboard_fab2_lib.baseboard_fab2(sch_1):page242_i54:b" )
			)
			( pin "C5G44.1"
				( objectStatus "@baseboard_fab2_lib.baseboard_fab2(sch_1):page242_i55:a" )
			)
			( pin "C5G44.2"
				( objectStatus "@baseboard_fab2_lib.baseboard_fab2(sch_1):page242_i55:b" )
			)
			( pin "C5G43.1"
				( objectStatus "@baseboard_fab2_lib.baseboard_fab2(sch_1):page242_i56:a" )
			)
			( pin "C5G43.2"
				( objectStatus "@baseboard_fab2_lib.baseboard_fab2(sch_1):page242_i56:b" )
			)
			( pin "C5G48.1"
				( objectStatus "@baseboard_fab2_lib.baseboard_fab2(sch_1):page242_i57:a" )
			)
			( pin "C5G48.2"
				( objectStatus "@baseboard_fab2_lib.baseboard_fab2(sch_1):page242_i57:b" )
			)
			( pin "C5G47.1"
				( objectStatus "@baseboard_fab2_lib.baseboard_fab2(sch_1):page242_i58:a" )
			)
			( pin "C5G47.2"
				( objectStatus "@baseboard_fab2_lib.baseboard_fab2(sch_1):page242_i58:b" )
			)
			( pin "C5G46.1"
				( objectStatus "@baseboard_fab2_lib.baseboard_fab2(sch_1):page242_i59:a" )
			)
			( pin "C5G46.2"
				( objectStatus "@baseboard_fab2_lib.baseboard_fab2(sch_1):page242_i59:b" )
			)
			( pin "C5G45.1"
				( objectStatus "@baseboard_fab2_lib.baseboard_fab2(sch_1):page242_i60:a" )
			)
			( pin "C5G45.2"
				( objectStatus "@baseboard_fab2_lib.baseboard_fab2(sch_1):page242_i60:b" )
			)
			( pin "C5G49.1"
				( objectStatus "@baseboard_fab2_lib.baseboard_fab2(sch_1):page242_i61:a" )
			)
			( pin "C5G49.2"
				( objectStatus "@baseboard_fab2_lib.baseboard_fab2(sch_1):page242_i61:b" )
			)
			( pin "C5G54.1"
				( objectStatus "@baseboard_fab2_lib.baseboard_fab2(sch_1):page242_i62:a" )
			)
			( pin "C5G54.2"
				( objectStatus "@baseboard_fab2_lib.baseboard_fab2(sch_1):page242_i62:b" )
			)
			( pin "C5G58.1"
				( objectStatus "@baseboard_fab2_lib.baseboard_fab2(sch_1):page242_i63:a" )
			)
			( pin "C5G58.2"
				( objectStatus "@baseboard_fab2_lib.baseboard_fab2(sch_1):page242_i63:b" )
			)
			( pin "C5G57.1"
				( objectStatus "@baseboard_fab2_lib.baseboard_fab2(sch_1):page242_i64:a" )
			)
			( pin "C5G57.2"
				( objectStatus "@baseboard_fab2_lib.baseboard_fab2(sch_1):page242_i64:b" )
			)
			( pin "C5G56.1"
				( objectStatus "@baseboard_fab2_lib.baseboard_fab2(sch_1):page242_i65:a" )
			)
			( pin "C5G56.2"
				( objectStatus "@baseboard_fab2_lib.baseboard_fab2(sch_1):page242_i65:b" )
			)
			( pin "C5G55.1"
				( objectStatus "@baseboard_fab2_lib.baseboard_fab2(sch_1):page242_i66:a" )
			)
			( pin "C5G55.2"
				( objectStatus "@baseboard_fab2_lib.baseboard_fab2(sch_1):page242_i66:b" )
			)
			( pin "C5G53.1"
				( objectStatus "@baseboard_fab2_lib.baseboard_fab2(sch_1):page242_i67:a" )
			)
			( pin "C5G53.2"
				( objectStatus "@baseboard_fab2_lib.baseboard_fab2(sch_1):page242_i67:b" )
			)
			( pin "C5G52.1"
				( objectStatus "@baseboard_fab2_lib.baseboard_fab2(sch_1):page242_i68:a" )
			)
			( pin "C5G52.2"
				( objectStatus "@baseboard_fab2_lib.baseboard_fab2(sch_1):page242_i68:b" )
			)
			( pin "C5G51.1"
				( objectStatus "@baseboard_fab2_lib.baseboard_fab2(sch_1):page242_i69:a" )
			)
			( pin "C5G51.2"
				( objectStatus "@baseboard_fab2_lib.baseboard_fab2(sch_1):page242_i69:b" )
			)
			( pin "C5G50.1"
				( objectStatus "@baseboard_fab2_lib.baseboard_fab2(sch_1):page242_i70:a" )
			)
			( pin "C5G50.2"
				( objectStatus "@baseboard_fab2_lib.baseboard_fab2(sch_1):page242_i70:b" )
			)
			( pin "C5G67.1"
				( objectStatus "@baseboard_fab2_lib.baseboard_fab2(sch_1):page242_i71:a" )
			)
			( pin "C5G67.2"
				( objectStatus "@baseboard_fab2_lib.baseboard_fab2(sch_1):page242_i71:b" )
			)
			( pin "C5G66.1"
				( objectStatus "@baseboard_fab2_lib.baseboard_fab2(sch_1):page242_i72:a" )
			)
			( pin "C5G66.2"
				( objectStatus "@baseboard_fab2_lib.baseboard_fab2(sch_1):page242_i72:b" )
			)
			( pin "C5G65.1"
				( objectStatus "@baseboard_fab2_lib.baseboard_fab2(sch_1):page242_i73:a" )
			)
			( pin "C5G65.2"
				( objectStatus "@baseboard_fab2_lib.baseboard_fab2(sch_1):page242_i73:b" )
			)
			( pin "C5G64.1"
				( objectStatus "@baseboard_fab2_lib.baseboard_fab2(sch_1):page242_i74:a" )
			)
			( pin "C5G64.2"
				( objectStatus "@baseboard_fab2_lib.baseboard_fab2(sch_1):page242_i74:b" )
			)
			( pin "C5G63.1"
				( objectStatus "@baseboard_fab2_lib.baseboard_fab2(sch_1):page242_i75:a" )
			)
			( pin "C5G63.2"
				( objectStatus "@baseboard_fab2_lib.baseboard_fab2(sch_1):page242_i75:b" )
			)
			( pin "C5G62.1"
				( objectStatus "@baseboard_fab2_lib.baseboard_fab2(sch_1):page242_i76:a" )
			)
			( pin "C5G62.2"
				( objectStatus "@baseboard_fab2_lib.baseboard_fab2(sch_1):page242_i76:b" )
			)
			( pin "C5G61.1"
				( objectStatus "@baseboard_fab2_lib.baseboard_fab2(sch_1):page242_i77:a" )
			)
			( pin "C5G61.2"
				( objectStatus "@baseboard_fab2_lib.baseboard_fab2(sch_1):page242_i77:b" )
			)
			( pin "C5G60.1"
				( objectStatus "@baseboard_fab2_lib.baseboard_fab2(sch_1):page242_i78:a" )
			)
			( pin "C5G60.2"
				( objectStatus "@baseboard_fab2_lib.baseboard_fab2(sch_1):page242_i78:b" )
			)
			( pin "C5G59.1"
				( objectStatus "@baseboard_fab2_lib.baseboard_fab2(sch_1):page242_i79:a" )
			)
			( pin "C5G59.2"
				( objectStatus "@baseboard_fab2_lib.baseboard_fab2(sch_1):page242_i79:b" )
			)
			( pin "C5G76.1"
				( objectStatus "@baseboard_fab2_lib.baseboard_fab2(sch_1):page242_i80:a" )
			)
			( pin "C5G76.2"
				( objectStatus "@baseboard_fab2_lib.baseboard_fab2(sch_1):page242_i80:b" )
			)
			( pin "C5G75.1"
				( objectStatus "@baseboard_fab2_lib.baseboard_fab2(sch_1):page242_i81:a" )
			)
			( pin "C5G75.2"
				( objectStatus "@baseboard_fab2_lib.baseboard_fab2(sch_1):page242_i81:b" )
			)
			( pin "C5G74.1"
				( objectStatus "@baseboard_fab2_lib.baseboard_fab2(sch_1):page242_i82:a" )
			)
			( pin "C5G74.2"
				( objectStatus "@baseboard_fab2_lib.baseboard_fab2(sch_1):page242_i82:b" )
			)
			( pin "C5G73.1"
				( objectStatus "@baseboard_fab2_lib.baseboard_fab2(sch_1):page242_i83:a" )
			)
			( pin "C5G73.2"
				( objectStatus "@baseboard_fab2_lib.baseboard_fab2(sch_1):page242_i83:b" )
			)
			( pin "C5G72.1"
				( objectStatus "@baseboard_fab2_lib.baseboard_fab2(sch_1):page242_i84:a" )
			)
			( pin "C5G72.2"
				( objectStatus "@baseboard_fab2_lib.baseboard_fab2(sch_1):page242_i84:b" )
			)
			( pin "C5G71.1"
				( objectStatus "@baseboard_fab2_lib.baseboard_fab2(sch_1):page242_i85:a" )
			)
			( pin "C5G71.2"
				( objectStatus "@baseboard_fab2_lib.baseboard_fab2(sch_1):page242_i85:b" )
			)
			( pin "C5G70.1"
				( objectStatus "@baseboard_fab2_lib.baseboard_fab2(sch_1):page242_i86:a" )
			)
			( pin "C5G70.2"
				( objectStatus "@baseboard_fab2_lib.baseboard_fab2(sch_1):page242_i86:b" )
			)
			( pin "C5G69.1"
				( objectStatus "@baseboard_fab2_lib.baseboard_fab2(sch_1):page242_i87:a" )
			)
			( pin "C5G69.2"
				( objectStatus "@baseboard_fab2_lib.baseboard_fab2(sch_1):page242_i87:b" )
			)
			( pin "C5G68.1"
				( objectStatus "@baseboard_fab2_lib.baseboard_fab2(sch_1):page242_i88:a" )
			)
			( pin "C5G68.2"
				( objectStatus "@baseboard_fab2_lib.baseboard_fab2(sch_1):page242_i88:b" )
			)
			( pin "RT17.1"
				( objectStatus "@baseboard_fab2_lib.baseboard_fab2(sch_1):page207_i100:a" )
			)
			( pin "RT17.2"
				( objectStatus "@baseboard_fab2_lib.baseboard_fab2(sch_1):page207_i100:b" )
			)
			( pin "CT1.1"
				( objectStatus "@baseboard_fab2_lib.baseboard_fab2(sch_1):page202_i70:a" )
			)
			( pin "CT1.2"
				( objectStatus "@baseboard_fab2_lib.baseboard_fab2(sch_1):page202_i70:b" )
			)
			( pin "RT24.1"
				( objectStatus "@baseboard_fab2_lib.baseboard_fab2(sch_1):page204_i114:\1\" )
			)
			( pin "RT24.2"
				( objectStatus "@baseboard_fab2_lib.baseboard_fab2(sch_1):page204_i114:\2\" )
			)
			( pin "CT35.1"
				( objectStatus "@baseboard_fab2_lib.baseboard_fab2(sch_1):page204_i97:a" )
			)
			( pin "CT35.2"
				( objectStatus "@baseboard_fab2_lib.baseboard_fab2(sch_1):page204_i97:b" )
			)
			( pin "CT2.1"
				( objectStatus "@baseboard_fab2_lib.baseboard_fab2(sch_1):page202_i78:a" )
			)
			( pin "CT2.2"
				( objectStatus "@baseboard_fab2_lib.baseboard_fab2(sch_1):page202_i78:b" )
			)
			( pin "CT6.1"
				( objectStatus "@baseboard_fab2_lib.baseboard_fab2(sch_1):page202_i81:a" )
			)
			( pin "CT6.2"
				( objectStatus "@baseboard_fab2_lib.baseboard_fab2(sch_1):page202_i81:b" )
			)
			( pin "CT27.1"
				( objectStatus "@baseboard_fab2_lib.baseboard_fab2(sch_1):page207_i96:a" )
			)
			( pin "CT27.2"
				( objectStatus "@baseboard_fab2_lib.baseboard_fab2(sch_1):page207_i96:b" )
			)
			( pin "CT7.1"
				( objectStatus "@baseboard_fab2_lib.baseboard_fab2(sch_1):page227_i109:a" )
			)
			( pin "CT7.2"
				( objectStatus "@baseboard_fab2_lib.baseboard_fab2(sch_1):page227_i109:b" )
			)
			( pin "CT53.1"
				( objectStatus "@baseboard_fab2_lib.baseboard_fab2(sch_1):page216_i136:a" )
			)
			( pin "CT53.2"
				( objectStatus "@baseboard_fab2_lib.baseboard_fab2(sch_1):page216_i136:b" )
			)
			( pin "CT8.1"
				( objectStatus "@baseboard_fab2_lib.baseboard_fab2(sch_1):page227_i114:a" )
			)
			( pin "CT8.2"
				( objectStatus "@baseboard_fab2_lib.baseboard_fab2(sch_1):page227_i114:b" )
			)
			( pin "CT10.1"
				( objectStatus "@baseboard_fab2_lib.baseboard_fab2(sch_1):page227_i119:a" )
			)
			( pin "CT10.2"
				( objectStatus "@baseboard_fab2_lib.baseboard_fab2(sch_1):page227_i119:b" )
			)
			( pin "CT12.1"
				( objectStatus "@baseboard_fab2_lib.baseboard_fab2(sch_1):page227_i122:a" )
			)
			( pin "CT12.2"
				( objectStatus "@baseboard_fab2_lib.baseboard_fab2(sch_1):page227_i122:b" )
			)
			( pin "CT56.1"
				( objectStatus "@baseboard_fab2_lib.baseboard_fab2(sch_1):page210_i66:a" )
			)
			( pin "CT56.2"
				( objectStatus "@baseboard_fab2_lib.baseboard_fab2(sch_1):page210_i66:b" )
			)
			( pin "CT13.1"
				( objectStatus "@baseboard_fab2_lib.baseboard_fab2(sch_1):page209_i62:a" )
			)
			( pin "CT13.2"
				( objectStatus "@baseboard_fab2_lib.baseboard_fab2(sch_1):page209_i62:b" )
			)
			( pin "CT23.1"
				( objectStatus "@baseboard_fab2_lib.baseboard_fab2(sch_1):page207_i95:a" )
			)
			( pin "CT23.2"
				( objectStatus "@baseboard_fab2_lib.baseboard_fab2(sch_1):page207_i95:b" )
			)
			( pin "RT20.1"
				( objectStatus "@baseboard_fab2_lib.baseboard_fab2(sch_1):page224_i156:\1\" )
			)
			( pin "RT20.2"
				( objectStatus "@baseboard_fab2_lib.baseboard_fab2(sch_1):page224_i156:\2\" )
			)
			( pin "CT15.1"
				( objectStatus "@baseboard_fab2_lib.baseboard_fab2(sch_1):page209_i67:a" )
			)
			( pin "CT15.2"
				( objectStatus "@baseboard_fab2_lib.baseboard_fab2(sch_1):page209_i67:b" )
			)
			( pin "CT16.1"
				( objectStatus "@baseboard_fab2_lib.baseboard_fab2(sch_1):page208_i80:a" )
			)
			( pin "CT16.2"
				( objectStatus "@baseboard_fab2_lib.baseboard_fab2(sch_1):page208_i80:b" )
			)
			( pin "CTI7.1"
				( objectStatus "@baseboard_fab2_lib.baseboard_fab2(sch_1):page208_i82:a" )
			)
			( pin "CTI7.2"
				( objectStatus "@baseboard_fab2_lib.baseboard_fab2(sch_1):page208_i82:b" )
			)
			( pin "CT21.1"
				( objectStatus "@baseboard_fab2_lib.baseboard_fab2(sch_1):page208_i87:a" )
			)
			( pin "CT21.2"
				( objectStatus "@baseboard_fab2_lib.baseboard_fab2(sch_1):page208_i87:b" )
			)
			( pin "CT19.1"
				( objectStatus "@baseboard_fab2_lib.baseboard_fab2(sch_1):page208_i90:a" )
			)
			( pin "CT19.2"
				( objectStatus "@baseboard_fab2_lib.baseboard_fab2(sch_1):page208_i90:b" )
			)
			( pin "RT48.1"
				( objectStatus "@baseboard_fab2_lib.baseboard_fab2(sch_1):page212_i144:\1\" )
			)
			( pin "RT48.2"
				( objectStatus "@baseboard_fab2_lib.baseboard_fab2(sch_1):page212_i144:\2\" )
			)
			( pin "CT24.1"
				( objectStatus "@baseboard_fab2_lib.baseboard_fab2(sch_1):page207_i71:a" )
			)
			( pin "CT24.2"
				( objectStatus "@baseboard_fab2_lib.baseboard_fab2(sch_1):page207_i71:b" )
			)
			( pin "CT22.1"
				( objectStatus "@baseboard_fab2_lib.baseboard_fab2(sch_1):page207_i74:a" )
			)
			( pin "CT22.2"
				( objectStatus "@baseboard_fab2_lib.baseboard_fab2(sch_1):page207_i74:b" )
			)
			( pin "RT34.1"
				( objectStatus "@baseboard_fab2_lib.baseboard_fab2(sch_1):page216_i151:\1\" )
			)
			( pin "RT34.2"
				( objectStatus "@baseboard_fab2_lib.baseboard_fab2(sch_1):page216_i151:\2\" )
			)
			( pin "CT62.1"
				( objectStatus "@baseboard_fab2_lib.baseboard_fab2(sch_1):page214_i143:a" )
			)
			( pin "CT62.2"
				( objectStatus "@baseboard_fab2_lib.baseboard_fab2(sch_1):page214_i143:b" )
			)
			( pin "CT30.1"
				( objectStatus "@baseboard_fab2_lib.baseboard_fab2(sch_1):page224_i117:a" )
			)
			( pin "CT30.2"
				( objectStatus "@baseboard_fab2_lib.baseboard_fab2(sch_1):page224_i117:b" )
			)
			( pin "CT65.1"
				( objectStatus "@baseboard_fab2_lib.baseboard_fab2(sch_1):page236_i149:a" )
			)
			( pin "CT65.2"
				( objectStatus "@baseboard_fab2_lib.baseboard_fab2(sch_1):page236_i149:b" )
			)
			( pin "CT28.1"
				( objectStatus "@baseboard_fab2_lib.baseboard_fab2(sch_1):page224_i122:a" )
			)
			( pin "CT28.2"
				( objectStatus "@baseboard_fab2_lib.baseboard_fab2(sch_1):page224_i122:b" )
			)
			( pin "CT31.1"
				( objectStatus "@baseboard_fab2_lib.baseboard_fab2(sch_1):page224_i124:a" )
			)
			( pin "CT31.2"
				( objectStatus "@baseboard_fab2_lib.baseboard_fab2(sch_1):page224_i124:b" )
			)
			( pin "CT68.1"
				( objectStatus "@baseboard_fab2_lib.baseboard_fab2(sch_1):page236_i150:a" )
			)
			( pin "CT68.2"
				( objectStatus "@baseboard_fab2_lib.baseboard_fab2(sch_1):page236_i150:b" )
			)
			( pin "CT32.1"
				( objectStatus "@baseboard_fab2_lib.baseboard_fab2(sch_1):page224_i130:a" )
			)
			( pin "CT32.2"
				( objectStatus "@baseboard_fab2_lib.baseboard_fab2(sch_1):page224_i130:b" )
			)
			( pin "CT36.1"
				( objectStatus "@baseboard_fab2_lib.baseboard_fab2(sch_1):page204_i85:a" )
			)
			( pin "CT36.2"
				( objectStatus "@baseboard_fab2_lib.baseboard_fab2(sch_1):page204_i85:b" )
			)
			( pin "RT11.1"
				( objectStatus "@baseboard_fab2_lib.baseboard_fab2(sch_1):page208_i108:a" )
			)
			( pin "RT11.2"
				( objectStatus "@baseboard_fab2_lib.baseboard_fab2(sch_1):page208_i108:b" )
			)
			( pin "CT34.1"
				( objectStatus "@baseboard_fab2_lib.baseboard_fab2(sch_1):page204_i88:a" )
			)
			( pin "CT34.2"
				( objectStatus "@baseboard_fab2_lib.baseboard_fab2(sch_1):page204_i88:b" )
			)
			( pin "C5G77.1"
				( objectStatus "@baseboard_fab2_lib.baseboard_fab2(sch_1):page242_i89:a" )
			)
			( pin "C5G77.2"
				( objectStatus "@baseboard_fab2_lib.baseboard_fab2(sch_1):page242_i89:b" )
			)
			( pin "RT38.1"
				( objectStatus "@baseboard_fab2_lib.baseboard_fab2(sch_1):page210_i74:\1\" )
			)
			( pin "RT38.2"
				( objectStatus "@baseboard_fab2_lib.baseboard_fab2(sch_1):page210_i74:\2\" )
			)
			( pin "CT40.1"
				( objectStatus "@baseboard_fab2_lib.baseboard_fab2(sch_1):page203_i93:a" )
			)
			( pin "CT40.2"
				( objectStatus "@baseboard_fab2_lib.baseboard_fab2(sch_1):page203_i93:b" )
			)
			( pin "RT8.1"
				( objectStatus "@baseboard_fab2_lib.baseboard_fab2(sch_1):page227_i139:a" )
			)
			( pin "RT8.2"
				( objectStatus "@baseboard_fab2_lib.baseboard_fab2(sch_1):page227_i139:b" )
			)
			( pin "CT39.1"
				( objectStatus "@baseboard_fab2_lib.baseboard_fab2(sch_1):page203_i96:a" )
			)
			( pin "CT39.2"
				( objectStatus "@baseboard_fab2_lib.baseboard_fab2(sch_1):page203_i96:b" )
			)
			( pin "RT5.1"
				( objectStatus "@baseboard_fab2_lib.baseboard_fab2(sch_1):page227_i138:a" )
			)
			( pin "RT5.2"
				( objectStatus "@baseboard_fab2_lib.baseboard_fab2(sch_1):page227_i138:b" )
			)
			( pin "CT37.1"
				( objectStatus "@baseboard_fab2_lib.baseboard_fab2(sch_1):page203_i99:a" )
			)
			( pin "CT37.2"
				( objectStatus "@baseboard_fab2_lib.baseboard_fab2(sch_1):page203_i99:b" )
			)
			( pin "C5G22.1"
				( objectStatus "@baseboard_fab2_lib.baseboard_fab2(sch_1):page242_i90:a" )
			)
			( pin "C5G22.2"
				( objectStatus "@baseboard_fab2_lib.baseboard_fab2(sch_1):page242_i90:b" )
			)
			( pin "RT22.1"
				( objectStatus "@baseboard_fab2_lib.baseboard_fab2(sch_1):page224_i157:\1\" )
			)
			( pin "RT22.2"
				( objectStatus "@baseboard_fab2_lib.baseboard_fab2(sch_1):page224_i157:\2\" )
			)
			( pin "RT10.1"
				( objectStatus "@baseboard_fab2_lib.baseboard_fab2(sch_1):page209_i90:\1\" )
			)
			( pin "RT10.2"
				( objectStatus "@baseboard_fab2_lib.baseboard_fab2(sch_1):page209_i90:\2\" )
			)
			( pin "CT59.1"
				( objectStatus "@baseboard_fab2_lib.baseboard_fab2(sch_1):page205_i76:a" )
			)
			( pin "CT59.2"
				( objectStatus "@baseboard_fab2_lib.baseboard_fab2(sch_1):page205_i76:b" )
			)
			( pin "CT42.1"
				( objectStatus "@baseboard_fab2_lib.baseboard_fab2(sch_1):page203_i108:a" )
			)
			( pin "CT42.2"
				( objectStatus "@baseboard_fab2_lib.baseboard_fab2(sch_1):page203_i108:b" )
			)
			( pin "CT46.1"
				( objectStatus "@baseboard_fab2_lib.baseboard_fab2(sch_1):page219_i113:a" )
			)
			( pin "CT46.2"
				( objectStatus "@baseboard_fab2_lib.baseboard_fab2(sch_1):page219_i113:b" )
			)
			( pin "RT21.1"
				( objectStatus "@baseboard_fab2_lib.baseboard_fab2(sch_1):page224_i145:a" )
			)
			( pin "RT21.2"
				( objectStatus "@baseboard_fab2_lib.baseboard_fab2(sch_1):page224_i145:b" )
			)
			( pin "CT45.1"
				( objectStatus "@baseboard_fab2_lib.baseboard_fab2(sch_1):page219_i116:a" )
			)
			( pin "CT45.2"
				( objectStatus "@baseboard_fab2_lib.baseboard_fab2(sch_1):page219_i116:b" )
			)
			( pin "RT19.1"
				( objectStatus "@baseboard_fab2_lib.baseboard_fab2(sch_1):page224_i144:a" )
			)
			( pin "RT19.2"
				( objectStatus "@baseboard_fab2_lib.baseboard_fab2(sch_1):page224_i144:b" )
			)
			( pin "CT48.1"
				( objectStatus "@baseboard_fab2_lib.baseboard_fab2(sch_1):page219_i119:a" )
			)
			( pin "CT48.2"
				( objectStatus "@baseboard_fab2_lib.baseboard_fab2(sch_1):page219_i119:b" )
			)
			( pin "CT9.1"
				( objectStatus "@baseboard_fab2_lib.baseboard_fab2(sch_1):page227_i134:a" )
			)
			( pin "CT9.2"
				( objectStatus "@baseboard_fab2_lib.baseboard_fab2(sch_1):page227_i134:b" )
			)
			( pin "CT43.1"
				( objectStatus "@baseboard_fab2_lib.baseboard_fab2(sch_1):page219_i124:a" )
			)
			( pin "CT43.2"
				( objectStatus "@baseboard_fab2_lib.baseboard_fab2(sch_1):page219_i124:b" )
			)
			( pin "CT11.1"
				( objectStatus "@baseboard_fab2_lib.baseboard_fab2(sch_1):page227_i135:a" )
			)
			( pin "CT11.2"
				( objectStatus "@baseboard_fab2_lib.baseboard_fab2(sch_1):page227_i135:b" )
			)
			( pin "CT51.1"
				( objectStatus "@baseboard_fab2_lib.baseboard_fab2(sch_1):page216_i108:a" )
			)
			( pin "CT51.2"
				( objectStatus "@baseboard_fab2_lib.baseboard_fab2(sch_1):page216_i108:b" )
			)
			( pin "C7G38.1"
				( objectStatus "@baseboard_fab2_lib.baseboard_fab2(sch_1):page216_i128:a" )
			)
			( pin "C7G38.2"
				( objectStatus "@baseboard_fab2_lib.baseboard_fab2(sch_1):page216_i128:b" )
			)
			( pin "CT52.1"
				( objectStatus "@baseboard_fab2_lib.baseboard_fab2(sch_1):page216_i111:a" )
			)
			( pin "CT52.2"
				( objectStatus "@baseboard_fab2_lib.baseboard_fab2(sch_1):page216_i111:b" )
			)
			( pin "RT41.1"
				( objectStatus "@baseboard_fab2_lib.baseboard_fab2(sch_1):page214_i145:a" )
			)
			( pin "RT41.2"
				( objectStatus "@baseboard_fab2_lib.baseboard_fab2(sch_1):page214_i145:b" )
			)
			( pin "RT32.1"
				( objectStatus "@baseboard_fab2_lib.baseboard_fab2(sch_1):page219_i154:\1\" )
			)
			( pin "RT32.2"
				( objectStatus "@baseboard_fab2_lib.baseboard_fab2(sch_1):page219_i154:\2\" )
			)
			( pin "CT49.1"
				( objectStatus "@baseboard_fab2_lib.baseboard_fab2(sch_1):page216_i118:a" )
			)
			( pin "CT49.2"
				( objectStatus "@baseboard_fab2_lib.baseboard_fab2(sch_1):page216_i118:b" )
			)
			( pin "CT29.1"
				( objectStatus "@baseboard_fab2_lib.baseboard_fab2(sch_1):page224_i140:a" )
			)
			( pin "CT29.2"
				( objectStatus "@baseboard_fab2_lib.baseboard_fab2(sch_1):page224_i140:b" )
			)
			( pin "CT54.1"
				( objectStatus "@baseboard_fab2_lib.baseboard_fab2(sch_1):page216_i121:a" )
			)
			( pin "CT54.2"
				( objectStatus "@baseboard_fab2_lib.baseboard_fab2(sch_1):page216_i121:b" )
			)
			( pin "CT33.1"
				( objectStatus "@baseboard_fab2_lib.baseboard_fab2(sch_1):page224_i141:a" )
			)
			( pin "CT33.2"
				( objectStatus "@baseboard_fab2_lib.baseboard_fab2(sch_1):page224_i141:b" )
			)
			( pin "RT47.1"
				( objectStatus "@baseboard_fab2_lib.baseboard_fab2(sch_1):page212_i120:a" )
			)
			( pin "RT47.2"
				( objectStatus "@baseboard_fab2_lib.baseboard_fab2(sch_1):page212_i120:b" )
			)
			( pin "CT18.1"
				( objectStatus "@baseboard_fab2_lib.baseboard_fab2(sch_1):page208_i104:a" )
			)
			( pin "CT18.2"
				( objectStatus "@baseboard_fab2_lib.baseboard_fab2(sch_1):page208_i104:b" )
			)
			( pin "RT45.1"
				( objectStatus "@baseboard_fab2_lib.baseboard_fab2(sch_1):page236_i183:\1\" )
			)
			( pin "RT45.2"
				( objectStatus "@baseboard_fab2_lib.baseboard_fab2(sch_1):page236_i183:\2\" )
			)
			( pin "CT55.1"
				( objectStatus "@baseboard_fab2_lib.baseboard_fab2(sch_1):page210_i60:a" )
			)
			( pin "CT55.2"
				( objectStatus "@baseboard_fab2_lib.baseboard_fab2(sch_1):page210_i60:b" )
			)
			( pin "CT72.1"
				( objectStatus "@baseboard_fab2_lib.baseboard_fab2(sch_1):page212_i118:a" )
			)
			( pin "CT72.2"
				( objectStatus "@baseboard_fab2_lib.baseboard_fab2(sch_1):page212_i118:b" )
			)
			( pin "CT58.1"
				( objectStatus "@baseboard_fab2_lib.baseboard_fab2(sch_1):page205_i65:a" )
			)
			( pin "CT58.2"
				( objectStatus "@baseboard_fab2_lib.baseboard_fab2(sch_1):page205_i65:b" )
			)
			( pin "RT42.1"
				( objectStatus "@baseboard_fab2_lib.baseboard_fab2(sch_1):page214_i176:\1\" )
			)
			( pin "RT42.2"
				( objectStatus "@baseboard_fab2_lib.baseboard_fab2(sch_1):page214_i176:\2\" )
			)
			( pin "CT60.1"
				( objectStatus "@baseboard_fab2_lib.baseboard_fab2(sch_1):page205_i69:a" )
			)
			( pin "CT60.2"
				( objectStatus "@baseboard_fab2_lib.baseboard_fab2(sch_1):page205_i69:b" )
			)
			( pin "RT31.1"
				( objectStatus "@baseboard_fab2_lib.baseboard_fab2(sch_1):page219_i142:a" )
			)
			( pin "RT31.2"
				( objectStatus "@baseboard_fab2_lib.baseboard_fab2(sch_1):page219_i142:b" )
			)
			( pin "RT30.1"
				( objectStatus "@baseboard_fab2_lib.baseboard_fab2(sch_1):page219_i141:a" )
			)
			( pin "RT30.2"
				( objectStatus "@baseboard_fab2_lib.baseboard_fab2(sch_1):page219_i141:b" )
			)
			( pin "CT61.1"
				( objectStatus "@baseboard_fab2_lib.baseboard_fab2(sch_1):page214_i134:a" )
			)
			( pin "CT61.2"
				( objectStatus "@baseboard_fab2_lib.baseboard_fab2(sch_1):page214_i134:b" )
			)
			( pin "CT63.1"
				( objectStatus "@baseboard_fab2_lib.baseboard_fab2(sch_1):page214_i137:a" )
			)
			( pin "CT63.2"
				( objectStatus "@baseboard_fab2_lib.baseboard_fab2(sch_1):page214_i137:b" )
			)
			( pin "C5G78.1"
				( objectStatus "@baseboard_fab2_lib.baseboard_fab2(sch_1):page242_i91:a" )
			)
			( pin "C5G78.2"
				( objectStatus "@baseboard_fab2_lib.baseboard_fab2(sch_1):page242_i91:b" )
			)
			( pin "CT67.1"
				( objectStatus "@baseboard_fab2_lib.baseboard_fab2(sch_1):page236_i124:a" )
			)
			( pin "CT67.2"
				( objectStatus "@baseboard_fab2_lib.baseboard_fab2(sch_1):page236_i124:b" )
			)
			( pin "CT66.1"
				( objectStatus "@baseboard_fab2_lib.baseboard_fab2(sch_1):page236_i127:a" )
			)
			( pin "CT66.2"
				( objectStatus "@baseboard_fab2_lib.baseboard_fab2(sch_1):page236_i127:b" )
			)
			( pin "RT33.1"
				( objectStatus "@baseboard_fab2_lib.baseboard_fab2(sch_1):page216_i139:a" )
			)
			( pin "RT33.2"
				( objectStatus "@baseboard_fab2_lib.baseboard_fab2(sch_1):page216_i139:b" )
			)
			( pin "RT7.1"
				( objectStatus "@baseboard_fab2_lib.baseboard_fab2(sch_1):page227_i150:\1\" )
			)
			( pin "RT7.2"
				( objectStatus "@baseboard_fab2_lib.baseboard_fab2(sch_1):page227_i150:\2\" )
			)
			( pin "CT69.1"
				( objectStatus "@baseboard_fab2_lib.baseboard_fab2(sch_1):page236_i134:a" )
			)
			( pin "CT69.2"
				( objectStatus "@baseboard_fab2_lib.baseboard_fab2(sch_1):page236_i134:b" )
			)
			( pin "CT64.1"
				( objectStatus "@baseboard_fab2_lib.baseboard_fab2(sch_1):page236_i136:a" )
			)
			( pin "CT64.2"
				( objectStatus "@baseboard_fab2_lib.baseboard_fab2(sch_1):page236_i136:b" )
			)
			( pin "C5G21.1"
				( objectStatus "@baseboard_fab2_lib.baseboard_fab2(sch_1):page242_i92:a" )
			)
			( pin "C5G21.2"
				( objectStatus "@baseboard_fab2_lib.baseboard_fab2(sch_1):page242_i92:b" )
			)
			( pin "CT70.1"
				( objectStatus "@baseboard_fab2_lib.baseboard_fab2(sch_1):page212_i106:a" )
			)
			( pin "CT70.2"
				( objectStatus "@baseboard_fab2_lib.baseboard_fab2(sch_1):page212_i106:b" )
			)
			( pin "R9F65.1"
				( objectStatus "@baseboard_fab2_lib.baseboard_fab2(sch_1):page158_i148:a" )
			)
			( pin "R9F65.2"
				( objectStatus "@baseboard_fab2_lib.baseboard_fab2(sch_1):page158_i148:b" )
			)
			( pin "CT71.1"
				( objectStatus "@baseboard_fab2_lib.baseboard_fab2(sch_1):page212_i109:a" )
			)
			( pin "CT71.2"
				( objectStatus "@baseboard_fab2_lib.baseboard_fab2(sch_1):page212_i109:b" )
			)
			( pin "CT50.1"
				( objectStatus "@baseboard_fab2_lib.baseboard_fab2(sch_1):page216_i135:a" )
			)
			( pin "CT50.2"
				( objectStatus "@baseboard_fab2_lib.baseboard_fab2(sch_1):page216_i135:b" )
			)
			( pin "C22W1.1"
				( objectStatus "@baseboard_fab2_lib.baseboard_fab2(sch_1):page225_i246:\1\" )
			)
			( pin "C22W1.2"
				( objectStatus "@baseboard_fab2_lib.baseboard_fab2(sch_1):page225_i246:\2\" )
			)
			( pin "CT25.1"
				( objectStatus "@baseboard_fab2_lib.baseboard_fab2(sch_1):page207_i81:a" )
			)
			( pin "CT25.2"
				( objectStatus "@baseboard_fab2_lib.baseboard_fab2(sch_1):page207_i81:b" )
			)
			( pin "CT26.1"
				( objectStatus "@baseboard_fab2_lib.baseboard_fab2(sch_1):page207_i82:a" )
			)
			( pin "CT26.2"
				( objectStatus "@baseboard_fab2_lib.baseboard_fab2(sch_1):page207_i82:b" )
			)
			( pin "CT44.1"
				( objectStatus "@baseboard_fab2_lib.baseboard_fab2(sch_1):page219_i137:a" )
			)
			( pin "CT44.2"
				( objectStatus "@baseboard_fab2_lib.baseboard_fab2(sch_1):page219_i137:b" )
			)
			( pin "RT43.1"
				( objectStatus "@baseboard_fab2_lib.baseboard_fab2(sch_1):page236_i182:\1\" )
			)
			( pin "RT43.2"
				( objectStatus "@baseboard_fab2_lib.baseboard_fab2(sch_1):page236_i182:\2\" )
			)
			( pin "CT4.1"
				( objectStatus "@baseboard_fab2_lib.baseboard_fab2(sch_1):page202_i87:a" )
			)
			( pin "CT4.2"
				( objectStatus "@baseboard_fab2_lib.baseboard_fab2(sch_1):page202_i87:b" )
			)
			( pin "C831.1"
				( objectStatus "@baseboard_fab2_lib.baseboard_fab2(sch_1):page244_i2:a" )
			)
			( pin "C831.2"
				( objectStatus "@baseboard_fab2_lib.baseboard_fab2(sch_1):page244_i2:b" )
			)
			( pin "C829.1"
				( objectStatus "@baseboard_fab2_lib.baseboard_fab2(sch_1):page244_i5:a" )
			)
			( pin "C829.2"
				( objectStatus "@baseboard_fab2_lib.baseboard_fab2(sch_1):page244_i5:b" )
			)
			( pin "C833.1"
				( objectStatus "@baseboard_fab2_lib.baseboard_fab2(sch_1):page244_i8:a" )
			)
			( pin "C833.2"
				( objectStatus "@baseboard_fab2_lib.baseboard_fab2(sch_1):page244_i8:b" )
			)
			( pin "C827.1"
				( objectStatus "@baseboard_fab2_lib.baseboard_fab2(sch_1):page244_i12:a" )
			)
			( pin "C827.2"
				( objectStatus "@baseboard_fab2_lib.baseboard_fab2(sch_1):page244_i12:b" )
			)
			( pin "C841.1"
				( objectStatus "@baseboard_fab2_lib.baseboard_fab2(sch_1):page244_i17:a" )
			)
			( pin "C841.2"
				( objectStatus "@baseboard_fab2_lib.baseboard_fab2(sch_1):page244_i17:b" )
			)
			( pin "C830.1"
				( objectStatus "@baseboard_fab2_lib.baseboard_fab2(sch_1):page244_i23:a" )
			)
			( pin "C830.2"
				( objectStatus "@baseboard_fab2_lib.baseboard_fab2(sch_1):page244_i23:b" )
			)
			( pin "C826.1"
				( objectStatus "@baseboard_fab2_lib.baseboard_fab2(sch_1):page244_i24:a" )
			)
			( pin "C826.2"
				( objectStatus "@baseboard_fab2_lib.baseboard_fab2(sch_1):page244_i24:b" )
			)
			( pin "C828.1"
				( objectStatus "@baseboard_fab2_lib.baseboard_fab2(sch_1):page244_i28:a" )
			)
			( pin "C828.2"
				( objectStatus "@baseboard_fab2_lib.baseboard_fab2(sch_1):page244_i28:b" )
			)
			( pin "C840.1"
				( objectStatus "@baseboard_fab2_lib.baseboard_fab2(sch_1):page244_i29:a" )
			)
			( pin "C840.2"
				( objectStatus "@baseboard_fab2_lib.baseboard_fab2(sch_1):page244_i29:b" )
			)
			( pin "C832.1"
				( objectStatus "@baseboard_fab2_lib.baseboard_fab2(sch_1):page244_i30:a" )
			)
			( pin "C832.2"
				( objectStatus "@baseboard_fab2_lib.baseboard_fab2(sch_1):page244_i30:b" )
			)
			( pin "C845.1"
				( objectStatus "@baseboard_fab2_lib.baseboard_fab2(sch_1):page244_i35:a" )
			)
			( pin "C845.2"
				( objectStatus "@baseboard_fab2_lib.baseboard_fab2(sch_1):page244_i35:b" )
			)
			( pin "R767.1"
				( objectStatus "@baseboard_fab2_lib.baseboard_fab2(sch_1):page244_i39:a" )
			)
			( pin "R767.2"
				( objectStatus "@baseboard_fab2_lib.baseboard_fab2(sch_1):page244_i39:b" )
			)
			( pin "C835.1"
				( objectStatus "@baseboard_fab2_lib.baseboard_fab2(sch_1):page244_i41:a" )
			)
			( pin "C835.2"
				( objectStatus "@baseboard_fab2_lib.baseboard_fab2(sch_1):page244_i41:b" )
			)
			( pin "C843.1"
				( objectStatus "@baseboard_fab2_lib.baseboard_fab2(sch_1):page244_i47:a" )
			)
			( pin "C843.2"
				( objectStatus "@baseboard_fab2_lib.baseboard_fab2(sch_1):page244_i47:b" )
			)
			( pin "C834.1"
				( objectStatus "@baseboard_fab2_lib.baseboard_fab2(sch_1):page244_i50:a" )
			)
			( pin "C834.2"
				( objectStatus "@baseboard_fab2_lib.baseboard_fab2(sch_1):page244_i50:b" )
			)
			( pin "C844.1"
				( objectStatus "@baseboard_fab2_lib.baseboard_fab2(sch_1):page244_i51:a" )
			)
			( pin "C844.2"
				( objectStatus "@baseboard_fab2_lib.baseboard_fab2(sch_1):page244_i51:b" )
			)
			( pin "C842.1"
				( objectStatus "@baseboard_fab2_lib.baseboard_fab2(sch_1):page244_i52:a" )
			)
			( pin "C842.2"
				( objectStatus "@baseboard_fab2_lib.baseboard_fab2(sch_1):page244_i52:b" )
			)
			( pin "R769.1"
				( objectStatus "@baseboard_fab2_lib.baseboard_fab2(sch_1):page244_i58:a" )
			)
			( pin "R769.2"
				( objectStatus "@baseboard_fab2_lib.baseboard_fab2(sch_1):page244_i58:b" )
			)
			( pin "R760.1"
				( objectStatus "@baseboard_fab2_lib.baseboard_fab2(sch_1):page244_i64:a" )
			)
			( pin "R760.2"
				( objectStatus "@baseboard_fab2_lib.baseboard_fab2(sch_1):page244_i64:b" )
			)
			( pin "R771.1"
				( objectStatus "@baseboard_fab2_lib.baseboard_fab2(sch_1):page244_i65:a" )
			)
			( pin "R771.2"
				( objectStatus "@baseboard_fab2_lib.baseboard_fab2(sch_1):page244_i65:b" )
			)
			( pin "R768.1"
				( objectStatus "@baseboard_fab2_lib.baseboard_fab2(sch_1):page244_i66:a" )
			)
			( pin "R768.2"
				( objectStatus "@baseboard_fab2_lib.baseboard_fab2(sch_1):page244_i66:b" )
			)
			( pin "R774.1"
				( objectStatus "@baseboard_fab2_lib.baseboard_fab2(sch_1):page244_i72:a" )
			)
			( pin "R774.2"
				( objectStatus "@baseboard_fab2_lib.baseboard_fab2(sch_1):page244_i72:b" )
			)
			( pin "R779.1"
				( objectStatus "@baseboard_fab2_lib.baseboard_fab2(sch_1):page244_i74:a" )
			)
			( pin "R779.2"
				( objectStatus "@baseboard_fab2_lib.baseboard_fab2(sch_1):page244_i74:b" )
			)
			( pin "R783.1"
				( objectStatus "@baseboard_fab2_lib.baseboard_fab2(sch_1):page244_i77:a" )
			)
			( pin "R783.2"
				( objectStatus "@baseboard_fab2_lib.baseboard_fab2(sch_1):page244_i77:b" )
			)
			( pin "R777.1"
				( objectStatus "@baseboard_fab2_lib.baseboard_fab2(sch_1):page244_i80:a" )
			)
			( pin "R777.2"
				( objectStatus "@baseboard_fab2_lib.baseboard_fab2(sch_1):page244_i80:b" )
			)
			( pin "R781.1"
				( objectStatus "@baseboard_fab2_lib.baseboard_fab2(sch_1):page244_i86:a" )
			)
			( pin "R781.2"
				( objectStatus "@baseboard_fab2_lib.baseboard_fab2(sch_1):page244_i86:b" )
			)
			( pin "R775.1"
				( objectStatus "@baseboard_fab2_lib.baseboard_fab2(sch_1):page244_i93:a" )
			)
			( pin "R775.2"
				( objectStatus "@baseboard_fab2_lib.baseboard_fab2(sch_1):page244_i93:b" )
			)
			( pin "R778.1"
				( objectStatus "@baseboard_fab2_lib.baseboard_fab2(sch_1):page244_i94:a" )
			)
			( pin "R778.2"
				( objectStatus "@baseboard_fab2_lib.baseboard_fab2(sch_1):page244_i94:b" )
			)
			( pin "R780.1"
				( objectStatus "@baseboard_fab2_lib.baseboard_fab2(sch_1):page244_i97:a" )
			)
			( pin "R780.2"
				( objectStatus "@baseboard_fab2_lib.baseboard_fab2(sch_1):page244_i97:b" )
			)
			( pin "R782.1"
				( objectStatus "@baseboard_fab2_lib.baseboard_fab2(sch_1):page244_i98:a" )
			)
			( pin "R782.2"
				( objectStatus "@baseboard_fab2_lib.baseboard_fab2(sch_1):page244_i98:b" )
			)
			( pin "R784.1"
				( objectStatus "@baseboard_fab2_lib.baseboard_fab2(sch_1):page244_i99:a" )
			)
			( pin "R784.2"
				( objectStatus "@baseboard_fab2_lib.baseboard_fab2(sch_1):page244_i99:b" )
			)
			( pin "R785.1"
				( objectStatus "@baseboard_fab2_lib.baseboard_fab2(sch_1):page244_i103:a" )
			)
			( pin "R785.2"
				( objectStatus "@baseboard_fab2_lib.baseboard_fab2(sch_1):page244_i103:b" )
			)
			( pin "CONX8.1"
				( objectStatus "@baseboard_fab2_lib.baseboard_fab2(sch_1):page245_i48:\1\" )
			)
			( pin "CONX8.2"
				( objectStatus "@baseboard_fab2_lib.baseboard_fab2(sch_1):page245_i48:\2\" )
			)
			( pin "CONX8.3"
				( objectStatus "@baseboard_fab2_lib.baseboard_fab2(sch_1):page245_i48:\3\" )
			)
			( pin "CONX8.4"
				( objectStatus "@baseboard_fab2_lib.baseboard_fab2(sch_1):page245_i48:\4\" )
			)
			( pin "CONX8.5"
				( objectStatus "@baseboard_fab2_lib.baseboard_fab2(sch_1):page245_i48:\5\" )
			)
			( pin "CONX8.6"
				( objectStatus "@baseboard_fab2_lib.baseboard_fab2(sch_1):page245_i48:\6\" )
			)
			( pin "CONX8.7"
				( objectStatus "@baseboard_fab2_lib.baseboard_fab2(sch_1):page245_i48:\7\" )
			)
			( pin "CONX8.8"
				( objectStatus "@baseboard_fab2_lib.baseboard_fab2(sch_1):page245_i48:\8\" )
			)
			( pin "CONX8.9"
				( objectStatus "@baseboard_fab2_lib.baseboard_fab2(sch_1):page245_i48:\9\" )
			)
			( pin "CONX8.10"
				( objectStatus "@baseboard_fab2_lib.baseboard_fab2(sch_1):page245_i48:\10\" )
			)
			( pin "CONX8.11"
				( objectStatus "@baseboard_fab2_lib.baseboard_fab2(sch_1):page245_i48:\11\" )
			)
			( pin "CONX8.12"
				( objectStatus "@baseboard_fab2_lib.baseboard_fab2(sch_1):page245_i48:\12\" )
			)
			( pin "CONX8.13"
				( objectStatus "@baseboard_fab2_lib.baseboard_fab2(sch_1):page245_i48:\13\" )
			)
			( pin "CONX8.14"
				( objectStatus "@baseboard_fab2_lib.baseboard_fab2(sch_1):page245_i48:\14\" )
			)
			( pin "CONX8.15"
				( objectStatus "@baseboard_fab2_lib.baseboard_fab2(sch_1):page245_i48:\15\" )
			)
			( pin "CONX8.16"
				( objectStatus "@baseboard_fab2_lib.baseboard_fab2(sch_1):page245_i48:\16\" )
			)
			( pin "CONX8.17"
				( objectStatus "@baseboard_fab2_lib.baseboard_fab2(sch_1):page245_i48:\17\" )
			)
			( pin "CONX8.18"
				( objectStatus "@baseboard_fab2_lib.baseboard_fab2(sch_1):page245_i48:\18\" )
			)
			( pin "CONX8.19"
				( objectStatus "@baseboard_fab2_lib.baseboard_fab2(sch_1):page245_i48:\19\" )
			)
			( pin "CONX8.20"
				( objectStatus "@baseboard_fab2_lib.baseboard_fab2(sch_1):page245_i48:\20\" )
			)
			( pin "CONX8.21"
				( objectStatus "@baseboard_fab2_lib.baseboard_fab2(sch_1):page245_i48:\21\" )
			)
			( pin "CONX8.22"
				( objectStatus "@baseboard_fab2_lib.baseboard_fab2(sch_1):page245_i48:\22\" )
			)
			( pin "CONX8.23"
				( objectStatus "@baseboard_fab2_lib.baseboard_fab2(sch_1):page245_i48:\23\" )
			)
			( pin "CONX8.24"
				( objectStatus "@baseboard_fab2_lib.baseboard_fab2(sch_1):page245_i48:\24\" )
			)
			( pin "CONX8.25"
				( objectStatus "@baseboard_fab2_lib.baseboard_fab2(sch_1):page245_i48:\25\" )
			)
			( pin "CONX8.26"
				( objectStatus "@baseboard_fab2_lib.baseboard_fab2(sch_1):page245_i48:\26\" )
			)
			( pin "CONX8.27"
				( objectStatus "@baseboard_fab2_lib.baseboard_fab2(sch_1):page245_i48:\27\" )
			)
			( pin "CONX8.28"
				( objectStatus "@baseboard_fab2_lib.baseboard_fab2(sch_1):page245_i48:\28\" )
			)
			( pin "CONX8.29"
				( objectStatus "@baseboard_fab2_lib.baseboard_fab2(sch_1):page245_i48:\29\" )
			)
			( pin "CONX8.30"
				( objectStatus "@baseboard_fab2_lib.baseboard_fab2(sch_1):page245_i48:\30\" )
			)
			( pin "CONX8.31"
				( objectStatus "@baseboard_fab2_lib.baseboard_fab2(sch_1):page245_i48:\31\" )
			)
			( pin "CONX8.32"
				( objectStatus "@baseboard_fab2_lib.baseboard_fab2(sch_1):page245_i48:\32\" )
			)
			( pin "CONX8.33"
				( objectStatus "@baseboard_fab2_lib.baseboard_fab2(sch_1):page245_i48:\33\" )
			)
			( pin "CONX8.34"
				( objectStatus "@baseboard_fab2_lib.baseboard_fab2(sch_1):page245_i48:\34\" )
			)
			( pin "CONX8.35"
				( objectStatus "@baseboard_fab2_lib.baseboard_fab2(sch_1):page245_i48:\35\" )
			)
			( pin "CONX8.36"
				( objectStatus "@baseboard_fab2_lib.baseboard_fab2(sch_1):page245_i48:\36\" )
			)
			( pin "CONX8.37"
				( objectStatus "@baseboard_fab2_lib.baseboard_fab2(sch_1):page245_i48:\37\" )
			)
			( pin "CONX8.38"
				( objectStatus "@baseboard_fab2_lib.baseboard_fab2(sch_1):page245_i48:\38\" )
			)
			( pin "CONX8.39"
				( objectStatus "@baseboard_fab2_lib.baseboard_fab2(sch_1):page245_i48:\39\" )
			)
			( pin "CONX8.40"
				( objectStatus "@baseboard_fab2_lib.baseboard_fab2(sch_1):page245_i48:\40\" )
			)
			( pin "CONX8.41"
				( objectStatus "@baseboard_fab2_lib.baseboard_fab2(sch_1):page245_i48:\41\" )
			)
			( pin "CONX8.42"
				( objectStatus "@baseboard_fab2_lib.baseboard_fab2(sch_1):page245_i48:\42\" )
			)
			( pin "CONX8.43"
				( objectStatus "@baseboard_fab2_lib.baseboard_fab2(sch_1):page245_i48:\43\" )
			)
			( pin "CONX8.44"
				( objectStatus "@baseboard_fab2_lib.baseboard_fab2(sch_1):page245_i48:\44\" )
			)
			( pin "CONX8.45"
				( objectStatus "@baseboard_fab2_lib.baseboard_fab2(sch_1):page245_i48:\45\" )
			)
			( pin "CONX8.46"
				( objectStatus "@baseboard_fab2_lib.baseboard_fab2(sch_1):page245_i48:\46\" )
			)
			( pin "CONX8.47"
				( objectStatus "@baseboard_fab2_lib.baseboard_fab2(sch_1):page245_i48:\47\" )
			)
			( pin "CONX8.48"
				( objectStatus "@baseboard_fab2_lib.baseboard_fab2(sch_1):page245_i48:\48\" )
			)
			( pin "CONX8.49"
				( objectStatus "@baseboard_fab2_lib.baseboard_fab2(sch_1):page245_i48:\49\" )
			)
			( pin "CONX8.50"
				( objectStatus "@baseboard_fab2_lib.baseboard_fab2(sch_1):page245_i48:\50\" )
			)
			( pin "CONX8.51"
				( objectStatus "@baseboard_fab2_lib.baseboard_fab2(sch_1):page245_i48:\51\" )
			)
			( pin "CONX8.52"
				( objectStatus "@baseboard_fab2_lib.baseboard_fab2(sch_1):page245_i48:\52\" )
			)
			( pin "CONX8.53"
				( objectStatus "@baseboard_fab2_lib.baseboard_fab2(sch_1):page245_i48:\53\" )
			)
			( pin "CONX8.54"
				( objectStatus "@baseboard_fab2_lib.baseboard_fab2(sch_1):page245_i48:\54\" )
			)
			( pin "CONX8.55"
				( objectStatus "@baseboard_fab2_lib.baseboard_fab2(sch_1):page245_i48:\55\" )
			)
			( pin "CONX8.56"
				( objectStatus "@baseboard_fab2_lib.baseboard_fab2(sch_1):page245_i48:\56\" )
			)
			( pin "CONX8.57"
				( objectStatus "@baseboard_fab2_lib.baseboard_fab2(sch_1):page245_i48:\57\" )
			)
			( pin "CONX8.58"
				( objectStatus "@baseboard_fab2_lib.baseboard_fab2(sch_1):page245_i48:\58\" )
			)
			( pin "CONX8.59"
				( objectStatus "@baseboard_fab2_lib.baseboard_fab2(sch_1):page245_i48:\59\" )
			)
			( pin "CONX8.60"
				( objectStatus "@baseboard_fab2_lib.baseboard_fab2(sch_1):page245_i48:\60\" )
			)
			( pin "CONX8.NP1"
				( objectStatus "@baseboard_fab2_lib.baseboard_fab2(sch_1):page245_i48:np1" )
			)
			( pin "CONX8.NP2"
				( objectStatus "@baseboard_fab2_lib.baseboard_fab2(sch_1):page245_i48:np2" )
			)
			( pin "CONX8.PTH1"
				( objectStatus "@baseboard_fab2_lib.baseboard_fab2(sch_1):page245_i48:pth1" )
			)
			( pin "CONX8.PTH2"
				( objectStatus "@baseboard_fab2_lib.baseboard_fab2(sch_1):page245_i48:pth2" )
			)
			( pin "J8G1.101"
				( objectStatus "@baseboard_fab2_lib.baseboard_fab2(sch_1):page109_i78:io101" )
			)
			( pin "J8G1.102"
				( objectStatus "@baseboard_fab2_lib.baseboard_fab2(sch_1):page109_i78:io102" )
			)
			( pin "J8G1.103"
				( objectStatus "@baseboard_fab2_lib.baseboard_fab2(sch_1):page109_i78:io103" )
			)
			( pin "J8G1.104"
				( objectStatus "@baseboard_fab2_lib.baseboard_fab2(sch_1):page109_i78:io104" )
			)
			( pin "J8G1.105"
				( objectStatus "@baseboard_fab2_lib.baseboard_fab2(sch_1):page109_i78:io105" )
			)
			( pin "J8G1.106"
				( objectStatus "@baseboard_fab2_lib.baseboard_fab2(sch_1):page109_i78:io106" )
			)
			( pin "J8G1.107"
				( objectStatus "@baseboard_fab2_lib.baseboard_fab2(sch_1):page109_i78:io107" )
			)
			( pin "J8G1.108"
				( objectStatus "@baseboard_fab2_lib.baseboard_fab2(sch_1):page109_i78:io108" )
			)
			( pin "J8G1.109"
				( objectStatus "@baseboard_fab2_lib.baseboard_fab2(sch_1):page109_i78:io109" )
			)
			( pin "J8G1.110"
				( objectStatus "@baseboard_fab2_lib.baseboard_fab2(sch_1):page109_i78:io110" )
			)
			( pin "J8G1.111"
				( objectStatus "@baseboard_fab2_lib.baseboard_fab2(sch_1):page109_i78:io111" )
			)
			( pin "J8G1.112"
				( objectStatus "@baseboard_fab2_lib.baseboard_fab2(sch_1):page109_i78:io112" )
			)
			( pin "J8G1.113"
				( objectStatus "@baseboard_fab2_lib.baseboard_fab2(sch_1):page109_i78:io113" )
			)
			( pin "J8G1.114"
				( objectStatus "@baseboard_fab2_lib.baseboard_fab2(sch_1):page109_i78:io114" )
			)
			( pin "J8G1.115"
				( objectStatus "@baseboard_fab2_lib.baseboard_fab2(sch_1):page109_i78:io115" )
			)
			( pin "J8G1.116"
				( objectStatus "@baseboard_fab2_lib.baseboard_fab2(sch_1):page109_i78:io116" )
			)
			( pin "J8G1.117"
				( objectStatus "@baseboard_fab2_lib.baseboard_fab2(sch_1):page109_i78:io117" )
			)
			( pin "J8G1.118"
				( objectStatus "@baseboard_fab2_lib.baseboard_fab2(sch_1):page109_i78:io118" )
			)
			( pin "J8G1.119"
				( objectStatus "@baseboard_fab2_lib.baseboard_fab2(sch_1):page109_i78:io119" )
			)
			( pin "J8G1.120"
				( objectStatus "@baseboard_fab2_lib.baseboard_fab2(sch_1):page109_i78:io120" )
			)
			( pin "J8G1.121"
				( objectStatus "@baseboard_fab2_lib.baseboard_fab2(sch_1):page109_i78:io121" )
			)
			( pin "J8G1.122"
				( objectStatus "@baseboard_fab2_lib.baseboard_fab2(sch_1):page109_i78:io122" )
			)
			( pin "J8G1.123"
				( objectStatus "@baseboard_fab2_lib.baseboard_fab2(sch_1):page109_i78:io123" )
			)
			( pin "J8G1.124"
				( objectStatus "@baseboard_fab2_lib.baseboard_fab2(sch_1):page109_i78:io124" )
			)
			( pin "J8G1.125"
				( objectStatus "@baseboard_fab2_lib.baseboard_fab2(sch_1):page109_i78:io125" )
			)
			( pin "J8G1.126"
				( objectStatus "@baseboard_fab2_lib.baseboard_fab2(sch_1):page109_i78:io126" )
			)
			( pin "J8G1.127"
				( objectStatus "@baseboard_fab2_lib.baseboard_fab2(sch_1):page109_i78:io127" )
			)
			( pin "J8G1.128"
				( objectStatus "@baseboard_fab2_lib.baseboard_fab2(sch_1):page109_i78:io128" )
			)
			( pin "J8G1.129"
				( objectStatus "@baseboard_fab2_lib.baseboard_fab2(sch_1):page109_i78:io129" )
			)
			( pin "J8G1.130"
				( objectStatus "@baseboard_fab2_lib.baseboard_fab2(sch_1):page109_i78:io130" )
			)
			( pin "J8G1.131"
				( objectStatus "@baseboard_fab2_lib.baseboard_fab2(sch_1):page109_i78:io131" )
			)
			( pin "J8G1.132"
				( objectStatus "@baseboard_fab2_lib.baseboard_fab2(sch_1):page109_i78:io132" )
			)
			( pin "J8G1.133"
				( objectStatus "@baseboard_fab2_lib.baseboard_fab2(sch_1):page109_i78:io133" )
			)
			( pin "J8G1.134"
				( objectStatus "@baseboard_fab2_lib.baseboard_fab2(sch_1):page109_i78:io134" )
			)
			( pin "J8G1.135"
				( objectStatus "@baseboard_fab2_lib.baseboard_fab2(sch_1):page109_i78:io135" )
			)
			( pin "J8G1.136"
				( objectStatus "@baseboard_fab2_lib.baseboard_fab2(sch_1):page109_i78:io136" )
			)
			( pin "J8G1.137"
				( objectStatus "@baseboard_fab2_lib.baseboard_fab2(sch_1):page109_i78:io137" )
			)
			( pin "J8G1.138"
				( objectStatus "@baseboard_fab2_lib.baseboard_fab2(sch_1):page109_i78:io138" )
			)
			( pin "J8G1.139"
				( objectStatus "@baseboard_fab2_lib.baseboard_fab2(sch_1):page109_i78:io139" )
			)
			( pin "J8G1.140"
				( objectStatus "@baseboard_fab2_lib.baseboard_fab2(sch_1):page109_i78:io140" )
			)
			( pin "J8G1.141"
				( objectStatus "@baseboard_fab2_lib.baseboard_fab2(sch_1):page109_i78:io141" )
			)
			( pin "J8G1.142"
				( objectStatus "@baseboard_fab2_lib.baseboard_fab2(sch_1):page109_i78:io142" )
			)
			( pin "J8G1.143"
				( objectStatus "@baseboard_fab2_lib.baseboard_fab2(sch_1):page109_i78:io143" )
			)
			( pin "J8G1.144"
				( objectStatus "@baseboard_fab2_lib.baseboard_fab2(sch_1):page109_i78:io144" )
			)
			( pin "J8G1.145"
				( objectStatus "@baseboard_fab2_lib.baseboard_fab2(sch_1):page109_i78:io145" )
			)
			( pin "J8G1.146"
				( objectStatus "@baseboard_fab2_lib.baseboard_fab2(sch_1):page109_i78:io146" )
			)
			( pin "J8G1.147"
				( objectStatus "@baseboard_fab2_lib.baseboard_fab2(sch_1):page109_i78:io147" )
			)
			( pin "J8G1.148"
				( objectStatus "@baseboard_fab2_lib.baseboard_fab2(sch_1):page109_i78:io148" )
			)
			( pin "J8G1.149"
				( objectStatus "@baseboard_fab2_lib.baseboard_fab2(sch_1):page109_i78:io149" )
			)
			( pin "J8G1.150"
				( objectStatus "@baseboard_fab2_lib.baseboard_fab2(sch_1):page109_i78:io150" )
			)
			( pin "J8G1.151"
				( objectStatus "@baseboard_fab2_lib.baseboard_fab2(sch_1):page109_i78:io151" )
			)
			( pin "J8G1.152"
				( objectStatus "@baseboard_fab2_lib.baseboard_fab2(sch_1):page109_i78:io152" )
			)
			( pin "J8G1.153"
				( objectStatus "@baseboard_fab2_lib.baseboard_fab2(sch_1):page109_i78:io153" )
			)
			( pin "J8G1.154"
				( objectStatus "@baseboard_fab2_lib.baseboard_fab2(sch_1):page109_i78:io154" )
			)
			( pin "J8G1.155"
				( objectStatus "@baseboard_fab2_lib.baseboard_fab2(sch_1):page109_i78:io155" )
			)
			( pin "J8G1.156"
				( objectStatus "@baseboard_fab2_lib.baseboard_fab2(sch_1):page109_i78:io156" )
			)
			( pin "J8G1.157"
				( objectStatus "@baseboard_fab2_lib.baseboard_fab2(sch_1):page109_i78:io157" )
			)
			( pin "J8G1.158"
				( objectStatus "@baseboard_fab2_lib.baseboard_fab2(sch_1):page109_i78:io158" )
			)
			( pin "J8G1.159"
				( objectStatus "@baseboard_fab2_lib.baseboard_fab2(sch_1):page109_i78:io159" )
			)
			( pin "J8G1.160"
				( objectStatus "@baseboard_fab2_lib.baseboard_fab2(sch_1):page109_i78:io160" )
			)
			( pin "J8G1.161"
				( objectStatus "@baseboard_fab2_lib.baseboard_fab2(sch_1):page109_i78:io161" )
			)
			( pin "J8G1.162"
				( objectStatus "@baseboard_fab2_lib.baseboard_fab2(sch_1):page109_i78:io162" )
			)
			( pin "J8G1.163"
				( objectStatus "@baseboard_fab2_lib.baseboard_fab2(sch_1):page109_i78:io163" )
			)
			( pin "J8G1.164"
				( objectStatus "@baseboard_fab2_lib.baseboard_fab2(sch_1):page109_i78:io164" )
			)
			( pin "J8G1.165"
				( objectStatus "@baseboard_fab2_lib.baseboard_fab2(sch_1):page109_i78:io165" )
			)
			( pin "J8G1.166"
				( objectStatus "@baseboard_fab2_lib.baseboard_fab2(sch_1):page109_i78:io166" )
			)
			( pin "J8G1.167"
				( objectStatus "@baseboard_fab2_lib.baseboard_fab2(sch_1):page109_i78:io167" )
			)
			( pin "J8G1.168"
				( objectStatus "@baseboard_fab2_lib.baseboard_fab2(sch_1):page109_i78:io168" )
			)
			( pin "J8G1.169"
				( objectStatus "@baseboard_fab2_lib.baseboard_fab2(sch_1):page109_i78:io169" )
			)
			( pin "J8G1.170"
				( objectStatus "@baseboard_fab2_lib.baseboard_fab2(sch_1):page109_i78:io170" )
			)
			( pin "J8G1.171"
				( objectStatus "@baseboard_fab2_lib.baseboard_fab2(sch_1):page109_i78:io171" )
			)
			( pin "J8G1.172"
				( objectStatus "@baseboard_fab2_lib.baseboard_fab2(sch_1):page109_i78:io172" )
			)
			( pin "J8G1.173"
				( objectStatus "@baseboard_fab2_lib.baseboard_fab2(sch_1):page109_i78:io173" )
			)
			( pin "J8G1.174"
				( objectStatus "@baseboard_fab2_lib.baseboard_fab2(sch_1):page109_i78:io174" )
			)
			( pin "J8G1.175"
				( objectStatus "@baseboard_fab2_lib.baseboard_fab2(sch_1):page109_i78:io175" )
			)
			( pin "J8G1.176"
				( objectStatus "@baseboard_fab2_lib.baseboard_fab2(sch_1):page109_i78:io176" )
			)
			( pin "J8G1.177"
				( objectStatus "@baseboard_fab2_lib.baseboard_fab2(sch_1):page109_i78:io177" )
			)
			( pin "J8G1.178"
				( objectStatus "@baseboard_fab2_lib.baseboard_fab2(sch_1):page109_i78:io178" )
			)
			( pin "J8G1.179"
				( objectStatus "@baseboard_fab2_lib.baseboard_fab2(sch_1):page109_i78:io179" )
			)
			( pin "J8G1.180"
				( objectStatus "@baseboard_fab2_lib.baseboard_fab2(sch_1):page109_i78:io180" )
			)
			( pin "J8G1.181"
				( objectStatus "@baseboard_fab2_lib.baseboard_fab2(sch_1):page109_i78:io181" )
			)
			( pin "J8G1.182"
				( objectStatus "@baseboard_fab2_lib.baseboard_fab2(sch_1):page109_i78:io182" )
			)
			( pin "J8G1.183"
				( objectStatus "@baseboard_fab2_lib.baseboard_fab2(sch_1):page109_i78:io183" )
			)
			( pin "J8G1.184"
				( objectStatus "@baseboard_fab2_lib.baseboard_fab2(sch_1):page109_i78:io184" )
			)
			( pin "J8G1.185"
				( objectStatus "@baseboard_fab2_lib.baseboard_fab2(sch_1):page109_i78:io185" )
			)
			( pin "J8G1.186"
				( objectStatus "@baseboard_fab2_lib.baseboard_fab2(sch_1):page109_i78:io186" )
			)
			( pin "J8G1.187"
				( objectStatus "@baseboard_fab2_lib.baseboard_fab2(sch_1):page109_i78:io187" )
			)
			( pin "J8G1.188"
				( objectStatus "@baseboard_fab2_lib.baseboard_fab2(sch_1):page109_i78:io188" )
			)
			( pin "J8G1.189"
				( objectStatus "@baseboard_fab2_lib.baseboard_fab2(sch_1):page109_i78:io189" )
			)
			( pin "J8G1.190"
				( objectStatus "@baseboard_fab2_lib.baseboard_fab2(sch_1):page109_i78:io190" )
			)
			( pin "J8G1.191"
				( objectStatus "@baseboard_fab2_lib.baseboard_fab2(sch_1):page109_i78:io191" )
			)
			( pin "J8G1.192"
				( objectStatus "@baseboard_fab2_lib.baseboard_fab2(sch_1):page109_i78:io192" )
			)
			( pin "J8G1.193"
				( objectStatus "@baseboard_fab2_lib.baseboard_fab2(sch_1):page109_i78:io193" )
			)
			( pin "J8G1.194"
				( objectStatus "@baseboard_fab2_lib.baseboard_fab2(sch_1):page109_i78:io194" )
			)
			( pin "J8G1.195"
				( objectStatus "@baseboard_fab2_lib.baseboard_fab2(sch_1):page109_i78:io195" )
			)
			( pin "J8G1.196"
				( objectStatus "@baseboard_fab2_lib.baseboard_fab2(sch_1):page109_i78:io196" )
			)
			( pin "J8G1.197"
				( objectStatus "@baseboard_fab2_lib.baseboard_fab2(sch_1):page109_i78:io197" )
			)
			( pin "J8G1.198"
				( objectStatus "@baseboard_fab2_lib.baseboard_fab2(sch_1):page109_i78:io198" )
			)
			( pin "J8G1.199"
				( objectStatus "@baseboard_fab2_lib.baseboard_fab2(sch_1):page109_i78:io199" )
			)
			( pin "J8G1.200"
				( objectStatus "@baseboard_fab2_lib.baseboard_fab2(sch_1):page109_i78:io200" )
			)
			( pin "RN8F5.1"
				( objectStatus "@baseboard_fab2_lib.baseboard_fab2(sch_1):page246_i9:a" )
			)
			( pin "RN8F5.2"
				( objectStatus "@baseboard_fab2_lib.baseboard_fab2(sch_1):page246_i9:b" )
			)
			( pin "RN8F3.1"
				( objectStatus "@baseboard_fab2_lib.baseboard_fab2(sch_1):page246_i11:a" )
			)
			( pin "RN8F3.2"
				( objectStatus "@baseboard_fab2_lib.baseboard_fab2(sch_1):page246_i11:b" )
			)
			( pin "RN8F4.1"
				( objectStatus "@baseboard_fab2_lib.baseboard_fab2(sch_1):page246_i12:a" )
			)
			( pin "RN8F4.2"
				( objectStatus "@baseboard_fab2_lib.baseboard_fab2(sch_1):page246_i12:b" )
			)
			( pin "C25W12.1"
				( objectStatus "@baseboard_fab2_lib.baseboard_fab2(sch_1):page151_i212:a" )
			)
			( pin "C25W12.2"
				( objectStatus "@baseboard_fab2_lib.baseboard_fab2(sch_1):page151_i212:b" )
			)
			( pin "C25W10.1"
				( objectStatus "@baseboard_fab2_lib.baseboard_fab2(sch_1):page151_i213:a" )
			)
			( pin "C25W10.2"
				( objectStatus "@baseboard_fab2_lib.baseboard_fab2(sch_1):page151_i213:b" )
			)
			( pin "UN8F2.16"
				( objectStatus "@baseboard_fab2_lib.baseboard_fab2(sch_1):page246_i17:clk" )
			)
			( pin "UN8F2.7"
				( objectStatus "@baseboard_fab2_lib.baseboard_fab2(sch_1):page246_i17:cs_n" )
			)
			( pin "UN8F2.15"
				( objectStatus "@baseboard_fab2_lib.baseboard_fab2(sch_1):page246_i17:di_io(0)" )
			)
			( pin "UN8F2.8"
				( objectStatus "@baseboard_fab2_lib.baseboard_fab2(sch_1):page246_i17:do_io(1)" )
			)
			( pin "UN8F2.10"
				( objectStatus "@baseboard_fab2_lib.baseboard_fab2(sch_1):page246_i17:gnd" )
			)
			( pin "UN8F2.1"
				( objectStatus "@baseboard_fab2_lib.baseboard_fab2(sch_1):page246_i17:hold_n_io(3)" )
			)
			( pin "UN8F2.14"
				( objectStatus "@baseboard_fab2_lib.baseboard_fab2(sch_1):page246_i17:nc(0)" )
			)
			( pin "UN8F2.13"
				( objectStatus "@baseboard_fab2_lib.baseboard_fab2(sch_1):page246_i17:nc(1)" )
			)
			( pin "UN8F2.12"
				( objectStatus "@baseboard_fab2_lib.baseboard_fab2(sch_1):page246_i17:nc(2)" )
			)
			( pin "UN8F2.11"
				( objectStatus "@baseboard_fab2_lib.baseboard_fab2(sch_1):page246_i17:nc(3)" )
			)
			( pin "UN8F2.6"
				( objectStatus "@baseboard_fab2_lib.baseboard_fab2(sch_1):page246_i17:nc(4)" )
			)
			( pin "UN8F2.5"
				( objectStatus "@baseboard_fab2_lib.baseboard_fab2(sch_1):page246_i17:nc(5)" )
			)
			( pin "UN8F2.4"
				( objectStatus "@baseboard_fab2_lib.baseboard_fab2(sch_1):page246_i17:nc(6)" )
			)
			( pin "UN8F2.3"
				( objectStatus "@baseboard_fab2_lib.baseboard_fab2(sch_1):page246_i17:reset_n" )
			)
			( pin "UN8F2.2"
				( objectStatus "@baseboard_fab2_lib.baseboard_fab2(sch_1):page246_i17:vcc" )
			)
			( pin "UN8F2.9"
				( objectStatus "@baseboard_fab2_lib.baseboard_fab2(sch_1):page246_i17:wp_n_io(2)" )
			)
			( pin "Q6W1.3"
				( objectStatus "@baseboard_fab2_lib.baseboard_fab2(sch_1):page200_i225:drn" )
			)
			( pin "Q6W1.1"
				( objectStatus "@baseboard_fab2_lib.baseboard_fab2(sch_1):page200_i225:gate" )
			)
			( pin "Q6W1.2"
				( objectStatus "@baseboard_fab2_lib.baseboard_fab2(sch_1):page200_i225:src" )
			)
			( pin "R6W10.1"
				( objectStatus "@baseboard_fab2_lib.baseboard_fab2(sch_1):page247_i1:a" )
			)
			( pin "R6W10.2"
				( objectStatus "@baseboard_fab2_lib.baseboard_fab2(sch_1):page247_i1:b" )
			)
			( pin "R7F21.1"
				( objectStatus "@baseboard_fab2_lib.baseboard_fab2(sch_1):page215_i13:a" )
			)
			( pin "R7F21.2"
				( objectStatus "@baseboard_fab2_lib.baseboard_fab2(sch_1):page215_i13:b" )
			)
			( pin "R7G9.1"
				( objectStatus "@baseboard_fab2_lib.baseboard_fab2(sch_1):page215_i12:a" )
			)
			( pin "R7G9.2"
				( objectStatus "@baseboard_fab2_lib.baseboard_fab2(sch_1):page215_i12:b" )
			)
			( pin "C8W2.1"
				( objectStatus "@baseboard_fab2_lib.baseboard_fab2(sch_1):page249_i37:a" )
			)
			( pin "C8W2.2"
				( objectStatus "@baseboard_fab2_lib.baseboard_fab2(sch_1):page249_i37:b" )
			)
			( pin "R10W7.1"
				( objectStatus "@baseboard_fab2_lib.baseboard_fab2(sch_1):page251_i31:a" )
			)
			( pin "R10W7.2"
				( objectStatus "@baseboard_fab2_lib.baseboard_fab2(sch_1):page251_i31:b" )
			)
			( pin "C10W5.1"
				( objectStatus "@baseboard_fab2_lib.baseboard_fab2(sch_1):page251_i29:a" )
			)
			( pin "C10W5.2"
				( objectStatus "@baseboard_fab2_lib.baseboard_fab2(sch_1):page251_i29:b" )
			)
			( pin "R10W6.1"
				( objectStatus "@baseboard_fab2_lib.baseboard_fab2(sch_1):page251_i27:a" )
			)
			( pin "R10W6.2"
				( objectStatus "@baseboard_fab2_lib.baseboard_fab2(sch_1):page251_i27:b" )
			)
			( pin "J1B2.1"
				( objectStatus "@baseboard_fab2_lib.baseboard_fab2(sch_1):page251_i25:io1" )
			)
			( pin "J1B2.2"
				( objectStatus "@baseboard_fab2_lib.baseboard_fab2(sch_1):page251_i25:io2" )
			)
			( pin "J1B2.3"
				( objectStatus "@baseboard_fab2_lib.baseboard_fab2(sch_1):page251_i25:io3" )
			)
			( pin "J1B2.4"
				( objectStatus "@baseboard_fab2_lib.baseboard_fab2(sch_1):page251_i25:io4" )
			)
			( pin "J1B2.5"
				( objectStatus "@baseboard_fab2_lib.baseboard_fab2(sch_1):page251_i25:io5" )
			)
			( pin "J1B2.6"
				( objectStatus "@baseboard_fab2_lib.baseboard_fab2(sch_1):page251_i25:io6" )
			)
			( pin "R25W63.1"
				( objectStatus "@baseboard_fab2_lib.baseboard_fab2(sch_1):page146_i65:a" )
			)
			( pin "R25W63.2"
				( objectStatus "@baseboard_fab2_lib.baseboard_fab2(sch_1):page146_i65:b" )
			)
			( pin "Q6W2.1"
				( objectStatus "@baseboard_fab2_lib.baseboard_fab2(sch_1):page168_i47:b" )
			)
			( pin "Q6W2.3"
				( objectStatus "@baseboard_fab2_lib.baseboard_fab2(sch_1):page168_i47:c" )
			)
			( pin "Q6W2.2"
				( objectStatus "@baseboard_fab2_lib.baseboard_fab2(sch_1):page168_i47:e" )
			)
			( pin "U6W11.1"
				( objectStatus "@baseboard_fab2_lib.baseboard_fab2(sch_1):page164_i97:a0" )
			)
			( pin "U6W11.2"
				( objectStatus "@baseboard_fab2_lib.baseboard_fab2(sch_1):page164_i97:a1" )
			)
			( pin "U6W11.3"
				( objectStatus "@baseboard_fab2_lib.baseboard_fab2(sch_1):page164_i97:a2" )
			)
			( pin "U6W11.8"
				( objectStatus "@baseboard_fab2_lib.baseboard_fab2(sch_1):page164_i97:gnd" )
			)
			( pin "U6W11.13"
				( objectStatus "@baseboard_fab2_lib.baseboard_fab2(sch_1):page164_i97:\int#\" )
			)
			( pin "U6W11.4"
				( objectStatus "@baseboard_fab2_lib.baseboard_fab2(sch_1):page164_i97:p0" )
			)
			( pin "U6W11.5"
				( objectStatus "@baseboard_fab2_lib.baseboard_fab2(sch_1):page164_i97:p1" )
			)
			( pin "U6W11.6"
				( objectStatus "@baseboard_fab2_lib.baseboard_fab2(sch_1):page164_i97:p2" )
			)
			( pin "U6W11.7"
				( objectStatus "@baseboard_fab2_lib.baseboard_fab2(sch_1):page164_i97:p3" )
			)
			( pin "U6W11.9"
				( objectStatus "@baseboard_fab2_lib.baseboard_fab2(sch_1):page164_i97:p4" )
			)
			( pin "U6W11.10"
				( objectStatus "@baseboard_fab2_lib.baseboard_fab2(sch_1):page164_i97:p5" )
			)
			( pin "U6W11.11"
				( objectStatus "@baseboard_fab2_lib.baseboard_fab2(sch_1):page164_i97:p6" )
			)
			( pin "U6W11.12"
				( objectStatus "@baseboard_fab2_lib.baseboard_fab2(sch_1):page164_i97:p7" )
			)
			( pin "U6W11.14"
				( objectStatus "@baseboard_fab2_lib.baseboard_fab2(sch_1):page164_i97:scl" )
			)
			( pin "U6W11.15"
				( objectStatus "@baseboard_fab2_lib.baseboard_fab2(sch_1):page164_i97:sda" )
			)
			( pin "U6W11.16"
				( objectStatus "@baseboard_fab2_lib.baseboard_fab2(sch_1):page164_i97:vcc" )
			)
			( pin "R25W58.1"
				( objectStatus "@baseboard_fab2_lib.baseboard_fab2(sch_1):page144_i150:\1\" )
			)
			( pin "R25W58.2"
				( objectStatus "@baseboard_fab2_lib.baseboard_fab2(sch_1):page144_i150:\2\" )
			)
			( pin "R3W1.1"
				( objectStatus "@baseboard_fab2_lib.baseboard_fab2(sch_1):page249_i2:a" )
			)
			( pin "R3W1.2"
				( objectStatus "@baseboard_fab2_lib.baseboard_fab2(sch_1):page249_i2:b" )
			)
			( pin "R3W9.1"
				( objectStatus "@baseboard_fab2_lib.baseboard_fab2(sch_1):page249_i7:a" )
			)
			( pin "R3W9.2"
				( objectStatus "@baseboard_fab2_lib.baseboard_fab2(sch_1):page249_i7:b" )
			)
			( pin "R3W7.1"
				( objectStatus "@baseboard_fab2_lib.baseboard_fab2(sch_1):page249_i8:a" )
			)
			( pin "R3W7.2"
				( objectStatus "@baseboard_fab2_lib.baseboard_fab2(sch_1):page249_i8:b" )
			)
			( pin "R3W4.1"
				( objectStatus "@baseboard_fab2_lib.baseboard_fab2(sch_1):page249_i31:\1\" )
			)
			( pin "R3W4.2"
				( objectStatus "@baseboard_fab2_lib.baseboard_fab2(sch_1):page249_i31:\2\" )
			)
			( pin "Q9W4.1"
				( objectStatus "@baseboard_fab2_lib.baseboard_fab2(sch_1):page249_i15:\+in\" )
			)
			( pin "Q9W4.3"
				( objectStatus "@baseboard_fab2_lib.baseboard_fab2(sch_1):page249_i15:\-in\" )
			)
			( pin "Q9W4.2"
				( objectStatus "@baseboard_fab2_lib.baseboard_fab2(sch_1):page249_i15:gnd" )
			)
			( pin "Q9W4.4"
				( objectStatus "@baseboard_fab2_lib.baseboard_fab2(sch_1):page249_i15:\out\" )
			)
			( pin "Q9W4.5"
				( objectStatus "@baseboard_fab2_lib.baseboard_fab2(sch_1):page249_i15:vcc" )
			)
			( pin "R3P53.1"
				( objectStatus "@baseboard_fab2_lib.baseboard_fab2(sch_1):page133_i365:a" )
			)
			( pin "R3P53.2"
				( objectStatus "@baseboard_fab2_lib.baseboard_fab2(sch_1):page133_i365:b" )
			)
			( pin "C25W13.1"
				( objectStatus "@baseboard_fab2_lib.baseboard_fab2(sch_1):page151_i217:a" )
			)
			( pin "C25W13.2"
				( objectStatus "@baseboard_fab2_lib.baseboard_fab2(sch_1):page151_i217:b" )
			)
			( pin "R3W6.1"
				( objectStatus "@baseboard_fab2_lib.baseboard_fab2(sch_1):page249_i48:a" )
			)
			( pin "R3W6.2"
				( objectStatus "@baseboard_fab2_lib.baseboard_fab2(sch_1):page249_i48:b" )
			)
			( pin "C3W2.1"
				( objectStatus "@baseboard_fab2_lib.baseboard_fab2(sch_1):page249_i57:a" )
			)
			( pin "C3W2.2"
				( objectStatus "@baseboard_fab2_lib.baseboard_fab2(sch_1):page249_i57:b" )
			)
			( pin "Q9W2.1"
				( objectStatus "@baseboard_fab2_lib.baseboard_fab2(sch_1):page249_i29:b" )
			)
			( pin "Q9W2.3"
				( objectStatus "@baseboard_fab2_lib.baseboard_fab2(sch_1):page249_i29:c" )
			)
			( pin "Q9W2.2"
				( objectStatus "@baseboard_fab2_lib.baseboard_fab2(sch_1):page249_i29:e" )
			)
			( pin "U14E2.1"
				( objectStatus "@baseboard_fab2_lib.baseboard_fab2(sch_1):page248_i11:a(0)" )
			)
			( pin "U14E2.2"
				( objectStatus "@baseboard_fab2_lib.baseboard_fab2(sch_1):page248_i11:b(0)" )
			)
			( pin "U14E2.4"
				( objectStatus "@baseboard_fab2_lib.baseboard_fab2(sch_1):page248_i11:y(0)" )
			)
			( pin "R6W17.1"
				( objectStatus "@baseboard_fab2_lib.baseboard_fab2(sch_1):page145_i120:a" )
			)
			( pin "R6W17.2"
				( objectStatus "@baseboard_fab2_lib.baseboard_fab2(sch_1):page145_i120:b" )
			)
			( pin "R25W65.1"
				( objectStatus "@baseboard_fab2_lib.baseboard_fab2(sch_1):page145_i38:a" )
			)
			( pin "R25W65.2"
				( objectStatus "@baseboard_fab2_lib.baseboard_fab2(sch_1):page145_i38:b" )
			)
			( pin "R25W64.1"
				( objectStatus "@baseboard_fab2_lib.baseboard_fab2(sch_1):page145_i36:a" )
			)
			( pin "R25W64.2"
				( objectStatus "@baseboard_fab2_lib.baseboard_fab2(sch_1):page145_i36:b" )
			)
			( pin "R25W23.1"
				( objectStatus "@baseboard_fab2_lib.baseboard_fab2(sch_1):page151_i269:\1\" )
			)
			( pin "R25W23.2"
				( objectStatus "@baseboard_fab2_lib.baseboard_fab2(sch_1):page151_i269:\2\" )
			)
			( pin "R9E24.1"
				( objectStatus "@baseboard_fab2_lib.baseboard_fab2(sch_1):page151_i138:a" )
			)
			( pin "R9E24.2"
				( objectStatus "@baseboard_fab2_lib.baseboard_fab2(sch_1):page151_i138:b" )
			)
			( pin "C9F23.1"
				( objectStatus "@baseboard_fab2_lib.baseboard_fab2(sch_1):page145_i15:a" )
			)
			( pin "C9F23.2"
				( objectStatus "@baseboard_fab2_lib.baseboard_fab2(sch_1):page145_i15:b" )
			)
			( pin "R9F33.1"
				( objectStatus "@baseboard_fab2_lib.baseboard_fab2(sch_1):page145_i20:a" )
			)
			( pin "R9F33.2"
				( objectStatus "@baseboard_fab2_lib.baseboard_fab2(sch_1):page145_i20:b" )
			)
			( pin "R12W5.1"
				( objectStatus "@baseboard_fab2_lib.baseboard_fab2(sch_1):page197_i111:\1\" )
			)
			( pin "R12W5.2"
				( objectStatus "@baseboard_fab2_lib.baseboard_fab2(sch_1):page197_i111:\2\" )
			)
			( pin "C25W8.1"
				( objectStatus "@baseboard_fab2_lib.baseboard_fab2(sch_1):page147_i162:a" )
			)
			( pin "C25W8.2"
				( objectStatus "@baseboard_fab2_lib.baseboard_fab2(sch_1):page147_i162:b" )
			)
			( pin "R25W61.1"
				( objectStatus "@baseboard_fab2_lib.baseboard_fab2(sch_1):page145_i30:a" )
			)
			( pin "R25W61.2"
				( objectStatus "@baseboard_fab2_lib.baseboard_fab2(sch_1):page145_i30:b" )
			)
			( pin "R25W62.1"
				( objectStatus "@baseboard_fab2_lib.baseboard_fab2(sch_1):page145_i31:a" )
			)
			( pin "R25W62.2"
				( objectStatus "@baseboard_fab2_lib.baseboard_fab2(sch_1):page145_i31:b" )
			)
			( pin "R6W24.1"
				( objectStatus "@baseboard_fab2_lib.baseboard_fab2(sch_1):page247_i100:a" )
			)
			( pin "R6W24.2"
				( objectStatus "@baseboard_fab2_lib.baseboard_fab2(sch_1):page247_i100:b" )
			)
			( pin "R25W107.1"
				( objectStatus "@baseboard_fab2_lib.baseboard_fab2(sch_1):page150_i190:a" )
			)
			( pin "R25W107.2"
				( objectStatus "@baseboard_fab2_lib.baseboard_fab2(sch_1):page150_i190:b" )
			)
			( pin "R9E14.1"
				( objectStatus "@baseboard_fab2_lib.baseboard_fab2(sch_1):page157_i393:a" )
			)
			( pin "R9E14.2"
				( objectStatus "@baseboard_fab2_lib.baseboard_fab2(sch_1):page157_i393:b" )
			)
			( pin "RT29.1"
				( objectStatus "@baseboard_fab2_lib.baseboard_fab2(sch_1):page219_i153:\1\" )
			)
			( pin "RT29.2"
				( objectStatus "@baseboard_fab2_lib.baseboard_fab2(sch_1):page219_i153:\2\" )
			)
			( pin "R9F29.1"
				( objectStatus "@baseboard_fab2_lib.baseboard_fab2(sch_1):page151_i55:a" )
			)
			( pin "R9F29.2"
				( objectStatus "@baseboard_fab2_lib.baseboard_fab2(sch_1):page151_i55:b" )
			)
			( pin "R25W95.1"
				( objectStatus "@baseboard_fab2_lib.baseboard_fab2(sch_1):page150_i144:a" )
			)
			( pin "R25W95.2"
				( objectStatus "@baseboard_fab2_lib.baseboard_fab2(sch_1):page150_i144:b" )
			)
			( pin "R25W96.1"
				( objectStatus "@baseboard_fab2_lib.baseboard_fab2(sch_1):page150_i145:a" )
			)
			( pin "R25W96.2"
				( objectStatus "@baseboard_fab2_lib.baseboard_fab2(sch_1):page150_i145:b" )
			)
			( pin "R25W97.1"
				( objectStatus "@baseboard_fab2_lib.baseboard_fab2(sch_1):page150_i146:a" )
			)
			( pin "R25W97.2"
				( objectStatus "@baseboard_fab2_lib.baseboard_fab2(sch_1):page150_i146:b" )
			)
			( pin "R25W151.1"
				( objectStatus "@baseboard_fab2_lib.baseboard_fab2(sch_1):page150_i232:a" )
			)
			( pin "R25W151.2"
				( objectStatus "@baseboard_fab2_lib.baseboard_fab2(sch_1):page150_i232:b" )
			)
			( pin "R25W113.1"
				( objectStatus "@baseboard_fab2_lib.baseboard_fab2(sch_1):page150_i230:a" )
			)
			( pin "R25W113.2"
				( objectStatus "@baseboard_fab2_lib.baseboard_fab2(sch_1):page150_i230:b" )
			)
			( pin "R25W112.1"
				( objectStatus "@baseboard_fab2_lib.baseboard_fab2(sch_1):page150_i228:a" )
			)
			( pin "R25W112.2"
				( objectStatus "@baseboard_fab2_lib.baseboard_fab2(sch_1):page150_i228:b" )
			)
			( pin "R25W102.1"
				( objectStatus "@baseboard_fab2_lib.baseboard_fab2(sch_1):page150_i239:a" )
			)
			( pin "R25W102.2"
				( objectStatus "@baseboard_fab2_lib.baseboard_fab2(sch_1):page150_i239:b" )
			)
			( pin "R25W142.1"
				( objectStatus "@baseboard_fab2_lib.baseboard_fab2(sch_1):page147_i156:a" )
			)
			( pin "R25W142.2"
				( objectStatus "@baseboard_fab2_lib.baseboard_fab2(sch_1):page147_i156:b" )
			)
			( pin "R25W106.1"
				( objectStatus "@baseboard_fab2_lib.baseboard_fab2(sch_1):page150_i175:a" )
			)
			( pin "R25W106.2"
				( objectStatus "@baseboard_fab2_lib.baseboard_fab2(sch_1):page150_i175:b" )
			)
			( pin "RT18.1"
				( objectStatus "@baseboard_fab2_lib.baseboard_fab2(sch_1):page207_i112:\1\" )
			)
			( pin "RT18.2"
				( objectStatus "@baseboard_fab2_lib.baseboard_fab2(sch_1):page207_i112:\2\" )
			)
			( pin "RT39.1"
				( objectStatus "@baseboard_fab2_lib.baseboard_fab2(sch_1):page205_i84:\1\" )
			)
			( pin "RT39.2"
				( objectStatus "@baseboard_fab2_lib.baseboard_fab2(sch_1):page205_i84:\2\" )
			)
			( pin "U25W5.P3"
				( objectStatus "@baseboard_fab2_lib.baseboard_fab2(sch_1):page151_i49:a0" )
			)
			( pin "U25W5.P7"
				( objectStatus "@baseboard_fab2_lib.baseboard_fab2(sch_1):page151_i49:a1" )
			)
			( pin "U25W5.R3"
				( objectStatus "@baseboard_fab2_lib.baseboard_fab2(sch_1):page151_i49:a2" )
			)
			( pin "U25W5.N7"
				( objectStatus "@baseboard_fab2_lib.baseboard_fab2(sch_1):page151_i49:a3" )
			)
			( pin "U25W5.N3"
				( objectStatus "@baseboard_fab2_lib.baseboard_fab2(sch_1):page151_i49:a4" )
			)
			( pin "U25W5.P8"
				( objectStatus "@baseboard_fab2_lib.baseboard_fab2(sch_1):page151_i49:a5" )
			)
			( pin "U25W5.P2"
				( objectStatus "@baseboard_fab2_lib.baseboard_fab2(sch_1):page151_i49:a6" )
			)
			( pin "U25W5.R8"
				( objectStatus "@baseboard_fab2_lib.baseboard_fab2(sch_1):page151_i49:a7" )
			)
			( pin "U25W5.R2"
				( objectStatus "@baseboard_fab2_lib.baseboard_fab2(sch_1):page151_i49:a8" )
			)
			( pin "U25W5.R7"
				( objectStatus "@baseboard_fab2_lib.baseboard_fab2(sch_1):page151_i49:a9" )
			)
			( pin "U25W5.M3"
				( objectStatus "@baseboard_fab2_lib.baseboard_fab2(sch_1):page151_i49:\a10/ap\" )
			)
			( pin "U25W5.T2"
				( objectStatus "@baseboard_fab2_lib.baseboard_fab2(sch_1):page151_i49:a11" )
			)
			( pin "U25W5.M7"
				( objectStatus "@baseboard_fab2_lib.baseboard_fab2(sch_1):page151_i49:\a12/bc#\" )
			)
			( pin "U25W5.T8"
				( objectStatus "@baseboard_fab2_lib.baseboard_fab2(sch_1):page151_i49:a13" )
			)
			( pin "U25W5.L3"
				( objectStatus "@baseboard_fab2_lib.baseboard_fab2(sch_1):page151_i49:\act#\" )
			)
			( pin "U25W5.P9"
				( objectStatus "@baseboard_fab2_lib.baseboard_fab2(sch_1):page151_i49:\alert#\" )
			)
			( pin "U25W5.N2"
				( objectStatus "@baseboard_fab2_lib.baseboard_fab2(sch_1):page151_i49:ba0" )
			)
			( pin "U25W5.N8"
				( objectStatus "@baseboard_fab2_lib.baseboard_fab2(sch_1):page151_i49:ba1" )
			)
			( pin "U25W5.M2"
				( objectStatus "@baseboard_fab2_lib.baseboard_fab2(sch_1):page151_i49:bg0" )
			)
			( pin "U25W5.M8"
				( objectStatus "@baseboard_fab2_lib.baseboard_fab2(sch_1):page151_i49:\cas#/a15\" )
			)
			( pin "U25W5.K8"
				( objectStatus "@baseboard_fab2_lib.baseboard_fab2(sch_1):page151_i49:ck_c" )
			)
			( pin "U25W5.K7"
				( objectStatus "@baseboard_fab2_lib.baseboard_fab2(sch_1):page151_i49:ck_t" )
			)
			( pin "U25W5.K2"
				( objectStatus "@baseboard_fab2_lib.baseboard_fab2(sch_1):page151_i49:cke" )
			)
			( pin "U25W5.L7"
				( objectStatus "@baseboard_fab2_lib.baseboard_fab2(sch_1):page151_i49:\cs#\" )
			)
			( pin "U25W5.E7"
				( objectStatus "@baseboard_fab2_lib.baseboard_fab2(sch_1):page151_i49:\dml#/dbil#\" )
			)
			( pin "U25W5.E2"
				( objectStatus "@baseboard_fab2_lib.baseboard_fab2(sch_1):page151_i49:\dmu#/dbiu#\" )
			)
			( pin "U25W5.G2"
				( objectStatus "@baseboard_fab2_lib.baseboard_fab2(sch_1):page151_i49:dql0" )
			)
			( pin "U25W5.F7"
				( objectStatus "@baseboard_fab2_lib.baseboard_fab2(sch_1):page151_i49:dql1" )
			)
			( pin "U25W5.H3"
				( objectStatus "@baseboard_fab2_lib.baseboard_fab2(sch_1):page151_i49:dql2" )
			)
			( pin "U25W5.H7"
				( objectStatus "@baseboard_fab2_lib.baseboard_fab2(sch_1):page151_i49:dql3" )
			)
			( pin "U25W5.H2"
				( objectStatus "@baseboard_fab2_lib.baseboard_fab2(sch_1):page151_i49:dql4" )
			)
			( pin "U25W5.H8"
				( objectStatus "@baseboard_fab2_lib.baseboard_fab2(sch_1):page151_i49:dql5" )
			)
			( pin "U25W5.J3"
				( objectStatus "@baseboard_fab2_lib.baseboard_fab2(sch_1):page151_i49:dql6" )
			)
			( pin "U25W5.J7"
				( objectStatus "@baseboard_fab2_lib.baseboard_fab2(sch_1):page151_i49:dql7" )
			)
			( pin "U25W5.F3"
				( objectStatus "@baseboard_fab2_lib.baseboard_fab2(sch_1):page151_i49:dqsl_c" )
			)
			( pin "U25W5.G3"
				( objectStatus "@baseboard_fab2_lib.baseboard_fab2(sch_1):page151_i49:dqsl_t" )
			)
			( pin "U25W5.A7"
				( objectStatus "@baseboard_fab2_lib.baseboard_fab2(sch_1):page151_i49:dqsu_c" )
			)
			( pin "U25W5.B7"
				( objectStatus "@baseboard_fab2_lib.baseboard_fab2(sch_1):page151_i49:dqsu_t" )
			)
			( pin "U25W5.A3"
				( objectStatus "@baseboard_fab2_lib.baseboard_fab2(sch_1):page151_i49:dqu0" )
			)
			( pin "U25W5.B8"
				( objectStatus "@baseboard_fab2_lib.baseboard_fab2(sch_1):page151_i49:dqu1" )
			)
			( pin "U25W5.C3"
				( objectStatus "@baseboard_fab2_lib.baseboard_fab2(sch_1):page151_i49:dqu2" )
			)
			( pin "U25W5.C7"
				( objectStatus "@baseboard_fab2_lib.baseboard_fab2(sch_1):page151_i49:dqu3" )
			)
			( pin "U25W5.C2"
				( objectStatus "@baseboard_fab2_lib.baseboard_fab2(sch_1):page151_i49:dqu4" )
			)
			( pin "U25W5.C8"
				( objectStatus "@baseboard_fab2_lib.baseboard_fab2(sch_1):page151_i49:dqu5" )
			)
			( pin "U25W5.D3"
				( objectStatus "@baseboard_fab2_lib.baseboard_fab2(sch_1):page151_i49:dqu6" )
			)
			( pin "U25W5.D7"
				( objectStatus "@baseboard_fab2_lib.baseboard_fab2(sch_1):page151_i49:dqu7" )
			)
			( pin "U25W5.T7"
				( objectStatus "@baseboard_fab2_lib.baseboard_fab2(sch_1):page151_i49:\nc#t7\" )
			)
			( pin "U25W5.K3"
				( objectStatus "@baseboard_fab2_lib.baseboard_fab2(sch_1):page151_i49:odt" )
			)
			( pin "U25W5.T3"
				( objectStatus "@baseboard_fab2_lib.baseboard_fab2(sch_1):page151_i49:par" )
			)
			( pin "U25W5.L8"
				( objectStatus "@baseboard_fab2_lib.baseboard_fab2(sch_1):page151_i49:\ras#/a16\" )
			)
			( pin "U25W5.P1"
				( objectStatus "@baseboard_fab2_lib.baseboard_fab2(sch_1):page151_i49:\reset#\" )
			)
			( pin "U25W5.N9"
				( objectStatus "@baseboard_fab2_lib.baseboard_fab2(sch_1):page151_i49:ten" )
			)
			( pin "U25W5.B3"
				( objectStatus "@baseboard_fab2_lib.baseboard_fab2(sch_1):page151_i49:vdd(0)" )
			)
			( pin "U25W5.B9"
				( objectStatus "@baseboard_fab2_lib.baseboard_fab2(sch_1):page151_i49:vdd(1)" )
			)
			( pin "U25W5.D1"
				( objectStatus "@baseboard_fab2_lib.baseboard_fab2(sch_1):page151_i49:vdd(2)" )
			)
			( pin "U25W5.G7"
				( objectStatus "@baseboard_fab2_lib.baseboard_fab2(sch_1):page151_i49:vdd(3)" )
			)
			( pin "U25W5.J1"
				( objectStatus "@baseboard_fab2_lib.baseboard_fab2(sch_1):page151_i49:vdd(4)" )
			)
			( pin "U25W5.J9"
				( objectStatus "@baseboard_fab2_lib.baseboard_fab2(sch_1):page151_i49:vdd(5)" )
			)
			( pin "U25W5.L1"
				( objectStatus "@baseboard_fab2_lib.baseboard_fab2(sch_1):page151_i49:vdd(6)" )
			)
			( pin "U25W5.L9"
				( objectStatus "@baseboard_fab2_lib.baseboard_fab2(sch_1):page151_i49:vdd(7)" )
			)
			( pin "U25W5.R1"
				( objectStatus "@baseboard_fab2_lib.baseboard_fab2(sch_1):page151_i49:vdd(8)" )
			)
			( pin "U25W5.T9"
				( objectStatus "@baseboard_fab2_lib.baseboard_fab2(sch_1):page151_i49:vdd(9)" )
			)
			( pin "U25W5.A1"
				( objectStatus "@baseboard_fab2_lib.baseboard_fab2(sch_1):page151_i49:vddq(0)" )
			)
			( pin "U25W5.A9"
				( objectStatus "@baseboard_fab2_lib.baseboard_fab2(sch_1):page151_i49:vddq(1)" )
			)
			( pin "U25W5.C1"
				( objectStatus "@baseboard_fab2_lib.baseboard_fab2(sch_1):page151_i49:vddq(2)" )
			)
			( pin "U25W5.D9"
				( objectStatus "@baseboard_fab2_lib.baseboard_fab2(sch_1):page151_i49:vddq(3)" )
			)
			( pin "U25W5.F2"
				( objectStatus "@baseboard_fab2_lib.baseboard_fab2(sch_1):page151_i49:vddq(4)" )
			)
			( pin "U25W5.F8"
				( objectStatus "@baseboard_fab2_lib.baseboard_fab2(sch_1):page151_i49:vddq(5)" )
			)
			( pin "U25W5.G1"
				( objectStatus "@baseboard_fab2_lib.baseboard_fab2(sch_1):page151_i49:vddq(6)" )
			)
			( pin "U25W5.G9"
				( objectStatus "@baseboard_fab2_lib.baseboard_fab2(sch_1):page151_i49:vddq(7)" )
			)
			( pin "U25W5.J2"
				( objectStatus "@baseboard_fab2_lib.baseboard_fab2(sch_1):page151_i49:vddq(8)" )
			)
			( pin "U25W5.J8"
				( objectStatus "@baseboard_fab2_lib.baseboard_fab2(sch_1):page151_i49:vddq(9)" )
			)
			( pin "U25W5.B1"
				( objectStatus "@baseboard_fab2_lib.baseboard_fab2(sch_1):page151_i49:vpp(0)" )
			)
			( pin "U25W5.R9"
				( objectStatus "@baseboard_fab2_lib.baseboard_fab2(sch_1):page151_i49:vpp(1)" )
			)
			( pin "U25W5.M1"
				( objectStatus "@baseboard_fab2_lib.baseboard_fab2(sch_1):page151_i49:vrefca" )
			)
			( pin "U25W5.B2"
				( objectStatus "@baseboard_fab2_lib.baseboard_fab2(sch_1):page151_i49:vss(0)" )
			)
			( pin "U25W5.E1"
				( objectStatus "@baseboard_fab2_lib.baseboard_fab2(sch_1):page151_i49:vss(1)" )
			)
			( pin "U25W5.E9"
				( objectStatus "@baseboard_fab2_lib.baseboard_fab2(sch_1):page151_i49:vss(2)" )
			)
			( pin "U25W5.G8"
				( objectStatus "@baseboard_fab2_lib.baseboard_fab2(sch_1):page151_i49:vss(3)" )
			)
			( pin "U25W5.K1"
				( objectStatus "@baseboard_fab2_lib.baseboard_fab2(sch_1):page151_i49:vss(4)" )
			)
			( pin "U25W5.K9"
				( objectStatus "@baseboard_fab2_lib.baseboard_fab2(sch_1):page151_i49:vss(5)" )
			)
			( pin "U25W5.M9"
				( objectStatus "@baseboard_fab2_lib.baseboard_fab2(sch_1):page151_i49:vss(6)" )
			)
			( pin "U25W5.N1"
				( objectStatus "@baseboard_fab2_lib.baseboard_fab2(sch_1):page151_i49:vss(7)" )
			)
			( pin "U25W5.T1"
				( objectStatus "@baseboard_fab2_lib.baseboard_fab2(sch_1):page151_i49:vss(8)" )
			)
			( pin "U25W5.A2"
				( objectStatus "@baseboard_fab2_lib.baseboard_fab2(sch_1):page151_i49:vssq(0)" )
			)
			( pin "U25W5.A8"
				( objectStatus "@baseboard_fab2_lib.baseboard_fab2(sch_1):page151_i49:vssq(1)" )
			)
			( pin "U25W5.C9"
				( objectStatus "@baseboard_fab2_lib.baseboard_fab2(sch_1):page151_i49:vssq(2)" )
			)
			( pin "U25W5.D2"
				( objectStatus "@baseboard_fab2_lib.baseboard_fab2(sch_1):page151_i49:vssq(3)" )
			)
			( pin "U25W5.D8"
				( objectStatus "@baseboard_fab2_lib.baseboard_fab2(sch_1):page151_i49:vssq(4)" )
			)
			( pin "U25W5.E3"
				( objectStatus "@baseboard_fab2_lib.baseboard_fab2(sch_1):page151_i49:vssq(5)" )
			)
			( pin "U25W5.E8"
				( objectStatus "@baseboard_fab2_lib.baseboard_fab2(sch_1):page151_i49:vssq(6)" )
			)
			( pin "U25W5.F1"
				( objectStatus "@baseboard_fab2_lib.baseboard_fab2(sch_1):page151_i49:vssq(7)" )
			)
			( pin "U25W5.H1"
				( objectStatus "@baseboard_fab2_lib.baseboard_fab2(sch_1):page151_i49:vssq(8)" )
			)
			( pin "U25W5.H9"
				( objectStatus "@baseboard_fab2_lib.baseboard_fab2(sch_1):page151_i49:vssq(9)" )
			)
			( pin "U25W5.L2"
				( objectStatus "@baseboard_fab2_lib.baseboard_fab2(sch_1):page151_i49:\we#/a14\" )
			)
			( pin "U25W5.F9"
				( objectStatus "@baseboard_fab2_lib.baseboard_fab2(sch_1):page151_i49:zq" )
			)
			( pin "R6W19.1"
				( objectStatus "@baseboard_fab2_lib.baseboard_fab2(sch_1):page155_i196:a" )
			)
			( pin "R6W19.2"
				( objectStatus "@baseboard_fab2_lib.baseboard_fab2(sch_1):page155_i196:b" )
			)
			( pin "R25W82.1"
				( objectStatus "@baseboard_fab2_lib.baseboard_fab2(sch_1):page146_i68:a" )
			)
			( pin "R25W82.2"
				( objectStatus "@baseboard_fab2_lib.baseboard_fab2(sch_1):page146_i68:b" )
			)
			( pin "C25W30.1"
				( objectStatus "@baseboard_fab2_lib.baseboard_fab2(sch_1):page149_i1:a" )
			)
			( pin "C25W30.2"
				( objectStatus "@baseboard_fab2_lib.baseboard_fab2(sch_1):page149_i1:b" )
			)
			( pin "EU25F2.4"
				( objectStatus "@baseboard_fab2_lib.baseboard_fab2(sch_1):page239_i73:adj_nc" )
			)
			( pin "EU25F2.6"
				( objectStatus "@baseboard_fab2_lib.baseboard_fab2(sch_1):page239_i73:en" )
			)
			( pin "EU25F2.11"
				( objectStatus "@baseboard_fab2_lib.baseboard_fab2(sch_1):page239_i73:gnd" )
			)
			( pin "EU25F2.5"
				( objectStatus "@baseboard_fab2_lib.baseboard_fab2(sch_1):page239_i73:pgood" )
			)
			( pin "EU25F2.10"
				( objectStatus "@baseboard_fab2_lib.baseboard_fab2(sch_1):page239_i73:vdd" )
			)
			( pin "EU25F2.7"
				( objectStatus "@baseboard_fab2_lib.baseboard_fab2(sch_1):page239_i73:vin(0)" )
			)
			( pin "EU25F2.8"
				( objectStatus "@baseboard_fab2_lib.baseboard_fab2(sch_1):page239_i73:vin(1)" )
			)
			( pin "EU25F2.9"
				( objectStatus "@baseboard_fab2_lib.baseboard_fab2(sch_1):page239_i73:vin(2)" )
			)
			( pin "EU25F2.1"
				( objectStatus "@baseboard_fab2_lib.baseboard_fab2(sch_1):page239_i73:vout(0)" )
			)
			( pin "EU25F2.2"
				( objectStatus "@baseboard_fab2_lib.baseboard_fab2(sch_1):page239_i73:vout(1)" )
			)
			( pin "EU25F2.3"
				( objectStatus "@baseboard_fab2_lib.baseboard_fab2(sch_1):page239_i73:vout(2)" )
			)
			( pin "R1W9.1"
				( objectStatus "@baseboard_fab2_lib.baseboard_fab2(sch_1):page239_i77:a" )
			)
			( pin "R1W9.2"
				( objectStatus "@baseboard_fab2_lib.baseboard_fab2(sch_1):page239_i77:b" )
			)
			( pin "R9W12.1"
				( objectStatus "@baseboard_fab2_lib.baseboard_fab2(sch_1):page239_i79:a" )
			)
			( pin "R9W12.2"
				( objectStatus "@baseboard_fab2_lib.baseboard_fab2(sch_1):page239_i79:b" )
			)
			( pin "C9W13.1"
				( objectStatus "@baseboard_fab2_lib.baseboard_fab2(sch_1):page239_i81:a" )
			)
			( pin "C9W13.2"
				( objectStatus "@baseboard_fab2_lib.baseboard_fab2(sch_1):page239_i81:b" )
			)
			( pin "C1W15.1"
				( objectStatus "@baseboard_fab2_lib.baseboard_fab2(sch_1):page239_i83:a" )
			)
			( pin "C1W15.2"
				( objectStatus "@baseboard_fab2_lib.baseboard_fab2(sch_1):page239_i83:b" )
			)
			( pin "C9W10.1"
				( objectStatus "@baseboard_fab2_lib.baseboard_fab2(sch_1):page239_i84:a" )
			)
			( pin "C9W10.2"
				( objectStatus "@baseboard_fab2_lib.baseboard_fab2(sch_1):page239_i84:b" )
			)
			( pin "C9W5.1"
				( objectStatus "@baseboard_fab2_lib.baseboard_fab2(sch_1):page239_i90:a" )
			)
			( pin "C9W5.2"
				( objectStatus "@baseboard_fab2_lib.baseboard_fab2(sch_1):page239_i90:b" )
			)
			( pin "C9W6.1"
				( objectStatus "@baseboard_fab2_lib.baseboard_fab2(sch_1):page239_i91:a" )
			)
			( pin "C9W6.2"
				( objectStatus "@baseboard_fab2_lib.baseboard_fab2(sch_1):page239_i91:b" )
			)
			( pin "C1W7.1"
				( objectStatus "@baseboard_fab2_lib.baseboard_fab2(sch_1):page239_i92:a" )
			)
			( pin "C1W7.2"
				( objectStatus "@baseboard_fab2_lib.baseboard_fab2(sch_1):page239_i92:b" )
			)
			( pin "U25W4.J2"
				( objectStatus "@baseboard_fab2_lib.baseboard_fab2(sch_1):page144_i95:dacb" )
			)
			( pin "U25W4.J3"
				( objectStatus "@baseboard_fab2_lib.baseboard_fab2(sch_1):page144_i95:dacg" )
			)
			( pin "U25W4.J4"
				( objectStatus "@baseboard_fab2_lib.baseboard_fab2(sch_1):page144_i95:dacr" )
			)
			( pin "U25W4.K4"
				( objectStatus "@baseboard_fab2_lib.baseboard_fab2(sch_1):page144_i95:dacrset" )
			)
			( pin "U25W4.C14"
				( objectStatus "@baseboard_fab2_lib.baseboard_fab2(sch_1):page144_i95:gpioa4_timer5_scl9" )
			)
			( pin "U25W4.A13"
				( objectStatus "@baseboard_fab2_lib.baseboard_fab2(sch_1):page144_i95:gpioa5_timer6_sda9" )
			)
			( pin "U25W4.K19"
				( objectStatus "@baseboard_fab2_lib.baseboard_fab2(sch_1):page144_i95:gpiob0" )
			)
			( pin "U25W4.L19"
				( objectStatus "@baseboard_fab2_lib.baseboard_fab2(sch_1):page144_i95:gpiob1" )
			)
			( pin "U25W4.L18"
				( objectStatus "@baseboard_fab2_lib.baseboard_fab2(sch_1):page144_i95:gpiob2" )
			)
			( pin "U25W4.K18"
				( objectStatus "@baseboard_fab2_lib.baseboard_fab2(sch_1):page144_i95:gpiob3" )
			)
			( pin "U25W4.J20"
				( objectStatus "@baseboard_fab2_lib.baseboard_fab2(sch_1):page144_i95:gpiob4_usbcki" )
			)
			( pin "U25W4.H21"
				( objectStatus "@baseboard_fab2_lib.baseboard_fab2(sch_1):page144_i95:\gpiob5_lpcpd#_lpcsmi#\" )
			)
			( pin "U25W4.H22"
				( objectStatus "@baseboard_fab2_lib.baseboard_fab2(sch_1):page144_i95:\gpiob6_lpcpme#\" )
			)
			( pin "U25W4.H20"
				( objectStatus "@baseboard_fab2_lib.baseboard_fab2(sch_1):page144_i95:gpiob7" )
			)
			( pin "U25W4.A19"
				( objectStatus "@baseboard_fab2_lib.baseboard_fab2(sch_1):page144_i95:gpiog0_sgps1ck" )
			)
			( pin "U25W4.E19"
				( objectStatus "@baseboard_fab2_lib.baseboard_fab2(sch_1):page144_i95:gpiog1_sgps1ld" )
			)
			( pin "U25W4.C19"
				( objectStatus "@baseboard_fab2_lib.baseboard_fab2(sch_1):page144_i95:gpiog2_sgps1i0" )
			)
			( pin "U25W4.E16"
				( objectStatus "@baseboard_fab2_lib.baseboard_fab2(sch_1):page144_i95:gpiog3_sgps1i1" )
			)
			( pin "U25W4.C18"
				( objectStatus "@baseboard_fab2_lib.baseboard_fab2(sch_1):page144_i95:\gpioi0_syscs#\" )
			)
			( pin "U25W4.E15"
				( objectStatus "@baseboard_fab2_lib.baseboard_fab2(sch_1):page144_i95:gpioi1_sysck" )
			)
			( pin "U25W4.B16"
				( objectStatus "@baseboard_fab2_lib.baseboard_fab2(sch_1):page144_i95:gpioi2_sysmosi" )
			)
			( pin "U25W4.C16"
				( objectStatus "@baseboard_fab2_lib.baseboard_fab2(sch_1):page144_i95:gpioi3_sysmiso" )
			)
			( pin "U25W4.B15"
				( objectStatus "@baseboard_fab2_lib.baseboard_fab2(sch_1):page144_i95:\gpioi4_spi1cs0#_vbcs#\" )
			)
			( pin "U25W4.C15"
				( objectStatus "@baseboard_fab2_lib.baseboard_fab2(sch_1):page144_i95:gpioi5_spi1ck_vbck" )
			)
			( pin "U25W4.A14"
				( objectStatus "@baseboard_fab2_lib.baseboard_fab2(sch_1):page144_i95:gpioi6_spi1mosi_vbmosi" )
			)
			( pin "U25W4.A15"
				( objectStatus "@baseboard_fab2_lib.baseboard_fab2(sch_1):page144_i95:gpioi7_spi1miso_vbmiso" )
			)
			( pin "U25W4.R2"
				( objectStatus "@baseboard_fab2_lib.baseboard_fab2(sch_1):page144_i95:gpioj0_sgpmck" )
			)
			( pin "U25W4.L2"
				( objectStatus "@baseboard_fab2_lib.baseboard_fab2(sch_1):page144_i95:gpioj1_sgpmld" )
			)
			( pin "U25W4.N3"
				( objectStatus "@baseboard_fab2_lib.baseboard_fab2(sch_1):page144_i95:gpioj2_sgpmo" )
			)
			( pin "U25W4.N4"
				( objectStatus "@baseboard_fab2_lib.baseboard_fab2(sch_1):page144_i95:gpioj3_sgpmi" )
			)
			( pin "U25W4.L3"
				( objectStatus "@baseboard_fab2_lib.baseboard_fab2(sch_1):page144_i95:gpiok0_scl5" )
			)
			( pin "U25W4.L4"
				( objectStatus "@baseboard_fab2_lib.baseboard_fab2(sch_1):page144_i95:gpiok1_sda5" )
			)
			( pin "U25W4.L1"
				( objectStatus "@baseboard_fab2_lib.baseboard_fab2(sch_1):page144_i95:gpiok2_scl6" )
			)
			( pin "U25W4.N2"
				( objectStatus "@baseboard_fab2_lib.baseboard_fab2(sch_1):page144_i95:gpiok3_sda6" )
			)
			( pin "U25W4.N1"
				( objectStatus "@baseboard_fab2_lib.baseboard_fab2(sch_1):page144_i95:gpiok4_scl7" )
			)
			( pin "U25W4.P1"
				( objectStatus "@baseboard_fab2_lib.baseboard_fab2(sch_1):page144_i95:gpiok5_sda7" )
			)
			( pin "U25W4.P2"
				( objectStatus "@baseboard_fab2_lib.baseboard_fab2(sch_1):page144_i95:gpiok6_scl8" )
			)
			( pin "U25W4.R1"
				( objectStatus "@baseboard_fab2_lib.baseboard_fab2(sch_1):page144_i95:gpiok7_sda8" )
			)
			( pin "U25W4.A11"
				( objectStatus "@baseboard_fab2_lib.baseboard_fab2(sch_1):page144_i95:gpioq0_scl3" )
			)
			( pin "U25W4.A10"
				( objectStatus "@baseboard_fab2_lib.baseboard_fab2(sch_1):page144_i95:gpioq1_sda3" )
			)
			( pin "U25W4.A9"
				( objectStatus "@baseboard_fab2_lib.baseboard_fab2(sch_1):page144_i95:gpioq2_scl4" )
			)
			( pin "U25W4.B9"
				( objectStatus "@baseboard_fab2_lib.baseboard_fab2(sch_1):page144_i95:gpioq3_sda4" )
			)
			( pin "U25W4.N21"
				( objectStatus "@baseboard_fab2_lib.baseboard_fab2(sch_1):page144_i95:gpioq4_scl14" )
			)
			( pin "U25W4.N22"
				( objectStatus "@baseboard_fab2_lib.baseboard_fab2(sch_1):page144_i95:gpioq5_sda14" )
			)
			( pin "U25W4.M18"
				( objectStatus "@baseboard_fab2_lib.baseboard_fab2(sch_1):page144_i95:gpioy4_scl1" )
			)
			( pin "U25W4.M19"
				( objectStatus "@baseboard_fab2_lib.baseboard_fab2(sch_1):page144_i95:gpioy5_sda1" )
			)
			( pin "U25W4.M20"
				( objectStatus "@baseboard_fab2_lib.baseboard_fab2(sch_1):page144_i95:gpioy6_scl2" )
			)
			( pin "U25W4.P20"
				( objectStatus "@baseboard_fab2_lib.baseboard_fab2(sch_1):page144_i95:gpioy7_sda2" )
			)
			( pin "U25W4.E11"
				( objectStatus "@baseboard_fab2_lib.baseboard_fab2(sch_1):page144_i95:ntrst" )
			)
			( pin "U25W4.C9"
				( objectStatus "@baseboard_fab2_lib.baseboard_fab2(sch_1):page144_i95:rtck" )
			)
			( pin "U25W4.C10"
				( objectStatus "@baseboard_fab2_lib.baseboard_fab2(sch_1):page144_i95:tck" )
			)
			( pin "U25W4.D12"
				( objectStatus "@baseboard_fab2_lib.baseboard_fab2(sch_1):page144_i95:tdi" )
			)
			( pin "U25W4.D11"
				( objectStatus "@baseboard_fab2_lib.baseboard_fab2(sch_1):page144_i95:tdo" )
			)
			( pin "U25W4.C8"
				( objectStatus "@baseboard_fab2_lib.baseboard_fab2(sch_1):page144_i95:tms" )
			)
			( pin "Q9W1.3"
				( objectStatus "@baseboard_fab2_lib.baseboard_fab2(sch_1):page249_i30:drn" )
			)
			( pin "Q9W1.1"
				( objectStatus "@baseboard_fab2_lib.baseboard_fab2(sch_1):page249_i30:gate" )
			)
			( pin "Q9W1.2"
				( objectStatus "@baseboard_fab2_lib.baseboard_fab2(sch_1):page249_i30:src" )
			)
			( pin "R6W25.1"
				( objectStatus "@baseboard_fab2_lib.baseboard_fab2(sch_1):page247_i101:a" )
			)
			( pin "R6W25.2"
				( objectStatus "@baseboard_fab2_lib.baseboard_fab2(sch_1):page247_i101:b" )
			)
			( pin "U25W4.Y21"
				( objectStatus "@baseboard_fab2_lib.baseboard_fab2(sch_1):page146_i104:gpioaa0_vpor2_nord0_salt7" )
			)
			( pin "U25W4.V21"
				( objectStatus "@baseboard_fab2_lib.baseboard_fab2(sch_1):page146_i104:gpioaa1_vpor3_nord1_salt8" )
			)
			( pin "U25W4.Y22"
				( objectStatus "@baseboard_fab2_lib.baseboard_fab2(sch_1):page146_i104:gpioaa2_vpor4_nord2_salt9" )
			)
			( pin "U25W4.AA22"
				( objectStatus "@baseboard_fab2_lib.baseboard_fab2(sch_1):page146_i104:gpioaa3_vpor5_nord3_salt10" )
			)
			( pin "U25W4.U22"
				( objectStatus "@baseboard_fab2_lib.baseboard_fab2(sch_1):page146_i104:gpioaa4_vpor6_nord4_salt11" )
			)
			( pin "U25W4.T20"
				( objectStatus "@baseboard_fab2_lib.baseboard_fab2(sch_1):page146_i104:gpioaa5_vpor7_nord5_salt12" )
			)
			( pin "U25W4.N18"
				( objectStatus "@baseboard_fab2_lib.baseboard_fab2(sch_1):page146_i104:gpioaa6_vpor8_nord6_salt13" )
			)
			( pin "U25W4.P19"
				( objectStatus "@baseboard_fab2_lib.baseboard_fab2(sch_1):page146_i104:gpioaa7_vpor9_nord7_salt14" )
			)
			( pin "U25W4.A18"
				( objectStatus "@baseboard_fab2_lib.baseboard_fab2(sch_1):page146_i104:gpioh0_ncts6" )
			)
			( pin "U25W4.B18"
				( objectStatus "@baseboard_fab2_lib.baseboard_fab2(sch_1):page146_i104:gpioh1_ndcd6" )
			)
			( pin "U25W4.D17"
				( objectStatus "@baseboard_fab2_lib.baseboard_fab2(sch_1):page146_i104:gpioh2_ndsr6" )
			)
			( pin "U25W4.C17"
				( objectStatus "@baseboard_fab2_lib.baseboard_fab2(sch_1):page146_i104:gpioh3_nri6" )
			)
			( pin "U25W4.A17"
				( objectStatus "@baseboard_fab2_lib.baseboard_fab2(sch_1):page146_i104:gpioh4_ndtr6" )
			)
			( pin "U25W4.B17"
				( objectStatus "@baseboard_fab2_lib.baseboard_fab2(sch_1):page146_i104:gpioh5_nrts6" )
			)
			( pin "U25W4.A16"
				( objectStatus "@baseboard_fab2_lib.baseboard_fab2(sch_1):page146_i104:gpioh6_txd6" )
			)
			( pin "U25W4.D18"
				( objectStatus "@baseboard_fab2_lib.baseboard_fab2(sch_1):page146_i104:gpioh7_rxd6" )
			)
			( pin "U25W4.V20"
				( objectStatus "@baseboard_fab2_lib.baseboard_fab2(sch_1):page146_i104:\gpios0_vpob2_spi2cs1#\" )
			)
			( pin "U25W4.U19"
				( objectStatus "@baseboard_fab2_lib.baseboard_fab2(sch_1):page146_i104:gpios1_vpob3_bmcint" )
			)
			( pin "U25W4.R18"
				( objectStatus "@baseboard_fab2_lib.baseboard_fab2(sch_1):page146_i104:gpios2_vpob4_salt5" )
			)
			( pin "U25W4.P18"
				( objectStatus "@baseboard_fab2_lib.baseboard_fab2(sch_1):page146_i104:gpios3_vpob5_salt6" )
			)
			( pin "U25W4.R19"
				( objectStatus "@baseboard_fab2_lib.baseboard_fab2(sch_1):page146_i104:gpios4_vpob6" )
			)
			( pin "U25W4.W20"
				( objectStatus "@baseboard_fab2_lib.baseboard_fab2(sch_1):page146_i104:gpios5_vpob7" )
			)
			( pin "U25W4.U20"
				( objectStatus "@baseboard_fab2_lib.baseboard_fab2(sch_1):page146_i104:gpios6_vpob8" )
			)
			( pin "U25W4.AA20"
				( objectStatus "@baseboard_fab2_lib.baseboard_fab2(sch_1):page146_i104:gpios7_vpob9" )
			)
			( pin "U25W4.Y20"
				( objectStatus "@baseboard_fab2_lib.baseboard_fab2(sch_1):page146_i104:\gpioz0_vpog2_nora0_siopbi#\" )
			)
			( pin "U25W4.AB20"
				( objectStatus "@baseboard_fab2_lib.baseboard_fab2(sch_1):page146_i104:gpioz1_vpog3_nora1_siopwrgd" )
			)
			( pin "U25W4.AB21"
				( objectStatus "@baseboard_fab2_lib.baseboard_fab2(sch_1):page146_i104:\gpioz2_vpog4_nora2_siopbo#\" )
			)
			( pin "U25W4.AA21"
				( objectStatus "@baseboard_fab2_lib.baseboard_fab2(sch_1):page146_i104:\gpioz3_vpog5_nora3_siosci#\" )
			)
			( pin "U25W4.U21"
				( objectStatus "@baseboard_fab2_lib.baseboard_fab2(sch_1):page146_i104:gpioz4_vpog6_nora4" )
			)
			( pin "U25W4.W22"
				( objectStatus "@baseboard_fab2_lib.baseboard_fab2(sch_1):page146_i104:gpioz5_vpog7_nora5" )
			)
			( pin "U25W4.V22"
				( objectStatus "@baseboard_fab2_lib.baseboard_fab2(sch_1):page146_i104:gpioz6_vpog8_nora6" )
			)
			( pin "U25W4.W21"
				( objectStatus "@baseboard_fab2_lib.baseboard_fab2(sch_1):page146_i104:gpioz7_vpog9_nora7" )
			)
			( pin "U25W4.A8"
				( objectStatus "@baseboard_fab2_lib.baseboard_fab2(sch_1):page146_i104:usb2a_dn" )
			)
			( pin "U25W4.A7"
				( objectStatus "@baseboard_fab2_lib.baseboard_fab2(sch_1):page146_i104:usb2a_dp" )
			)
			( pin "U25W4.B8"
				( objectStatus "@baseboard_fab2_lib.baseboard_fab2(sch_1):page146_i104:usb2avres" )
			)
			( pin "U25W4.A6"
				( objectStatus "@baseboard_fab2_lib.baseboard_fab2(sch_1):page146_i104:usb2b_dn" )
			)
			( pin "U25W4.B6"
				( objectStatus "@baseboard_fab2_lib.baseboard_fab2(sch_1):page146_i104:usb2b_dp" )
			)
			( pin "U25W4.B7"
				( objectStatus "@baseboard_fab2_lib.baseboard_fab2(sch_1):page146_i104:usb2bvres" )
			)
			( pin "C9W1.1"
				( objectStatus "@baseboard_fab2_lib.baseboard_fab2(sch_1):page200_i235:\1\" )
			)
			( pin "C9W1.2"
				( objectStatus "@baseboard_fab2_lib.baseboard_fab2(sch_1):page200_i235:\2\" )
			)
			( pin "C9W2.1"
				( objectStatus "@baseboard_fab2_lib.baseboard_fab2(sch_1):page200_i236:\1\" )
			)
			( pin "C9W2.2"
				( objectStatus "@baseboard_fab2_lib.baseboard_fab2(sch_1):page200_i236:\2\" )
			)
			( pin "R25W81.1"
				( objectStatus "@baseboard_fab2_lib.baseboard_fab2(sch_1):page146_i67:a" )
			)
			( pin "R25W81.2"
				( objectStatus "@baseboard_fab2_lib.baseboard_fab2(sch_1):page146_i67:b" )
			)
			( pin "R25W111.1"
				( objectStatus "@baseboard_fab2_lib.baseboard_fab2(sch_1):page150_i180:a" )
			)
			( pin "R25W111.2"
				( objectStatus "@baseboard_fab2_lib.baseboard_fab2(sch_1):page150_i180:b" )
			)
			( pin "RT23.1"
				( objectStatus "@baseboard_fab2_lib.baseboard_fab2(sch_1):page204_i99:a" )
			)
			( pin "RT23.2"
				( objectStatus "@baseboard_fab2_lib.baseboard_fab2(sch_1):page204_i99:b" )
			)
			( pin "R25W57.1"
				( objectStatus "@baseboard_fab2_lib.baseboard_fab2(sch_1):page147_i151:a" )
			)
			( pin "R25W57.2"
				( objectStatus "@baseboard_fab2_lib.baseboard_fab2(sch_1):page147_i151:b" )
			)
			( pin "RT15.1"
				( objectStatus "@baseboard_fab2_lib.baseboard_fab2(sch_1):page207_i99:a" )
			)
			( pin "RT15.2"
				( objectStatus "@baseboard_fab2_lib.baseboard_fab2(sch_1):page207_i99:b" )
			)
			( pin "RT37.1"
				( objectStatus "@baseboard_fab2_lib.baseboard_fab2(sch_1):page210_i68:a" )
			)
			( pin "RT37.2"
				( objectStatus "@baseboard_fab2_lib.baseboard_fab2(sch_1):page210_i68:b" )
			)
			( pin "RT9.1"
				( objectStatus "@baseboard_fab2_lib.baseboard_fab2(sch_1):page209_i75:a" )
			)
			( pin "RT9.2"
				( objectStatus "@baseboard_fab2_lib.baseboard_fab2(sch_1):page209_i75:b" )
			)
			( pin "RT36.1"
				( objectStatus "@baseboard_fab2_lib.baseboard_fab2(sch_1):page216_i140:a" )
			)
			( pin "RT36.2"
				( objectStatus "@baseboard_fab2_lib.baseboard_fab2(sch_1):page216_i140:b" )
			)
			( pin "RT44.1"
				( objectStatus "@baseboard_fab2_lib.baseboard_fab2(sch_1):page236_i153:a" )
			)
			( pin "RT44.2"
				( objectStatus "@baseboard_fab2_lib.baseboard_fab2(sch_1):page236_i153:b" )
			)
			( pin "RT46.1"
				( objectStatus "@baseboard_fab2_lib.baseboard_fab2(sch_1):page236_i154:a" )
			)
			( pin "RT46.2"
				( objectStatus "@baseboard_fab2_lib.baseboard_fab2(sch_1):page236_i154:b" )
			)
			( pin "RT14.1"
				( objectStatus "@baseboard_fab2_lib.baseboard_fab2(sch_1):page208_i109:a" )
			)
			( pin "RT14.2"
				( objectStatus "@baseboard_fab2_lib.baseboard_fab2(sch_1):page208_i109:b" )
			)
			( pin "RT40.1"
				( objectStatus "@baseboard_fab2_lib.baseboard_fab2(sch_1):page205_i78:a" )
			)
			( pin "RT40.2"
				( objectStatus "@baseboard_fab2_lib.baseboard_fab2(sch_1):page205_i78:b" )
			)
			( pin "R25W94.1"
				( objectStatus "@baseboard_fab2_lib.baseboard_fab2(sch_1):page137_i140:a" )
			)
			( pin "R25W94.2"
				( objectStatus "@baseboard_fab2_lib.baseboard_fab2(sch_1):page137_i140:b" )
			)
			( pin "R25W154.1"
				( objectStatus "@baseboard_fab2_lib.baseboard_fab2(sch_1):page137_i133:a" )
			)
			( pin "R25W154.2"
				( objectStatus "@baseboard_fab2_lib.baseboard_fab2(sch_1):page137_i133:b" )
			)
			( pin "R9F66.1"
				( objectStatus "@baseboard_fab2_lib.baseboard_fab2(sch_1):page158_i152:a" )
			)
			( pin "R9F66.2"
				( objectStatus "@baseboard_fab2_lib.baseboard_fab2(sch_1):page158_i152:b" )
			)
			( pin "R1U13.1"
				( objectStatus "@baseboard_fab2_lib.baseboard_fab2(sch_1):page144_i58:a" )
			)
			( pin "R1U13.2"
				( objectStatus "@baseboard_fab2_lib.baseboard_fab2(sch_1):page144_i58:b" )
			)
			( pin "R1U14.1"
				( objectStatus "@baseboard_fab2_lib.baseboard_fab2(sch_1):page144_i57:a" )
			)
			( pin "R1U14.2"
				( objectStatus "@baseboard_fab2_lib.baseboard_fab2(sch_1):page144_i57:b" )
			)
			( pin "U25W4.J6"
				( objectStatus "@baseboard_fab2_lib.baseboard_fab2(sch_1):page148_i28:adcav33" )
			)
			( pin "U25W4.E4"
				( objectStatus "@baseboard_fab2_lib.baseboard_fab2(sch_1):page148_i28:batvdd" )
			)
			( pin "U25W4.K6"
				( objectStatus "@baseboard_fab2_lib.baseboard_fab2(sch_1):page148_i28:dacav33" )
			)
			( pin "U25W4.K5"
				( objectStatus "@baseboard_fab2_lib.baseboard_fab2(sch_1):page148_i28:dacdv33" )
			)
			( pin "U25W4.A1"
				( objectStatus "@baseboard_fab2_lib.baseboard_fab2(sch_1):page148_i28:gnd0" )
			)
			( pin "U25W4.A22"
				( objectStatus "@baseboard_fab2_lib.baseboard_fab2(sch_1):page148_i28:gnd1" )
			)
			( pin "U25W4.AA11"
				( objectStatus "@baseboard_fab2_lib.baseboard_fab2(sch_1):page148_i28:gnd2" )
			)
			( pin "U25W4.AA13"
				( objectStatus "@baseboard_fab2_lib.baseboard_fab2(sch_1):page148_i28:gnd3" )
			)
			( pin "U25W4.AA15"
				( objectStatus "@baseboard_fab2_lib.baseboard_fab2(sch_1):page148_i28:gnd4" )
			)
			( pin "U25W4.AA7"
				( objectStatus "@baseboard_fab2_lib.baseboard_fab2(sch_1):page148_i28:gnd5" )
			)
			( pin "U25W4.AA9"
				( objectStatus "@baseboard_fab2_lib.baseboard_fab2(sch_1):page148_i28:gnd6" )
			)
			( pin "U25W4.AB1"
				( objectStatus "@baseboard_fab2_lib.baseboard_fab2(sch_1):page148_i28:gnd7" )
			)
			( pin "U25W4.AB22"
				( objectStatus "@baseboard_fab2_lib.baseboard_fab2(sch_1):page148_i28:gnd8" )
			)
			( pin "U25W4.C6"
				( objectStatus "@baseboard_fab2_lib.baseboard_fab2(sch_1):page148_i28:gnd9" )
			)
			( pin "U25W4.E8"
				( objectStatus "@baseboard_fab2_lib.baseboard_fab2(sch_1):page148_i28:gnd10" )
			)
			( pin "U25W4.F16"
				( objectStatus "@baseboard_fab2_lib.baseboard_fab2(sch_1):page148_i28:gnd11" )
			)
			( pin "U25W4.G19"
				( objectStatus "@baseboard_fab2_lib.baseboard_fab2(sch_1):page148_i28:gnd12" )
			)
			( pin "U25W4.G6"
				( objectStatus "@baseboard_fab2_lib.baseboard_fab2(sch_1):page148_i28:gnd13" )
			)
			( pin "U25W4.H6"
				( objectStatus "@baseboard_fab2_lib.baseboard_fab2(sch_1):page148_i28:gnd14" )
			)
			( pin "U25W4.J10"
				( objectStatus "@baseboard_fab2_lib.baseboard_fab2(sch_1):page148_i28:gnd15" )
			)
			( pin "U25W4.J11"
				( objectStatus "@baseboard_fab2_lib.baseboard_fab2(sch_1):page148_i28:gnd16" )
			)
			( pin "U25W4.J12"
				( objectStatus "@baseboard_fab2_lib.baseboard_fab2(sch_1):page148_i28:gnd17" )
			)
			( pin "U25W4.J13"
				( objectStatus "@baseboard_fab2_lib.baseboard_fab2(sch_1):page148_i28:gnd18" )
			)
			( pin "U25W4.J14"
				( objectStatus "@baseboard_fab2_lib.baseboard_fab2(sch_1):page148_i28:gnd19" )
			)
			( pin "U25W4.J21"
				( objectStatus "@baseboard_fab2_lib.baseboard_fab2(sch_1):page148_i28:gnd20" )
			)
			( pin "U25W4.J22"
				( objectStatus "@baseboard_fab2_lib.baseboard_fab2(sch_1):page148_i28:gnd21" )
			)
			( pin "U25W4.J5"
				( objectStatus "@baseboard_fab2_lib.baseboard_fab2(sch_1):page148_i28:gnd22" )
			)
			( pin "U25W4.J9"
				( objectStatus "@baseboard_fab2_lib.baseboard_fab2(sch_1):page148_i28:gnd23" )
			)
			( pin "U25W4.K10"
				( objectStatus "@baseboard_fab2_lib.baseboard_fab2(sch_1):page148_i28:gnd24" )
			)
			( pin "U25W4.K11"
				( objectStatus "@baseboard_fab2_lib.baseboard_fab2(sch_1):page148_i28:gnd25" )
			)
			( pin "U25W4.K12"
				( objectStatus "@baseboard_fab2_lib.baseboard_fab2(sch_1):page148_i28:gnd26" )
			)
			( pin "U25W4.K13"
				( objectStatus "@baseboard_fab2_lib.baseboard_fab2(sch_1):page148_i28:gnd27" )
			)
			( pin "U25W4.K14"
				( objectStatus "@baseboard_fab2_lib.baseboard_fab2(sch_1):page148_i28:gnd28" )
			)
			( pin "U25W4.K16"
				( objectStatus "@baseboard_fab2_lib.baseboard_fab2(sch_1):page148_i28:gnd29" )
			)
			( pin "U25W4.K9"
				( objectStatus "@baseboard_fab2_lib.baseboard_fab2(sch_1):page148_i28:gnd30" )
			)
			( pin "U25W4.L10"
				( objectStatus "@baseboard_fab2_lib.baseboard_fab2(sch_1):page148_i28:gnd31" )
			)
			( pin "U25W4.L11"
				( objectStatus "@baseboard_fab2_lib.baseboard_fab2(sch_1):page148_i28:gnd32" )
			)
			( pin "U25W4.L12"
				( objectStatus "@baseboard_fab2_lib.baseboard_fab2(sch_1):page148_i28:gnd33" )
			)
			( pin "U25W4.L13"
				( objectStatus "@baseboard_fab2_lib.baseboard_fab2(sch_1):page148_i28:gnd34" )
			)
			( pin "U25W4.L14"
				( objectStatus "@baseboard_fab2_lib.baseboard_fab2(sch_1):page148_i28:gnd35" )
			)
			( pin "U25W4.L9"
				( objectStatus "@baseboard_fab2_lib.baseboard_fab2(sch_1):page148_i28:gnd36" )
			)
			( pin "U25W4.M1"
				( objectStatus "@baseboard_fab2_lib.baseboard_fab2(sch_1):page148_i28:gnd37" )
			)
			( pin "U25W4.M10"
				( objectStatus "@baseboard_fab2_lib.baseboard_fab2(sch_1):page148_i28:gnd38" )
			)
			( pin "U25W4.M11"
				( objectStatus "@baseboard_fab2_lib.baseboard_fab2(sch_1):page148_i28:gnd39" )
			)
			( pin "U25W4.M12"
				( objectStatus "@baseboard_fab2_lib.baseboard_fab2(sch_1):page148_i28:gnd40" )
			)
			( pin "U25W4.M13"
				( objectStatus "@baseboard_fab2_lib.baseboard_fab2(sch_1):page148_i28:gnd41" )
			)
			( pin "U25W4.M14"
				( objectStatus "@baseboard_fab2_lib.baseboard_fab2(sch_1):page148_i28:gnd42" )
			)
			( pin "U25W4.M16"
				( objectStatus "@baseboard_fab2_lib.baseboard_fab2(sch_1):page148_i28:gnd43" )
			)
			( pin "U25W4.M17"
				( objectStatus "@baseboard_fab2_lib.baseboard_fab2(sch_1):page148_i28:gnd44" )
			)
			( pin "U25W4.M2"
				( objectStatus "@baseboard_fab2_lib.baseboard_fab2(sch_1):page148_i28:gnd45" )
			)
			( pin "U25W4.M3"
				( objectStatus "@baseboard_fab2_lib.baseboard_fab2(sch_1):page148_i28:gnd46" )
			)
			( pin "U25W4.M4"
				( objectStatus "@baseboard_fab2_lib.baseboard_fab2(sch_1):page148_i28:gnd47" )
			)
			( pin "U25W4.M5"
				( objectStatus "@baseboard_fab2_lib.baseboard_fab2(sch_1):page148_i28:gnd48" )
			)
			( pin "U25W4.M6"
				( objectStatus "@baseboard_fab2_lib.baseboard_fab2(sch_1):page148_i28:gnd49" )
			)
			( pin "U25W4.M7"
				( objectStatus "@baseboard_fab2_lib.baseboard_fab2(sch_1):page148_i28:gnd50" )
			)
			( pin "U25W4.M9"
				( objectStatus "@baseboard_fab2_lib.baseboard_fab2(sch_1):page148_i28:gnd51" )
			)
			( pin "U25W4.N10"
				( objectStatus "@baseboard_fab2_lib.baseboard_fab2(sch_1):page148_i28:gnd52" )
			)
			( pin "U25W4.N11"
				( objectStatus "@baseboard_fab2_lib.baseboard_fab2(sch_1):page148_i28:gnd53" )
			)
			( pin "U25W4.N12"
				( objectStatus "@baseboard_fab2_lib.baseboard_fab2(sch_1):page148_i28:gnd54" )
			)
			( pin "U25W4.N13"
				( objectStatus "@baseboard_fab2_lib.baseboard_fab2(sch_1):page148_i28:gnd55" )
			)
			( pin "U25W4.N14"
				( objectStatus "@baseboard_fab2_lib.baseboard_fab2(sch_1):page148_i28:gnd56" )
			)
			( pin "U25W4.N9"
				( objectStatus "@baseboard_fab2_lib.baseboard_fab2(sch_1):page148_i28:gnd57" )
			)
			( pin "U25W4.T16"
				( objectStatus "@baseboard_fab2_lib.baseboard_fab2(sch_1):page148_i28:gnd58" )
			)
			( pin "U25W4.T6"
				( objectStatus "@baseboard_fab2_lib.baseboard_fab2(sch_1):page148_i28:gnd59" )
			)
			( pin "U25W4.T7"
				( objectStatus "@baseboard_fab2_lib.baseboard_fab2(sch_1):page148_i28:gnd60" )
			)
			( pin "U25W4.U11"
				( objectStatus "@baseboard_fab2_lib.baseboard_fab2(sch_1):page148_i28:gnd61" )
			)
			( pin "U25W4.U6"
				( objectStatus "@baseboard_fab2_lib.baseboard_fab2(sch_1):page148_i28:gnd62" )
			)
			( pin "U25W4.V10"
				( objectStatus "@baseboard_fab2_lib.baseboard_fab2(sch_1):page148_i28:gnd63" )
			)
			( pin "U25W4.V12"
				( objectStatus "@baseboard_fab2_lib.baseboard_fab2(sch_1):page148_i28:gnd64" )
			)
			( pin "U25W4.V14"
				( objectStatus "@baseboard_fab2_lib.baseboard_fab2(sch_1):page148_i28:gnd65" )
			)
			( pin "U25W4.V16"
				( objectStatus "@baseboard_fab2_lib.baseboard_fab2(sch_1):page148_i28:gnd66" )
			)
			( pin "U25W4.V8"
				( objectStatus "@baseboard_fab2_lib.baseboard_fab2(sch_1):page148_i28:gnd67" )
			)
			( pin "U25W4.E5"
				( objectStatus "@baseboard_fab2_lib.baseboard_fab2(sch_1):page148_i28:gnd68" )
			)
			( pin "U25W4.R22"
				( objectStatus "@baseboard_fab2_lib.baseboard_fab2(sch_1):page148_i28:\gpioy0_sios3#\" )
			)
			( pin "U25W4.R21"
				( objectStatus "@baseboard_fab2_lib.baseboard_fab2(sch_1):page148_i28:\gpioy1_sios5#\" )
			)
			( pin "U25W4.P22"
				( objectStatus "@baseboard_fab2_lib.baseboard_fab2(sch_1):page148_i28:\gpioy2_siopwreq#\" )
			)
			( pin "U25W4.F6"
				( objectStatus "@baseboard_fab2_lib.baseboard_fab2(sch_1):page148_i28:iv11d0" )
			)
			( pin "U25W4.G10"
				( objectStatus "@baseboard_fab2_lib.baseboard_fab2(sch_1):page148_i28:iv11d1" )
			)
			( pin "U25W4.G11"
				( objectStatus "@baseboard_fab2_lib.baseboard_fab2(sch_1):page148_i28:iv11d2" )
			)
			( pin "U25W4.G12"
				( objectStatus "@baseboard_fab2_lib.baseboard_fab2(sch_1):page148_i28:iv11d3" )
			)
			( pin "U25W4.G13"
				( objectStatus "@baseboard_fab2_lib.baseboard_fab2(sch_1):page148_i28:iv11d4" )
			)
			( pin "U25W4.G14"
				( objectStatus "@baseboard_fab2_lib.baseboard_fab2(sch_1):page148_i28:iv11d5" )
			)
			( pin "U25W4.G15"
				( objectStatus "@baseboard_fab2_lib.baseboard_fab2(sch_1):page148_i28:iv11d6" )
			)
			( pin "U25W4.G7"
				( objectStatus "@baseboard_fab2_lib.baseboard_fab2(sch_1):page148_i28:iv11d7" )
			)
			( pin "U25W4.G8"
				( objectStatus "@baseboard_fab2_lib.baseboard_fab2(sch_1):page148_i28:iv11d8" )
			)
			( pin "U25W4.G9"
				( objectStatus "@baseboard_fab2_lib.baseboard_fab2(sch_1):page148_i28:iv11d9" )
			)
			( pin "U25W4.H16"
				( objectStatus "@baseboard_fab2_lib.baseboard_fab2(sch_1):page148_i28:iv11d10" )
			)
			( pin "U25W4.J16"
				( objectStatus "@baseboard_fab2_lib.baseboard_fab2(sch_1):page148_i28:iv11d11" )
			)
			( pin "U25W4.L7"
				( objectStatus "@baseboard_fab2_lib.baseboard_fab2(sch_1):page148_i28:iv11d12" )
			)
			( pin "U25W4.N16"
				( objectStatus "@baseboard_fab2_lib.baseboard_fab2(sch_1):page148_i28:iv11d13" )
			)
			( pin "U25W4.N7"
				( objectStatus "@baseboard_fab2_lib.baseboard_fab2(sch_1):page148_i28:iv11d14" )
			)
			( pin "U25W4.P10"
				( objectStatus "@baseboard_fab2_lib.baseboard_fab2(sch_1):page148_i28:iv11d15" )
			)
			( pin "U25W4.P11"
				( objectStatus "@baseboard_fab2_lib.baseboard_fab2(sch_1):page148_i28:iv11d16" )
			)
			( pin "U25W4.P12"
				( objectStatus "@baseboard_fab2_lib.baseboard_fab2(sch_1):page148_i28:iv11d17" )
			)
			( pin "U25W4.P13"
				( objectStatus "@baseboard_fab2_lib.baseboard_fab2(sch_1):page148_i28:iv11d18" )
			)
			( pin "U25W4.P14"
				( objectStatus "@baseboard_fab2_lib.baseboard_fab2(sch_1):page148_i28:iv11d19" )
			)
			( pin "U25W4.P16"
				( objectStatus "@baseboard_fab2_lib.baseboard_fab2(sch_1):page148_i28:iv11d20" )
			)
			( pin "U25W4.P7"
				( objectStatus "@baseboard_fab2_lib.baseboard_fab2(sch_1):page148_i28:iv11d21" )
			)
			( pin "U25W4.P9"
				( objectStatus "@baseboard_fab2_lib.baseboard_fab2(sch_1):page148_i28:iv11d22" )
			)
			( pin "U25W4.R16"
				( objectStatus "@baseboard_fab2_lib.baseboard_fab2(sch_1):page148_i28:iv11d23" )
			)
			( pin "U25W4.R7"
				( objectStatus "@baseboard_fab2_lib.baseboard_fab2(sch_1):page148_i28:iv11d24" )
			)
			( pin "U25W4.J17"
				( objectStatus "@baseboard_fab2_lib.baseboard_fab2(sch_1):page148_i28:lpvdd0" )
			)
			( pin "U25W4.K17"
				( objectStatus "@baseboard_fab2_lib.baseboard_fab2(sch_1):page148_i28:lpvdd1" )
			)
			( pin "U25W4.T10"
				( objectStatus "@baseboard_fab2_lib.baseboard_fab2(sch_1):page148_i28:mvdd0" )
			)
			( pin "U25W4.T12"
				( objectStatus "@baseboard_fab2_lib.baseboard_fab2(sch_1):page148_i28:mvdd1" )
			)
			( pin "U25W4.T13"
				( objectStatus "@baseboard_fab2_lib.baseboard_fab2(sch_1):page148_i28:mvdd2" )
			)
			( pin "U25W4.T14"
				( objectStatus "@baseboard_fab2_lib.baseboard_fab2(sch_1):page148_i28:mvdd3" )
			)
			( pin "U25W4.T8"
				( objectStatus "@baseboard_fab2_lib.baseboard_fab2(sch_1):page148_i28:mvdd4" )
			)
			( pin "U25W4.L17"
				( objectStatus "@baseboard_fab2_lib.baseboard_fab2(sch_1):page148_i28:peav11" )
			)
			( pin "U25W4.L16"
				( objectStatus "@baseboard_fab2_lib.baseboard_fab2(sch_1):page148_i28:peav33" )
			)
			( pin "U25W4.AA17"
				( objectStatus "@baseboard_fab2_lib.baseboard_fab2(sch_1):page148_i28:pecivdd" )
			)
			( pin "U25W4.Y17"
				( objectStatus "@baseboard_fab2_lib.baseboard_fab2(sch_1):page148_i28:pllav330" )
			)
			( pin "U25W4.W17"
				( objectStatus "@baseboard_fab2_lib.baseboard_fab2(sch_1):page148_i28:pllav331" )
			)
			( pin "U25W4.V17"
				( objectStatus "@baseboard_fab2_lib.baseboard_fab2(sch_1):page148_i28:plldv11" )
			)
			( pin "U25W4.F12"
				( objectStatus "@baseboard_fab2_lib.baseboard_fab2(sch_1):page148_i28:pv33d0" )
			)
			( pin "U25W4.F13"
				( objectStatus "@baseboard_fab2_lib.baseboard_fab2(sch_1):page148_i28:pv33d1" )
			)
			( pin "U25W4.F14"
				( objectStatus "@baseboard_fab2_lib.baseboard_fab2(sch_1):page148_i28:pv33d2" )
			)
			( pin "U25W4.F15"
				( objectStatus "@baseboard_fab2_lib.baseboard_fab2(sch_1):page148_i28:pv33d3" )
			)
			( pin "U25W4.G16"
				( objectStatus "@baseboard_fab2_lib.baseboard_fab2(sch_1):page148_i28:pv33d4" )
			)
			( pin "U25W4.H17"
				( objectStatus "@baseboard_fab2_lib.baseboard_fab2(sch_1):page148_i28:pv33d5" )
			)
			( pin "U25W4.K7"
				( objectStatus "@baseboard_fab2_lib.baseboard_fab2(sch_1):page148_i28:pv33d6" )
			)
			( pin "U25W4.N17"
				( objectStatus "@baseboard_fab2_lib.baseboard_fab2(sch_1):page148_i28:pv33d7" )
			)
			( pin "U25W4.N6"
				( objectStatus "@baseboard_fab2_lib.baseboard_fab2(sch_1):page148_i28:pv33d8" )
			)
			( pin "U25W4.P17"
				( objectStatus "@baseboard_fab2_lib.baseboard_fab2(sch_1):page148_i28:pv33d9" )
			)
			( pin "U25W4.P6"
				( objectStatus "@baseboard_fab2_lib.baseboard_fab2(sch_1):page148_i28:pv33d10" )
			)
			( pin "U25W4.R17"
				( objectStatus "@baseboard_fab2_lib.baseboard_fab2(sch_1):page148_i28:pv33d11" )
			)
			( pin "U25W4.R6"
				( objectStatus "@baseboard_fab2_lib.baseboard_fab2(sch_1):page148_i28:pv33d12" )
			)
			( pin "U25W4.T11"
				( objectStatus "@baseboard_fab2_lib.baseboard_fab2(sch_1):page148_i28:pv33d13" )
			)
			( pin "U25W4.T15"
				( objectStatus "@baseboard_fab2_lib.baseboard_fab2(sch_1):page148_i28:pv33d14" )
			)
			( pin "U25W4.F10"
				( objectStatus "@baseboard_fab2_lib.baseboard_fab2(sch_1):page148_i28:r1vdd0" )
			)
			( pin "U25W4.F11"
				( objectStatus "@baseboard_fab2_lib.baseboard_fab2(sch_1):page148_i28:r1vdd1" )
			)
			( pin "U25W4.F7"
				( objectStatus "@baseboard_fab2_lib.baseboard_fab2(sch_1):page148_i28:r2vdd0" )
			)
			( pin "U25W4.F8"
				( objectStatus "@baseboard_fab2_lib.baseboard_fab2(sch_1):page148_i28:r2vdd1" )
			)
			( pin "U25W4.C7"
				( objectStatus "@baseboard_fab2_lib.baseboard_fab2(sch_1):page148_i28:usb2av33" )
			)
			( pin "U25W4.L5"
				( objectStatus "@baseboard_fab2_lib.baseboard_fab2(sch_1):page148_i28:vpllav110" )
			)
			( pin "U25W4.L6"
				( objectStatus "@baseboard_fab2_lib.baseboard_fab2(sch_1):page148_i28:vpllav111" )
			)
			( pin "U25W4.J7"
				( objectStatus "@baseboard_fab2_lib.baseboard_fab2(sch_1):page148_i28:vpllav330" )
			)
			( pin "U25W4.H7"
				( objectStatus "@baseboard_fab2_lib.baseboard_fab2(sch_1):page148_i28:vpllav331" )
			)
			( pin "C25W49.1"
				( objectStatus "@baseboard_fab2_lib.baseboard_fab2(sch_1):page149_i123:a" )
			)
			( pin "C25W49.2"
				( objectStatus "@baseboard_fab2_lib.baseboard_fab2(sch_1):page149_i123:b" )
			)
			( pin "C1T21.1"
				( objectStatus "@baseboard_fab2_lib.baseboard_fab2(sch_1):page148_i20:a" )
			)
			( pin "C1T21.2"
				( objectStatus "@baseboard_fab2_lib.baseboard_fab2(sch_1):page148_i20:b" )
			)
			( pin "R1U12.1"
				( objectStatus "@baseboard_fab2_lib.baseboard_fab2(sch_1):page144_i59:a" )
			)
			( pin "R1U12.2"
				( objectStatus "@baseboard_fab2_lib.baseboard_fab2(sch_1):page144_i59:b" )
			)
			( pin "R25W59.1"
				( objectStatus "@baseboard_fab2_lib.baseboard_fab2(sch_1):page148_i16:a" )
			)
			( pin "R25W59.2"
				( objectStatus "@baseboard_fab2_lib.baseboard_fab2(sch_1):page148_i16:b" )
			)
			( pin "R1U2.1"
				( objectStatus "@baseboard_fab2_lib.baseboard_fab2(sch_1):page147_i62:a" )
			)
			( pin "R1U2.2"
				( objectStatus "@baseboard_fab2_lib.baseboard_fab2(sch_1):page147_i62:b" )
			)
			( pin "R25W60.1"
				( objectStatus "@baseboard_fab2_lib.baseboard_fab2(sch_1):page145_i34:a" )
			)
			( pin "R25W60.2"
				( objectStatus "@baseboard_fab2_lib.baseboard_fab2(sch_1):page145_i34:b" )
			)
			( pin "U25W4.F4"
				( objectStatus "@baseboard_fab2_lib.baseboard_fab2(sch_1):page147_i106:adc0_gpiw0" )
			)
			( pin "U25W4.F5"
				( objectStatus "@baseboard_fab2_lib.baseboard_fab2(sch_1):page147_i106:adc1_gpiw1" )
			)
			( pin "U25W4.E2"
				( objectStatus "@baseboard_fab2_lib.baseboard_fab2(sch_1):page147_i106:adc2_gpiw2" )
			)
			( pin "U25W4.E1"
				( objectStatus "@baseboard_fab2_lib.baseboard_fab2(sch_1):page147_i106:adc3_gpiw3" )
			)
			( pin "U25W4.F3"
				( objectStatus "@baseboard_fab2_lib.baseboard_fab2(sch_1):page147_i106:adc4_gpiw4" )
			)
			( pin "U25W4.E3"
				( objectStatus "@baseboard_fab2_lib.baseboard_fab2(sch_1):page147_i106:adc5_gpiw5" )
			)
			( pin "U25W4.G5"
				( objectStatus "@baseboard_fab2_lib.baseboard_fab2(sch_1):page147_i106:adc6_gpiw6" )
			)
			( pin "U25W4.G4"
				( objectStatus "@baseboard_fab2_lib.baseboard_fab2(sch_1):page147_i106:adc7_gpiw7" )
			)
			( pin "U25W4.F2"
				( objectStatus "@baseboard_fab2_lib.baseboard_fab2(sch_1):page147_i106:adc8_gpix0" )
			)
			( pin "U25W4.G3"
				( objectStatus "@baseboard_fab2_lib.baseboard_fab2(sch_1):page147_i106:adc9_gpix1" )
			)
			( pin "U25W4.G2"
				( objectStatus "@baseboard_fab2_lib.baseboard_fab2(sch_1):page147_i106:adc10_gpix2" )
			)
			( pin "U25W4.F1"
				( objectStatus "@baseboard_fab2_lib.baseboard_fab2(sch_1):page147_i106:adc11_gpix3" )
			)
			( pin "U25W4.H5"
				( objectStatus "@baseboard_fab2_lib.baseboard_fab2(sch_1):page147_i106:adc12_gpix4" )
			)
			( pin "U25W4.G1"
				( objectStatus "@baseboard_fab2_lib.baseboard_fab2(sch_1):page147_i106:adc13_gpix5" )
			)
			( pin "U25W4.H3"
				( objectStatus "@baseboard_fab2_lib.baseboard_fab2(sch_1):page147_i106:adc14_gpix6" )
			)
			( pin "U25W4.H4"
				( objectStatus "@baseboard_fab2_lib.baseboard_fab2(sch_1):page147_i106:adc15_gpix7" )
			)
			( pin "U25W4.J1"
				( objectStatus "@baseboard_fab2_lib.baseboard_fab2(sch_1):page147_i106:adcrext" )
			)
			( pin "U25W4.H1"
				( objectStatus "@baseboard_fab2_lib.baseboard_fab2(sch_1):page147_i106:adcvrefn" )
			)
			( pin "U25W4.H2"
				( objectStatus "@baseboard_fab2_lib.baseboard_fab2(sch_1):page147_i106:adcvrefp" )
			)
			( pin "U25W4.C13"
				( objectStatus "@baseboard_fab2_lib.baseboard_fab2(sch_1):page147_i106:gpioa6_timer7_mdc2" )
			)
			( pin "U25W4.B13"
				( objectStatus "@baseboard_fab2_lib.baseboard_fab2(sch_1):page147_i106:gpioa7_timer8_mdio2" )
			)
			( pin "U25W4.V2"
				( objectStatus "@baseboard_fab2_lib.baseboard_fab2(sch_1):page147_i106:gpion0_pwm0" )
			)
			( pin "U25W4.W2"
				( objectStatus "@baseboard_fab2_lib.baseboard_fab2(sch_1):page147_i106:gpion1_pwm1" )
			)
			( pin "U25W4.V3"
				( objectStatus "@baseboard_fab2_lib.baseboard_fab2(sch_1):page147_i106:gpion2_pwm2_vpig2" )
			)
			( pin "U25W4.U3"
				( objectStatus "@baseboard_fab2_lib.baseboard_fab2(sch_1):page147_i106:gpion3_pwm3_vpig3" )
			)
			( pin "U25W4.W3"
				( objectStatus "@baseboard_fab2_lib.baseboard_fab2(sch_1):page147_i106:gpion4_pwm4_vpig4" )
			)
			( pin "U25W4.AA3"
				( objectStatus "@baseboard_fab2_lib.baseboard_fab2(sch_1):page147_i106:gpion5_pwm5_vpig5" )
			)
			( pin "U25W4.Y3"
				( objectStatus "@baseboard_fab2_lib.baseboard_fab2(sch_1):page147_i106:gpion6_pwm6_vpig6" )
			)
			( pin "U25W4.T4"
				( objectStatus "@baseboard_fab2_lib.baseboard_fab2(sch_1):page147_i106:gpion7_pwm7_vpig7" )
			)
			( pin "U25W4.U5"
				( objectStatus "@baseboard_fab2_lib.baseboard_fab2(sch_1):page147_i106:gpioo0_tach0_vpig8" )
			)
			( pin "U25W4.U4"
				( objectStatus "@baseboard_fab2_lib.baseboard_fab2(sch_1):page147_i106:gpioo1_tach1_vpig9" )
			)
			( pin "U25W4.V5"
				( objectStatus "@baseboard_fab2_lib.baseboard_fab2(sch_1):page147_i106:gpioo2_tach2" )
			)
			( pin "U25W4.AB4"
				( objectStatus "@baseboard_fab2_lib.baseboard_fab2(sch_1):page147_i106:gpioo3_tach3" )
			)
			( pin "U25W4.AB3"
				( objectStatus "@baseboard_fab2_lib.baseboard_fab2(sch_1):page147_i106:gpioo4_tach4_vpir2" )
			)
			( pin "U25W4.Y4"
				( objectStatus "@baseboard_fab2_lib.baseboard_fab2(sch_1):page147_i106:gpioo5_tach5_vpir3" )
			)
			( pin "U25W4.AA4"
				( objectStatus "@baseboard_fab2_lib.baseboard_fab2(sch_1):page147_i106:gpioo6_tach6_vpir4" )
			)
			( pin "U25W4.W4"
				( objectStatus "@baseboard_fab2_lib.baseboard_fab2(sch_1):page147_i106:gpioo7_tach7_vpir5" )
			)
			( pin "U25W4.V4"
				( objectStatus "@baseboard_fab2_lib.baseboard_fab2(sch_1):page147_i106:gpiop0_tach8_vpir6" )
			)
			( pin "U25W4.W5"
				( objectStatus "@baseboard_fab2_lib.baseboard_fab2(sch_1):page147_i106:gpiop1_tach9_vpir7" )
			)
			( pin "U25W4.AA5"
				( objectStatus "@baseboard_fab2_lib.baseboard_fab2(sch_1):page147_i106:gpiop2_tach10_vpir8" )
			)
			( pin "U25W4.AB5"
				( objectStatus "@baseboard_fab2_lib.baseboard_fab2(sch_1):page147_i106:gpiop3_tach11_vpir9" )
			)
			( pin "U25W4.Y6"
				( objectStatus "@baseboard_fab2_lib.baseboard_fab2(sch_1):page147_i106:gpiop4_tach12" )
			)
			( pin "U25W4.Y5"
				( objectStatus "@baseboard_fab2_lib.baseboard_fab2(sch_1):page147_i106:gpiop5_tach13" )
			)
			( pin "U25W4.W6"
				( objectStatus "@baseboard_fab2_lib.baseboard_fab2(sch_1):page147_i106:gpiop6_tach14" )
			)
			( pin "U25W4.V6"
				( objectStatus "@baseboard_fab2_lib.baseboard_fab2(sch_1):page147_i106:gpiop7_tach15" )
			)
			( pin "U25W4.D8"
				( objectStatus "@baseboard_fab2_lib.baseboard_fab2(sch_1):page147_i106:gpior6_mdc1" )
			)
			( pin "U25W4.E10"
				( objectStatus "@baseboard_fab2_lib.baseboard_fab2(sch_1):page147_i106:gpior7_mdio1" )
			)
			( pin "U25W4.B4"
				( objectStatus "@baseboard_fab2_lib.baseboard_fab2(sch_1):page147_i106:rgmii1rxck_rmii1rclki_gpiou4" )
			)
			( pin "U25W4.A4"
				( objectStatus "@baseboard_fab2_lib.baseboard_fab2(sch_1):page147_i106:rgmii1rxctl_gpiou5" )
			)
			( pin "U25W4.A3"
				( objectStatus "@baseboard_fab2_lib.baseboard_fab2(sch_1):page147_i106:rgmii1rxd0_rmii1rxd0_gpiou6" )
			)
			( pin "U25W4.D6"
				( objectStatus "@baseboard_fab2_lib.baseboard_fab2(sch_1):page147_i106:rgmii1rxd1_rmii1rxd1_gpiou7" )
			)
			( pin "U25W4.C5"
				( objectStatus "@baseboard_fab2_lib.baseboard_fab2(sch_1):page147_i106:rgmii1rxd2_rmii1crsdv_gpiov0" )
			)
			( pin "U25W4.C4"
				( objectStatus "@baseboard_fab2_lib.baseboard_fab2(sch_1):page147_i106:rgmii1rxd3_rmii1rxer_gpiov1" )
			)
			( pin "U25W4.B5"
				( objectStatus "@baseboard_fab2_lib.baseboard_fab2(sch_1):page147_i106:rgmii1txck_rmii1rclko_gpiot0" )
			)
			( pin "U25W4.E9"
				( objectStatus "@baseboard_fab2_lib.baseboard_fab2(sch_1):page147_i106:rgmii1txctl_rmii1txen_gpiot1" )
			)
			( pin "U25W4.F9"
				( objectStatus "@baseboard_fab2_lib.baseboard_fab2(sch_1):page147_i106:rgmii1txd0_rmii1txd0_gpiot2" )
			)
			( pin "U25W4.A5"
				( objectStatus "@baseboard_fab2_lib.baseboard_fab2(sch_1):page147_i106:rgmii1txd1_rmii1txd1_gpiot3" )
			)
			( pin "U25W4.E7"
				( objectStatus "@baseboard_fab2_lib.baseboard_fab2(sch_1):page147_i106:rgmii1txd2_gpiot4" )
			)
			( pin "U25W4.D7"
				( objectStatus "@baseboard_fab2_lib.baseboard_fab2(sch_1):page147_i106:rgmii1txd3_gpiot5" )
			)
			( pin "U25W4.C2"
				( objectStatus "@baseboard_fab2_lib.baseboard_fab2(sch_1):page147_i106:rgmii2rxck_rmii2rclki_gpiov2" )
			)
			( pin "U25W4.C1"
				( objectStatus "@baseboard_fab2_lib.baseboard_fab2(sch_1):page147_i106:rgmii2rxctl_gpiov3" )
			)
			( pin "U25W4.C3"
				( objectStatus "@baseboard_fab2_lib.baseboard_fab2(sch_1):page147_i106:rgmii2rxd0_rmii2rxd0_gpiov4" )
			)
			( pin "U25W4.D1"
				( objectStatus "@baseboard_fab2_lib.baseboard_fab2(sch_1):page147_i106:rgmii2rxd1_rmii2rxd1_gpiov5" )
			)
			( pin "U25W4.D2"
				( objectStatus "@baseboard_fab2_lib.baseboard_fab2(sch_1):page147_i106:rgmii2rxd2_rmii2crsdv_gpiov6" )
			)
			( pin "U25W4.E6"
				( objectStatus "@baseboard_fab2_lib.baseboard_fab2(sch_1):page147_i106:rgmii2rxd3_rmii2rxer_gpiov7" )
			)
			( pin "U25W4.B2"
				( objectStatus "@baseboard_fab2_lib.baseboard_fab2(sch_1):page147_i106:rgmii2txck_rmii2rclko_gpiot6" )
			)
			( pin "U25W4.B1"
				( objectStatus "@baseboard_fab2_lib.baseboard_fab2(sch_1):page147_i106:rgmii2txctl_rmii2txen_gpiot7" )
			)
			( pin "U25W4.A2"
				( objectStatus "@baseboard_fab2_lib.baseboard_fab2(sch_1):page147_i106:rgmii2txd0_rmii2txd0_gpiou0" )
			)
			( pin "U25W4.B3"
				( objectStatus "@baseboard_fab2_lib.baseboard_fab2(sch_1):page147_i106:rgmii2txd1_rmii2txd1_gpiou1" )
			)
			( pin "U25W4.D5"
				( objectStatus "@baseboard_fab2_lib.baseboard_fab2(sch_1):page147_i106:rgmii2txd2_gpiou2" )
			)
			( pin "U25W4.D4"
				( objectStatus "@baseboard_fab2_lib.baseboard_fab2(sch_1):page147_i106:rgmii2txd3_gpiou3" )
			)
			( pin "U25W4.D3"
				( objectStatus "@baseboard_fab2_lib.baseboard_fab2(sch_1):page147_i106:rgmiick" )
			)
			( pin "R1U1.1"
				( objectStatus "@baseboard_fab2_lib.baseboard_fab2(sch_1):page147_i61:a" )
			)
			( pin "R1U1.2"
				( objectStatus "@baseboard_fab2_lib.baseboard_fab2(sch_1):page147_i61:b" )
			)
			( pin "R1T26.1"
				( objectStatus "@baseboard_fab2_lib.baseboard_fab2(sch_1):page146_i37:a" )
			)
			( pin "R1T26.2"
				( objectStatus "@baseboard_fab2_lib.baseboard_fab2(sch_1):page146_i37:b" )
			)
			( pin "R1T25.1"
				( objectStatus "@baseboard_fab2_lib.baseboard_fab2(sch_1):page146_i35:a" )
			)
			( pin "R1T25.2"
				( objectStatus "@baseboard_fab2_lib.baseboard_fab2(sch_1):page146_i35:b" )
			)
			( pin "R25W83.1"
				( objectStatus "@baseboard_fab2_lib.baseboard_fab2(sch_1):page146_i26:a" )
			)
			( pin "R25W83.2"
				( objectStatus "@baseboard_fab2_lib.baseboard_fab2(sch_1):page146_i26:b" )
			)
			( pin "C25W70.1"
				( objectStatus "@baseboard_fab2_lib.baseboard_fab2(sch_1):page149_i5:a" )
			)
			( pin "C25W70.2"
				( objectStatus "@baseboard_fab2_lib.baseboard_fab2(sch_1):page149_i5:b" )
			)
			( pin "R25W90.1"
				( objectStatus "@baseboard_fab2_lib.baseboard_fab2(sch_1):page147_i21:a" )
			)
			( pin "R25W90.2"
				( objectStatus "@baseboard_fab2_lib.baseboard_fab2(sch_1):page147_i21:b" )
			)
			( pin "C25W55.1"
				( objectStatus "@baseboard_fab2_lib.baseboard_fab2(sch_1):page149_i124:a" )
			)
			( pin "C25W55.2"
				( objectStatus "@baseboard_fab2_lib.baseboard_fab2(sch_1):page149_i124:b" )
			)
			( pin "RT12.1"
				( objectStatus "@baseboard_fab2_lib.baseboard_fab2(sch_1):page208_i120:\1\" )
			)
			( pin "RT12.2"
				( objectStatus "@baseboard_fab2_lib.baseboard_fab2(sch_1):page208_i120:\2\" )
			)
			( pin "R9F61.1"
				( objectStatus "@baseboard_fab2_lib.baseboard_fab2(sch_1):page145_i14:a" )
			)
			( pin "R9F61.2"
				( objectStatus "@baseboard_fab2_lib.baseboard_fab2(sch_1):page145_i14:b" )
			)
			( pin "R9F62.1"
				( objectStatus "@baseboard_fab2_lib.baseboard_fab2(sch_1):page145_i11:a" )
			)
			( pin "R9F62.2"
				( objectStatus "@baseboard_fab2_lib.baseboard_fab2(sch_1):page145_i11:b" )
			)
			( pin "R9F60.1"
				( objectStatus "@baseboard_fab2_lib.baseboard_fab2(sch_1):page145_i10:a" )
			)
			( pin "R9F60.2"
				( objectStatus "@baseboard_fab2_lib.baseboard_fab2(sch_1):page145_i10:b" )
			)
			( pin "Y9F2.1"
				( objectStatus "@baseboard_fab2_lib.baseboard_fab2(sch_1):page145_i8:enable_control" )
			)
			( pin "Y9F2.2"
				( objectStatus "@baseboard_fab2_lib.baseboard_fab2(sch_1):page145_i8:gnd" )
			)
			( pin "Y9F2.3"
				( objectStatus "@baseboard_fab2_lib.baseboard_fab2(sch_1):page145_i8:\out\" )
			)
			( pin "Y9F2.4"
				( objectStatus "@baseboard_fab2_lib.baseboard_fab2(sch_1):page145_i8:vdd" )
			)
			( pin "R12W15.1"
				( objectStatus "@baseboard_fab2_lib.baseboard_fab2(sch_1):page197_i112:\1\" )
			)
			( pin "R12W15.2"
				( objectStatus "@baseboard_fab2_lib.baseboard_fab2(sch_1):page197_i112:\2\" )
			)
			( pin "R25W33.1"
				( objectStatus "@baseboard_fab2_lib.baseboard_fab2(sch_1):page151_i228:\1\" )
			)
			( pin "R25W33.2"
				( objectStatus "@baseboard_fab2_lib.baseboard_fab2(sch_1):page151_i228:\2\" )
			)
			( pin "C25W1.1"
				( objectStatus "@baseboard_fab2_lib.baseboard_fab2(sch_1):page151_i125:a" )
			)
			( pin "C25W1.2"
				( objectStatus "@baseboard_fab2_lib.baseboard_fab2(sch_1):page151_i125:b" )
			)
			( pin "C25W19.1"
				( objectStatus "@baseboard_fab2_lib.baseboard_fab2(sch_1):page151_i123:a" )
			)
			( pin "C25W19.2"
				( objectStatus "@baseboard_fab2_lib.baseboard_fab2(sch_1):page151_i123:b" )
			)
			( pin "C25W18.1"
				( objectStatus "@baseboard_fab2_lib.baseboard_fab2(sch_1):page151_i121:\1\" )
			)
			( pin "C25W18.2"
				( objectStatus "@baseboard_fab2_lib.baseboard_fab2(sch_1):page151_i121:\2\" )
			)
			( pin "C25W17.1"
				( objectStatus "@baseboard_fab2_lib.baseboard_fab2(sch_1):page151_i120:\1\" )
			)
			( pin "C25W17.2"
				( objectStatus "@baseboard_fab2_lib.baseboard_fab2(sch_1):page151_i120:\2\" )
			)
			( pin "C1W21.1"
				( objectStatus "@baseboard_fab2_lib.baseboard_fab2(sch_1):page146_i160:a" )
			)
			( pin "C1W21.2"
				( objectStatus "@baseboard_fab2_lib.baseboard_fab2(sch_1):page146_i160:b" )
			)
			( pin "R6U14.1"
				( objectStatus "@baseboard_fab2_lib.baseboard_fab2(sch_1):page99_i115:a" )
			)
			( pin "R6U14.2"
				( objectStatus "@baseboard_fab2_lib.baseboard_fab2(sch_1):page99_i115:b" )
			)
			( pin "R25W117.1"
				( objectStatus "@baseboard_fab2_lib.baseboard_fab2(sch_1):page151_i101:a" )
			)
			( pin "R25W117.2"
				( objectStatus "@baseboard_fab2_lib.baseboard_fab2(sch_1):page151_i101:b" )
			)
			( pin "C25W31.1"
				( objectStatus "@baseboard_fab2_lib.baseboard_fab2(sch_1):page149_i119:a" )
			)
			( pin "C25W31.2"
				( objectStatus "@baseboard_fab2_lib.baseboard_fab2(sch_1):page149_i119:b" )
			)
			( pin "C25W34.1"
				( objectStatus "@baseboard_fab2_lib.baseboard_fab2(sch_1):page149_i120:a" )
			)
			( pin "C25W34.2"
				( objectStatus "@baseboard_fab2_lib.baseboard_fab2(sch_1):page149_i120:b" )
			)
			( pin "R25W1.1"
				( objectStatus "@baseboard_fab2_lib.baseboard_fab2(sch_1):page151_i248:\1\" )
			)
			( pin "R25W1.2"
				( objectStatus "@baseboard_fab2_lib.baseboard_fab2(sch_1):page151_i248:\2\" )
			)
			( pin "U9F3.2"
				( objectStatus "@baseboard_fab2_lib.baseboard_fab2(sch_1):page151_i56:a" )
			)
			( pin "U9F3.4"
				( objectStatus "@baseboard_fab2_lib.baseboard_fab2(sch_1):page151_i56:y" )
			)
			( pin "R1T24.1"
				( objectStatus "@baseboard_fab2_lib.baseboard_fab2(sch_1):page147_i129:a" )
			)
			( pin "R1T24.2"
				( objectStatus "@baseboard_fab2_lib.baseboard_fab2(sch_1):page147_i129:b" )
			)
			( pin "R1U5.1"
				( objectStatus "@baseboard_fab2_lib.baseboard_fab2(sch_1):page147_i66:a" )
			)
			( pin "R1U5.2"
				( objectStatus "@baseboard_fab2_lib.baseboard_fab2(sch_1):page147_i66:b" )
			)
			( pin "R1U4.1"
				( objectStatus "@baseboard_fab2_lib.baseboard_fab2(sch_1):page147_i65:a" )
			)
			( pin "R1U4.2"
				( objectStatus "@baseboard_fab2_lib.baseboard_fab2(sch_1):page147_i65:b" )
			)
			( pin "R25W80.1"
				( objectStatus "@baseboard_fab2_lib.baseboard_fab2(sch_1):page147_i43:a" )
			)
			( pin "R25W80.2"
				( objectStatus "@baseboard_fab2_lib.baseboard_fab2(sch_1):page147_i43:b" )
			)
			( pin "R25W79.1"
				( objectStatus "@baseboard_fab2_lib.baseboard_fab2(sch_1):page147_i42:a" )
			)
			( pin "R25W79.2"
				( objectStatus "@baseboard_fab2_lib.baseboard_fab2(sch_1):page147_i42:b" )
			)
			( pin "C25W7.1"
				( objectStatus "@baseboard_fab2_lib.baseboard_fab2(sch_1):page147_i161:a" )
			)
			( pin "C25W7.2"
				( objectStatus "@baseboard_fab2_lib.baseboard_fab2(sch_1):page147_i161:b" )
			)
			( pin "R25W87.1"
				( objectStatus "@baseboard_fab2_lib.baseboard_fab2(sch_1):page147_i25:a" )
			)
			( pin "R25W87.2"
				( objectStatus "@baseboard_fab2_lib.baseboard_fab2(sch_1):page147_i25:b" )
			)
			( pin "R25W86.1"
				( objectStatus "@baseboard_fab2_lib.baseboard_fab2(sch_1):page147_i24:a" )
			)
			( pin "R25W86.2"
				( objectStatus "@baseboard_fab2_lib.baseboard_fab2(sch_1):page147_i24:b" )
			)
			( pin "R25W85.1"
				( objectStatus "@baseboard_fab2_lib.baseboard_fab2(sch_1):page147_i23:a" )
			)
			( pin "R25W85.2"
				( objectStatus "@baseboard_fab2_lib.baseboard_fab2(sch_1):page147_i23:b" )
			)
			( pin "R25W89.1"
				( objectStatus "@baseboard_fab2_lib.baseboard_fab2(sch_1):page147_i22:a" )
			)
			( pin "R25W89.2"
				( objectStatus "@baseboard_fab2_lib.baseboard_fab2(sch_1):page147_i22:b" )
			)
			( pin "R25W88.1"
				( objectStatus "@baseboard_fab2_lib.baseboard_fab2(sch_1):page147_i8:a" )
			)
			( pin "R25W88.2"
				( objectStatus "@baseboard_fab2_lib.baseboard_fab2(sch_1):page147_i8:b" )
			)
			( pin "R25W69.1"
				( objectStatus "@baseboard_fab2_lib.baseboard_fab2(sch_1):page146_i85:a" )
			)
			( pin "R25W69.2"
				( objectStatus "@baseboard_fab2_lib.baseboard_fab2(sch_1):page146_i85:b" )
			)
			( pin "R25W68.1"
				( objectStatus "@baseboard_fab2_lib.baseboard_fab2(sch_1):page146_i84:a" )
			)
			( pin "R25W68.2"
				( objectStatus "@baseboard_fab2_lib.baseboard_fab2(sch_1):page146_i84:b" )
			)
			( pin "R1U7.1"
				( objectStatus "@baseboard_fab2_lib.baseboard_fab2(sch_1):page146_i78:a" )
			)
			( pin "R1U7.2"
				( objectStatus "@baseboard_fab2_lib.baseboard_fab2(sch_1):page146_i78:b" )
			)
			( pin "R25W66.1"
				( objectStatus "@baseboard_fab2_lib.baseboard_fab2(sch_1):page146_i76:a" )
			)
			( pin "R25W66.2"
				( objectStatus "@baseboard_fab2_lib.baseboard_fab2(sch_1):page146_i76:b" )
			)
			( pin "R3N26.1"
				( objectStatus "@baseboard_fab2_lib.baseboard_fab2(sch_1):page146_i75:a" )
			)
			( pin "R3N26.2"
				( objectStatus "@baseboard_fab2_lib.baseboard_fab2(sch_1):page146_i75:b" )
			)
			( pin "R3N24.1"
				( objectStatus "@baseboard_fab2_lib.baseboard_fab2(sch_1):page146_i74:a" )
			)
			( pin "R3N24.2"
				( objectStatus "@baseboard_fab2_lib.baseboard_fab2(sch_1):page146_i74:b" )
			)
			( pin "R25W73.1"
				( objectStatus "@baseboard_fab2_lib.baseboard_fab2(sch_1):page146_i73:a" )
			)
			( pin "R25W73.2"
				( objectStatus "@baseboard_fab2_lib.baseboard_fab2(sch_1):page146_i73:b" )
			)
			( pin "RF4.1"
				( objectStatus "@baseboard_fab2_lib.baseboard_fab2(sch_1):page201_i185:a" )
			)
			( pin "RF4.2"
				( objectStatus "@baseboard_fab2_lib.baseboard_fab2(sch_1):page201_i185:b" )
			)
			( pin "R25W72.1"
				( objectStatus "@baseboard_fab2_lib.baseboard_fab2(sch_1):page146_i71:a" )
			)
			( pin "R25W72.2"
				( objectStatus "@baseboard_fab2_lib.baseboard_fab2(sch_1):page146_i71:b" )
			)
			( pin "R25W74.1"
				( objectStatus "@baseboard_fab2_lib.baseboard_fab2(sch_1):page146_i70:a" )
			)
			( pin "R25W74.2"
				( objectStatus "@baseboard_fab2_lib.baseboard_fab2(sch_1):page146_i70:b" )
			)
			( pin "R9E21.1"
				( objectStatus "@baseboard_fab2_lib.baseboard_fab2(sch_1):page151_i173:a" )
			)
			( pin "R9E21.2"
				( objectStatus "@baseboard_fab2_lib.baseboard_fab2(sch_1):page151_i173:b" )
			)
			( pin "R25W2.1"
				( objectStatus "@baseboard_fab2_lib.baseboard_fab2(sch_1):page151_i249:\1\" )
			)
			( pin "R25W2.2"
				( objectStatus "@baseboard_fab2_lib.baseboard_fab2(sch_1):page151_i249:\2\" )
			)
			( pin "R25W3.1"
				( objectStatus "@baseboard_fab2_lib.baseboard_fab2(sch_1):page151_i250:\1\" )
			)
			( pin "R25W3.2"
				( objectStatus "@baseboard_fab2_lib.baseboard_fab2(sch_1):page151_i250:\2\" )
			)
			( pin "R25W4.1"
				( objectStatus "@baseboard_fab2_lib.baseboard_fab2(sch_1):page151_i251:\1\" )
			)
			( pin "R25W4.2"
				( objectStatus "@baseboard_fab2_lib.baseboard_fab2(sch_1):page151_i251:\2\" )
			)
			( pin "R25W5.1"
				( objectStatus "@baseboard_fab2_lib.baseboard_fab2(sch_1):page151_i252:\1\" )
			)
			( pin "R25W5.2"
				( objectStatus "@baseboard_fab2_lib.baseboard_fab2(sch_1):page151_i252:\2\" )
			)
			( pin "R25W6.1"
				( objectStatus "@baseboard_fab2_lib.baseboard_fab2(sch_1):page151_i253:\1\" )
			)
			( pin "R25W6.2"
				( objectStatus "@baseboard_fab2_lib.baseboard_fab2(sch_1):page151_i253:\2\" )
			)
			( pin "R25W7.1"
				( objectStatus "@baseboard_fab2_lib.baseboard_fab2(sch_1):page151_i254:\1\" )
			)
			( pin "R25W7.2"
				( objectStatus "@baseboard_fab2_lib.baseboard_fab2(sch_1):page151_i254:\2\" )
			)
			( pin "R25W8.1"
				( objectStatus "@baseboard_fab2_lib.baseboard_fab2(sch_1):page151_i255:\1\" )
			)
			( pin "R25W8.2"
				( objectStatus "@baseboard_fab2_lib.baseboard_fab2(sch_1):page151_i255:\2\" )
			)
			( pin "R25W12.1"
				( objectStatus "@baseboard_fab2_lib.baseboard_fab2(sch_1):page151_i256:\1\" )
			)
			( pin "R25W12.2"
				( objectStatus "@baseboard_fab2_lib.baseboard_fab2(sch_1):page151_i256:\2\" )
			)
			( pin "R25W11.1"
				( objectStatus "@baseboard_fab2_lib.baseboard_fab2(sch_1):page151_i257:\1\" )
			)
			( pin "R25W11.2"
				( objectStatus "@baseboard_fab2_lib.baseboard_fab2(sch_1):page151_i257:\2\" )
			)
			( pin "R25W9.1"
				( objectStatus "@baseboard_fab2_lib.baseboard_fab2(sch_1):page151_i258:\1\" )
			)
			( pin "R25W9.2"
				( objectStatus "@baseboard_fab2_lib.baseboard_fab2(sch_1):page151_i258:\2\" )
			)
			( pin "R25W10.1"
				( objectStatus "@baseboard_fab2_lib.baseboard_fab2(sch_1):page151_i259:\1\" )
			)
			( pin "R25W10.2"
				( objectStatus "@baseboard_fab2_lib.baseboard_fab2(sch_1):page151_i259:\2\" )
			)
			( pin "R25W13.1"
				( objectStatus "@baseboard_fab2_lib.baseboard_fab2(sch_1):page151_i260:\1\" )
			)
			( pin "R25W13.2"
				( objectStatus "@baseboard_fab2_lib.baseboard_fab2(sch_1):page151_i260:\2\" )
			)
			( pin "R25W16.1"
				( objectStatus "@baseboard_fab2_lib.baseboard_fab2(sch_1):page151_i261:\1\" )
			)
			( pin "R25W16.2"
				( objectStatus "@baseboard_fab2_lib.baseboard_fab2(sch_1):page151_i261:\2\" )
			)
			( pin "R25W15.1"
				( objectStatus "@baseboard_fab2_lib.baseboard_fab2(sch_1):page151_i262:\1\" )
			)
			( pin "R25W15.2"
				( objectStatus "@baseboard_fab2_lib.baseboard_fab2(sch_1):page151_i262:\2\" )
			)
			( pin "R25W14.1"
				( objectStatus "@baseboard_fab2_lib.baseboard_fab2(sch_1):page151_i263:\1\" )
			)
			( pin "R25W14.2"
				( objectStatus "@baseboard_fab2_lib.baseboard_fab2(sch_1):page151_i263:\2\" )
			)
			( pin "R25W17.1"
				( objectStatus "@baseboard_fab2_lib.baseboard_fab2(sch_1):page151_i264:\1\" )
			)
			( pin "R25W17.2"
				( objectStatus "@baseboard_fab2_lib.baseboard_fab2(sch_1):page151_i264:\2\" )
			)
			( pin "R25W18.1"
				( objectStatus "@baseboard_fab2_lib.baseboard_fab2(sch_1):page151_i265:\1\" )
			)
			( pin "R25W18.2"
				( objectStatus "@baseboard_fab2_lib.baseboard_fab2(sch_1):page151_i265:\2\" )
			)
			( pin "R25W20.1"
				( objectStatus "@baseboard_fab2_lib.baseboard_fab2(sch_1):page151_i266:\1\" )
			)
			( pin "R25W20.2"
				( objectStatus "@baseboard_fab2_lib.baseboard_fab2(sch_1):page151_i266:\2\" )
			)
			( pin "R25W19.1"
				( objectStatus "@baseboard_fab2_lib.baseboard_fab2(sch_1):page151_i267:\1\" )
			)
			( pin "R25W19.2"
				( objectStatus "@baseboard_fab2_lib.baseboard_fab2(sch_1):page151_i267:\2\" )
			)
			( pin "R25W24.1"
				( objectStatus "@baseboard_fab2_lib.baseboard_fab2(sch_1):page151_i268:\1\" )
			)
			( pin "R25W24.2"
				( objectStatus "@baseboard_fab2_lib.baseboard_fab2(sch_1):page151_i268:\2\" )
			)
			( pin "R25W118.1"
				( objectStatus "@baseboard_fab2_lib.baseboard_fab2(sch_1):page151_i211:a" )
			)
			( pin "R25W118.2"
				( objectStatus "@baseboard_fab2_lib.baseboard_fab2(sch_1):page151_i211:b" )
			)
			( pin "Q9E1.3"
				( objectStatus "@baseboard_fab2_lib.baseboard_fab2(sch_1):page151_i145:drain(0)" )
			)
			( pin "Q9E1.5"
				( objectStatus "@baseboard_fab2_lib.baseboard_fab2(sch_1):page151_i145:gate(0)" )
			)
			( pin "Q9E1.4"
				( objectStatus "@baseboard_fab2_lib.baseboard_fab2(sch_1):page151_i145:source(0)" )
			)
			( pin "DS9E1.1"
				( objectStatus "@baseboard_fab2_lib.baseboard_fab2(sch_1):page151_i144:a" )
			)
			( pin "DS9E1.2"
				( objectStatus "@baseboard_fab2_lib.baseboard_fab2(sch_1):page151_i144:c" )
			)
			( pin "C25W16.1"
				( objectStatus "@baseboard_fab2_lib.baseboard_fab2(sch_1):page151_i58:a" )
			)
			( pin "C25W16.2"
				( objectStatus "@baseboard_fab2_lib.baseboard_fab2(sch_1):page151_i58:b" )
			)
			( pin "R2N13.1"
				( objectStatus "@baseboard_fab2_lib.baseboard_fab2(sch_1):page147_i75:a" )
			)
			( pin "R2N13.2"
				( objectStatus "@baseboard_fab2_lib.baseboard_fab2(sch_1):page147_i75:b" )
			)
			( pin "R25W78.1"
				( objectStatus "@baseboard_fab2_lib.baseboard_fab2(sch_1):page146_i123:a" )
			)
			( pin "R25W78.2"
				( objectStatus "@baseboard_fab2_lib.baseboard_fab2(sch_1):page146_i123:b" )
			)
			( pin "R1T15.1"
				( objectStatus "@baseboard_fab2_lib.baseboard_fab2(sch_1):page145_i100:a" )
			)
			( pin "R1T15.2"
				( objectStatus "@baseboard_fab2_lib.baseboard_fab2(sch_1):page145_i100:b" )
			)
			( pin "R1T23.1"
				( objectStatus "@baseboard_fab2_lib.baseboard_fab2(sch_1):page145_i101:a" )
			)
			( pin "R1T23.2"
				( objectStatus "@baseboard_fab2_lib.baseboard_fab2(sch_1):page145_i101:b" )
			)
			( pin "C6W3.1"
				( objectStatus "@baseboard_fab2_lib.baseboard_fab2(sch_1):page247_i85:a" )
			)
			( pin "C6W3.2"
				( objectStatus "@baseboard_fab2_lib.baseboard_fab2(sch_1):page247_i85:b" )
			)
			( pin "R6W20.1"
				( objectStatus "@baseboard_fab2_lib.baseboard_fab2(sch_1):page247_i87:a" )
			)
			( pin "R6W20.2"
				( objectStatus "@baseboard_fab2_lib.baseboard_fab2(sch_1):page247_i87:b" )
			)
			( pin "U6W3.1"
				( objectStatus "@baseboard_fab2_lib.baseboard_fab2(sch_1):page247_i89:a0" )
			)
			( pin "U6W3.2"
				( objectStatus "@baseboard_fab2_lib.baseboard_fab2(sch_1):page247_i89:a1" )
			)
			( pin "U6W3.3"
				( objectStatus "@baseboard_fab2_lib.baseboard_fab2(sch_1):page247_i89:a2" )
			)
			( pin "U6W3.6"
				( objectStatus "@baseboard_fab2_lib.baseboard_fab2(sch_1):page247_i89:scl" )
			)
			( pin "U6W3.5"
				( objectStatus "@baseboard_fab2_lib.baseboard_fab2(sch_1):page247_i89:sda" )
			)
			( pin "U6W3.7"
				( objectStatus "@baseboard_fab2_lib.baseboard_fab2(sch_1):page247_i89:wp" )
			)
			( pin "R6W21.1"
				( objectStatus "@baseboard_fab2_lib.baseboard_fab2(sch_1):page247_i90:a" )
			)
			( pin "R6W21.2"
				( objectStatus "@baseboard_fab2_lib.baseboard_fab2(sch_1):page247_i90:b" )
			)
			( pin "R6W23.1"
				( objectStatus "@baseboard_fab2_lib.baseboard_fab2(sch_1):page247_i92:a" )
			)
			( pin "R6W23.2"
				( objectStatus "@baseboard_fab2_lib.baseboard_fab2(sch_1):page247_i92:b" )
			)
			( pin "R6W22.1"
				( objectStatus "@baseboard_fab2_lib.baseboard_fab2(sch_1):page247_i94:a" )
			)
			( pin "R6W22.2"
				( objectStatus "@baseboard_fab2_lib.baseboard_fab2(sch_1):page247_i94:b" )
			)
			( pin "U25W4.V13"
				( objectStatus "@baseboard_fab2_lib.baseboard_fab2(sch_1):page143_i63:ma0" )
			)
			( pin "U25W4.AB14"
				( objectStatus "@baseboard_fab2_lib.baseboard_fab2(sch_1):page143_i63:ma1" )
			)
			( pin "U25W4.W14"
				( objectStatus "@baseboard_fab2_lib.baseboard_fab2(sch_1):page143_i63:ma2" )
			)
			( pin "U25W4.U14"
				( objectStatus "@baseboard_fab2_lib.baseboard_fab2(sch_1):page143_i63:ma3" )
			)
			( pin "U25W4.W15"
				( objectStatus "@baseboard_fab2_lib.baseboard_fab2(sch_1):page143_i63:ma4" )
			)
			( pin "U25W4.V15"
				( objectStatus "@baseboard_fab2_lib.baseboard_fab2(sch_1):page143_i63:ma5" )
			)
			( pin "U25W4.AB16"
				( objectStatus "@baseboard_fab2_lib.baseboard_fab2(sch_1):page143_i63:ma6" )
			)
			( pin "U25W4.AA16"
				( objectStatus "@baseboard_fab2_lib.baseboard_fab2(sch_1):page143_i63:ma7" )
			)
			( pin "U25W4.W16"
				( objectStatus "@baseboard_fab2_lib.baseboard_fab2(sch_1):page143_i63:ma8" )
			)
			( pin "U25W4.Y16"
				( objectStatus "@baseboard_fab2_lib.baseboard_fab2(sch_1):page143_i63:ma9" )
			)
			( pin "U25W4.U13"
				( objectStatus "@baseboard_fab2_lib.baseboard_fab2(sch_1):page143_i63:ma10" )
			)
			( pin "U25W4.AA14"
				( objectStatus "@baseboard_fab2_lib.baseboard_fab2(sch_1):page143_i63:ma11" )
			)
			( pin "U25W4.Y14"
				( objectStatus "@baseboard_fab2_lib.baseboard_fab2(sch_1):page143_i63:ma12" )
			)
			( pin "U25W4.AB15"
				( objectStatus "@baseboard_fab2_lib.baseboard_fab2(sch_1):page143_i63:ma13" )
			)
			( pin "U25W4.Y15"
				( objectStatus "@baseboard_fab2_lib.baseboard_fab2(sch_1):page143_i63:\ma14_mact#\" )
			)
			( pin "U25W4.U15"
				( objectStatus "@baseboard_fab2_lib.baseboard_fab2(sch_1):page143_i63:ma15" )
			)
			( pin "U25W4.U12"
				( objectStatus "@baseboard_fab2_lib.baseboard_fab2(sch_1):page143_i63:mba0" )
			)
			( pin "U25W4.Y13"
				( objectStatus "@baseboard_fab2_lib.baseboard_fab2(sch_1):page143_i63:mba1" )
			)
			( pin "U25W4.W13"
				( objectStatus "@baseboard_fab2_lib.baseboard_fab2(sch_1):page143_i63:mba2_mbg0" )
			)
			( pin "U25W4.AB13"
				( objectStatus "@baseboard_fab2_lib.baseboard_fab2(sch_1):page143_i63:\mcas#\" )
			)
			( pin "U25W4.Y11"
				( objectStatus "@baseboard_fab2_lib.baseboard_fab2(sch_1):page143_i63:mcke" )
			)
			( pin "U25W4.AB12"
				( objectStatus "@baseboard_fab2_lib.baseboard_fab2(sch_1):page143_i63:mckn" )
			)
			( pin "U25W4.AB11"
				( objectStatus "@baseboard_fab2_lib.baseboard_fab2(sch_1):page143_i63:mckp" )
			)
			( pin "U25W4.AA12"
				( objectStatus "@baseboard_fab2_lib.baseboard_fab2(sch_1):page143_i63:\mcs#\" )
			)
			( pin "U25W4.U8"
				( objectStatus "@baseboard_fab2_lib.baseboard_fab2(sch_1):page143_i63:mdm0" )
			)
			( pin "U25W4.AB8"
				( objectStatus "@baseboard_fab2_lib.baseboard_fab2(sch_1):page143_i63:mdm1" )
			)
			( pin "U25W4.U10"
				( objectStatus "@baseboard_fab2_lib.baseboard_fab2(sch_1):page143_i63:mdq0" )
			)
			( pin "U25W4.W10"
				( objectStatus "@baseboard_fab2_lib.baseboard_fab2(sch_1):page143_i63:mdq1" )
			)
			( pin "U25W4.Y10"
				( objectStatus "@baseboard_fab2_lib.baseboard_fab2(sch_1):page143_i63:mdq2" )
			)
			( pin "U25W4.AA10"
				( objectStatus "@baseboard_fab2_lib.baseboard_fab2(sch_1):page143_i63:mdq3" )
			)
			( pin "U25W4.U9"
				( objectStatus "@baseboard_fab2_lib.baseboard_fab2(sch_1):page143_i63:mdq4" )
			)
			( pin "U25W4.Y9"
				( objectStatus "@baseboard_fab2_lib.baseboard_fab2(sch_1):page143_i63:mdq5" )
			)
			( pin "U25W4.W9"
				( objectStatus "@baseboard_fab2_lib.baseboard_fab2(sch_1):page143_i63:mdq6" )
			)
			( pin "U25W4.V9"
				( objectStatus "@baseboard_fab2_lib.baseboard_fab2(sch_1):page143_i63:mdq7" )
			)
			( pin "U25W4.AA8"
				( objectStatus "@baseboard_fab2_lib.baseboard_fab2(sch_1):page143_i63:mdq8" )
			)
			( pin "U25W4.Y8"
				( objectStatus "@baseboard_fab2_lib.baseboard_fab2(sch_1):page143_i63:mdq9" )
			)
			( pin "U25W4.Y7"
				( objectStatus "@baseboard_fab2_lib.baseboard_fab2(sch_1):page143_i63:mdq10" )
			)
			( pin "U25W4.W8"
				( objectStatus "@baseboard_fab2_lib.baseboard_fab2(sch_1):page143_i63:mdq11" )
			)
			( pin "U25W4.AA6"
				( objectStatus "@baseboard_fab2_lib.baseboard_fab2(sch_1):page143_i63:mdq12" )
			)
			( pin "U25W4.W7"
				( objectStatus "@baseboard_fab2_lib.baseboard_fab2(sch_1):page143_i63:mdq13" )
			)
			( pin "U25W4.V7"
				( objectStatus "@baseboard_fab2_lib.baseboard_fab2(sch_1):page143_i63:mdq14" )
			)
			( pin "U25W4.U7"
				( objectStatus "@baseboard_fab2_lib.baseboard_fab2(sch_1):page143_i63:mdq15" )
			)
			( pin "U25W4.AB10"
				( objectStatus "@baseboard_fab2_lib.baseboard_fab2(sch_1):page143_i63:mdqs0n" )
			)
			( pin "U25W4.AB9"
				( objectStatus "@baseboard_fab2_lib.baseboard_fab2(sch_1):page143_i63:mdqs0p" )
			)
			( pin "U25W4.AB6"
				( objectStatus "@baseboard_fab2_lib.baseboard_fab2(sch_1):page143_i63:mdqs1n" )
			)
			( pin "U25W4.AB7"
				( objectStatus "@baseboard_fab2_lib.baseboard_fab2(sch_1):page143_i63:mdqs1p" )
			)
			( pin "U25W4.W11"
				( objectStatus "@baseboard_fab2_lib.baseboard_fab2(sch_1):page143_i63:mioz" )
			)
			( pin "U25W4.V11"
				( objectStatus "@baseboard_fab2_lib.baseboard_fab2(sch_1):page143_i63:modt" )
			)
			( pin "U25W4.W12"
				( objectStatus "@baseboard_fab2_lib.baseboard_fab2(sch_1):page143_i63:\mras#\" )
			)
			( pin "U25W4.T9"
				( objectStatus "@baseboard_fab2_lib.baseboard_fab2(sch_1):page143_i63:mvref" )
			)
			( pin "U25W4.Y12"
				( objectStatus "@baseboard_fab2_lib.baseboard_fab2(sch_1):page143_i63:\mwe#\" )
			)
			( pin "U25W4.K3"
				( objectStatus "@baseboard_fab2_lib.baseboard_fab2(sch_1):page146_i105:entest" )
			)
			( pin "U25W4.V18"
				( objectStatus "@baseboard_fab2_lib.baseboard_fab2(sch_1):page146_i105:\extrst#\" )
			)
			( pin "U25W4.AA18"
				( objectStatus "@baseboard_fab2_lib.baseboard_fab2(sch_1):page146_i105:fwspick" )
			)
			( pin "U25W4.AB19"
				( objectStatus "@baseboard_fab2_lib.baseboard_fab2(sch_1):page146_i105:\fwspics0#\" )
			)
			( pin "U25W4.T18"
				( objectStatus "@baseboard_fab2_lib.baseboard_fab2(sch_1):page146_i105:fwspimiso" )
			)
			( pin "U25W4.U17"
				( objectStatus "@baseboard_fab2_lib.baseboard_fab2(sch_1):page146_i105:fwspimosi" )
			)
			( pin "U25W4.N19"
				( objectStatus "@baseboard_fab2_lib.baseboard_fab2(sch_1):page146_i105:\gpioab0_vpode_noroe#\" )
			)
			( pin "U25W4.T21"
				( objectStatus "@baseboard_fab2_lib.baseboard_fab2(sch_1):page146_i105:\gpioab1_vpohs_norwe#\" )
			)
			( pin "U25W4.T22"
				( objectStatus "@baseboard_fab2_lib.baseboard_fab2(sch_1):page146_i105:gpioab2_vpovs_wdtrst1" )
			)
			( pin "U25W4.R20"
				( objectStatus "@baseboard_fab2_lib.baseboard_fab2(sch_1):page146_i105:gpioab3_vpoclk_wdtrst2" )
			)
			( pin "U25W4.G21"
				( objectStatus "@baseboard_fab2_lib.baseboard_fab2(sch_1):page146_i105:gpioac0_espid0_lad0" )
			)
			( pin "U25W4.G20"
				( objectStatus "@baseboard_fab2_lib.baseboard_fab2(sch_1):page146_i105:gpioac1_espid1_lad1" )
			)
			( pin "U25W4.D22"
				( objectStatus "@baseboard_fab2_lib.baseboard_fab2(sch_1):page146_i105:gpioac2_espid2_lad2" )
			)
			( pin "U25W4.E22"
				( objectStatus "@baseboard_fab2_lib.baseboard_fab2(sch_1):page146_i105:gpioac3_espid3_lad3" )
			)
			( pin "U25W4.C22"
				( objectStatus "@baseboard_fab2_lib.baseboard_fab2(sch_1):page146_i105:gpioac4_espick_lclk" )
			)
			( pin "U25W4.F21"
				( objectStatus "@baseboard_fab2_lib.baseboard_fab2(sch_1):page146_i105:\gpioac5_espics#_lframe#\" )
			)
			( pin "U25W4.F22"
				( objectStatus "@baseboard_fab2_lib.baseboard_fab2(sch_1):page146_i105:\gpioac6_espialt#_lsirq#\" )
			)
			( pin "U25W4.G22"
				( objectStatus "@baseboard_fab2_lib.baseboard_fab2(sch_1):page146_i105:\gpioac7_espirst#_lpcrst#\" )
			)
			( pin "U25W4.N5"
				( objectStatus "@baseboard_fab2_lib.baseboard_fab2(sch_1):page146_i105:gpioj4_vgahs" )
			)
			( pin "U25W4.R4"
				( objectStatus "@baseboard_fab2_lib.baseboard_fab2(sch_1):page146_i105:gpioj5_vgavs" )
			)
			( pin "U25W4.R3"
				( objectStatus "@baseboard_fab2_lib.baseboard_fab2(sch_1):page146_i105:gpioj6_ddcclk" )
			)
			( pin "U25W4.T3"
				( objectStatus "@baseboard_fab2_lib.baseboard_fab2(sch_1):page146_i105:gpioj7_ddcdat" )
			)
			( pin "U25W4.B10"
				( objectStatus "@baseboard_fab2_lib.baseboard_fab2(sch_1):page146_i105:gpioq6_oscclk" )
			)
			( pin "U25W4.N20"
				( objectStatus "@baseboard_fab2_lib.baseboard_fab2(sch_1):page146_i105:\gpioq7_pewake#\" )
			)
			( pin "U25W4.AA19"
				( objectStatus "@baseboard_fab2_lib.baseboard_fab2(sch_1):page146_i105:\gpior0_fwspics1#\" )
			)
			( pin "U25W4.T19"
				( objectStatus "@baseboard_fab2_lib.baseboard_fab2(sch_1):page146_i105:\gpior1_fwspics2#\" )
			)
			( pin "U25W4.T17"
				( objectStatus "@baseboard_fab2_lib.baseboard_fab2(sch_1):page146_i105:\gpior2_spi2cs0#\" )
			)
			( pin "U25W4.Y19"
				( objectStatus "@baseboard_fab2_lib.baseboard_fab2(sch_1):page146_i105:gpior3_spi2ck" )
			)
			( pin "U25W4.W19"
				( objectStatus "@baseboard_fab2_lib.baseboard_fab2(sch_1):page146_i105:gpior4_spi2mosi" )
			)
			( pin "U25W4.V19"
				( objectStatus "@baseboard_fab2_lib.baseboard_fab2(sch_1):page146_i105:gpior5_spi2miso" )
			)
			( pin "U25W4.Y18"
				( objectStatus "@baseboard_fab2_lib.baseboard_fab2(sch_1):page146_i105:\hbled#\" )
			)
			( pin "U25W4.U16"
				( objectStatus "@baseboard_fab2_lib.baseboard_fab2(sch_1):page146_i105:\malert#\" )
			)
			( pin "U25W4.AB17"
				( objectStatus "@baseboard_fab2_lib.baseboard_fab2(sch_1):page146_i105:\mreset#\" )
			)
			( pin "F25W1.1"
				( objectStatus "@baseboard_fab2_lib.baseboard_fab2(sch_1):page255_i89:\1\" )
			)
			( pin "F25W1.2"
				( objectStatus "@baseboard_fab2_lib.baseboard_fab2(sch_1):page255_i89:\2\" )
			)
			( pin "R6W11.1"
				( objectStatus "@baseboard_fab2_lib.baseboard_fab2(sch_1):page247_i98:a" )
			)
			( pin "R6W11.2"
				( objectStatus "@baseboard_fab2_lib.baseboard_fab2(sch_1):page247_i98:b" )
			)
			( pin "C6W2.1"
				( objectStatus "@baseboard_fab2_lib.baseboard_fab2(sch_1):page247_i107:a" )
			)
			( pin "C6W2.2"
				( objectStatus "@baseboard_fab2_lib.baseboard_fab2(sch_1):page247_i107:b" )
			)
			( pin "C7G19.1"
				( objectStatus "@baseboard_fab2_lib.baseboard_fab2(sch_1):page105_i257:a" )
			)
			( pin "C7G19.2"
				( objectStatus "@baseboard_fab2_lib.baseboard_fab2(sch_1):page105_i257:b" )
			)
			( pin "C7G20.1"
				( objectStatus "@baseboard_fab2_lib.baseboard_fab2(sch_1):page105_i258:a" )
			)
			( pin "C7G20.2"
				( objectStatus "@baseboard_fab2_lib.baseboard_fab2(sch_1):page105_i258:b" )
			)
			( pin "R25W67.1"
				( objectStatus "@baseboard_fab2_lib.baseboard_fab2(sch_1):page145_i118:\1\" )
			)
			( pin "R25W67.2"
				( objectStatus "@baseboard_fab2_lib.baseboard_fab2(sch_1):page145_i118:\2\" )
			)
			( pin "R6W18.1"
				( objectStatus "@baseboard_fab2_lib.baseboard_fab2(sch_1):page145_i119:a" )
			)
			( pin "R6W18.2"
				( objectStatus "@baseboard_fab2_lib.baseboard_fab2(sch_1):page145_i119:b" )
			)
			( pin "CF5.1"
				( objectStatus "@baseboard_fab2_lib.baseboard_fab2(sch_1):page201_i172:\1\" )
			)
			( pin "CF5.2"
				( objectStatus "@baseboard_fab2_lib.baseboard_fab2(sch_1):page201_i172:\2\" )
			)
			( pin "CF4.1"
				( objectStatus "@baseboard_fab2_lib.baseboard_fab2(sch_1):page201_i171:\1\" )
			)
			( pin "CF4.2"
				( objectStatus "@baseboard_fab2_lib.baseboard_fab2(sch_1):page201_i171:\2\" )
			)
			( pin "CF3.1"
				( objectStatus "@baseboard_fab2_lib.baseboard_fab2(sch_1):page201_i170:\1\" )
			)
			( pin "CF3.2"
				( objectStatus "@baseboard_fab2_lib.baseboard_fab2(sch_1):page201_i170:\2\" )
			)
			( pin "CF2.1"
				( objectStatus "@baseboard_fab2_lib.baseboard_fab2(sch_1):page201_i169:\1\" )
			)
			( pin "CF2.2"
				( objectStatus "@baseboard_fab2_lib.baseboard_fab2(sch_1):page201_i169:\2\" )
			)
			( pin "CF1.1"
				( objectStatus "@baseboard_fab2_lib.baseboard_fab2(sch_1):page201_i168:\1\" )
			)
			( pin "CF1.2"
				( objectStatus "@baseboard_fab2_lib.baseboard_fab2(sch_1):page201_i168:\2\" )
			)
			( pin "RF12.1"
				( objectStatus "@baseboard_fab2_lib.baseboard_fab2(sch_1):page206_i149:a" )
			)
			( pin "RF12.2"
				( objectStatus "@baseboard_fab2_lib.baseboard_fab2(sch_1):page206_i149:b" )
			)
			( pin "RF7.1"
				( objectStatus "@baseboard_fab2_lib.baseboard_fab2(sch_1):page206_i150:a" )
			)
			( pin "RF7.2"
				( objectStatus "@baseboard_fab2_lib.baseboard_fab2(sch_1):page206_i150:b" )
			)
			( pin "RF8.1"
				( objectStatus "@baseboard_fab2_lib.baseboard_fab2(sch_1):page206_i151:a" )
			)
			( pin "RF8.2"
				( objectStatus "@baseboard_fab2_lib.baseboard_fab2(sch_1):page206_i151:b" )
			)
			( pin "RF9.1"
				( objectStatus "@baseboard_fab2_lib.baseboard_fab2(sch_1):page206_i152:a" )
			)
			( pin "RF9.2"
				( objectStatus "@baseboard_fab2_lib.baseboard_fab2(sch_1):page206_i152:b" )
			)
			( pin "RF10.1"
				( objectStatus "@baseboard_fab2_lib.baseboard_fab2(sch_1):page206_i153:a" )
			)
			( pin "RF10.2"
				( objectStatus "@baseboard_fab2_lib.baseboard_fab2(sch_1):page206_i153:b" )
			)
			( pin "RF11.1"
				( objectStatus "@baseboard_fab2_lib.baseboard_fab2(sch_1):page206_i154:a" )
			)
			( pin "RF11.2"
				( objectStatus "@baseboard_fab2_lib.baseboard_fab2(sch_1):page206_i154:b" )
			)
			( pin "RF14.1"
				( objectStatus "@baseboard_fab2_lib.baseboard_fab2(sch_1):page213_i99:a" )
			)
			( pin "RF14.2"
				( objectStatus "@baseboard_fab2_lib.baseboard_fab2(sch_1):page213_i99:b" )
			)
			( pin "R4G23.1"
				( objectStatus "@baseboard_fab2_lib.baseboard_fab2(sch_1):page221_i4:a" )
			)
			( pin "R4G23.2"
				( objectStatus "@baseboard_fab2_lib.baseboard_fab2(sch_1):page221_i4:b" )
			)
			( pin "C4A2.1"
				( objectStatus "@baseboard_fab2_lib.baseboard_fab2(sch_1):page222_i2:a" )
			)
			( pin "C4A2.2"
				( objectStatus "@baseboard_fab2_lib.baseboard_fab2(sch_1):page222_i2:b" )
			)
			( pin "R4A2.1"
				( objectStatus "@baseboard_fab2_lib.baseboard_fab2(sch_1):page222_i4:a" )
			)
			( pin "R4A2.2"
				( objectStatus "@baseboard_fab2_lib.baseboard_fab2(sch_1):page222_i4:b" )
			)
			( pin "C4G12.1"
				( objectStatus "@baseboard_fab2_lib.baseboard_fab2(sch_1):page229_i2:a" )
			)
			( pin "C4G12.2"
				( objectStatus "@baseboard_fab2_lib.baseboard_fab2(sch_1):page229_i2:b" )
			)
			( pin "R4G16.1"
				( objectStatus "@baseboard_fab2_lib.baseboard_fab2(sch_1):page229_i4:a" )
			)
			( pin "R4G16.2"
				( objectStatus "@baseboard_fab2_lib.baseboard_fab2(sch_1):page229_i4:b" )
			)
			( pin "C12W2.1"
				( objectStatus "@baseboard_fab2_lib.baseboard_fab2(sch_1):page197_i1:a" )
			)
			( pin "C12W2.2"
				( objectStatus "@baseboard_fab2_lib.baseboard_fab2(sch_1):page197_i1:b" )
			)
			( pin "RF24.1"
				( objectStatus "@baseboard_fab2_lib.baseboard_fab2(sch_1):page235_i242:a" )
			)
			( pin "RF24.2"
				( objectStatus "@baseboard_fab2_lib.baseboard_fab2(sch_1):page235_i242:b" )
			)
			( pin "RF23.1"
				( objectStatus "@baseboard_fab2_lib.baseboard_fab2(sch_1):page235_i241:a" )
			)
			( pin "RF23.2"
				( objectStatus "@baseboard_fab2_lib.baseboard_fab2(sch_1):page235_i241:b" )
			)
			( pin "R6W12.1"
				( objectStatus "@baseboard_fab2_lib.baseboard_fab2(sch_1):page247_i99:a" )
			)
			( pin "R6W12.2"
				( objectStatus "@baseboard_fab2_lib.baseboard_fab2(sch_1):page247_i99:b" )
			)
			( pin "C14W1.1"
				( objectStatus "@baseboard_fab2_lib.baseboard_fab2(sch_1):page248_i13:a" )
			)
			( pin "C14W1.2"
				( objectStatus "@baseboard_fab2_lib.baseboard_fab2(sch_1):page248_i13:b" )
			)
			( pin "C14W2.1"
				( objectStatus "@baseboard_fab2_lib.baseboard_fab2(sch_1):page248_i17:a" )
			)
			( pin "C14W2.2"
				( objectStatus "@baseboard_fab2_lib.baseboard_fab2(sch_1):page248_i17:b" )
			)
			( pin "S9A2.1"
				( objectStatus "@baseboard_fab2_lib.baseboard_fab2(sch_1):page175_i92:pin1" )
			)
			( pin "S9A2.2"
				( objectStatus "@baseboard_fab2_lib.baseboard_fab2(sch_1):page175_i92:pin2" )
			)
			( pin "S9A2.3"
				( objectStatus "@baseboard_fab2_lib.baseboard_fab2(sch_1):page175_i92:pin3" )
			)
			( pin "S9A2.4"
				( objectStatus "@baseboard_fab2_lib.baseboard_fab2(sch_1):page175_i92:pin4" )
			)
			( pin "RF5.1"
				( objectStatus "@baseboard_fab2_lib.baseboard_fab2(sch_1):page201_i186:a" )
			)
			( pin "RF5.2"
				( objectStatus "@baseboard_fab2_lib.baseboard_fab2(sch_1):page201_i186:b" )
			)
			( pin "RF3.1"
				( objectStatus "@baseboard_fab2_lib.baseboard_fab2(sch_1):page201_i184:a" )
			)
			( pin "RF3.2"
				( objectStatus "@baseboard_fab2_lib.baseboard_fab2(sch_1):page201_i184:b" )
			)
			( pin "RF2.1"
				( objectStatus "@baseboard_fab2_lib.baseboard_fab2(sch_1):page201_i183:a" )
			)
			( pin "RF2.2"
				( objectStatus "@baseboard_fab2_lib.baseboard_fab2(sch_1):page201_i183:b" )
			)
			( pin "RF1.1"
				( objectStatus "@baseboard_fab2_lib.baseboard_fab2(sch_1):page201_i182:a" )
			)
			( pin "RF1.2"
				( objectStatus "@baseboard_fab2_lib.baseboard_fab2(sch_1):page201_i182:b" )
			)
			( pin "RF6.1"
				( objectStatus "@baseboard_fab2_lib.baseboard_fab2(sch_1):page201_i180:a" )
			)
			( pin "RF6.2"
				( objectStatus "@baseboard_fab2_lib.baseboard_fab2(sch_1):page201_i180:b" )
			)
			( pin "CF6.1"
				( objectStatus "@baseboard_fab2_lib.baseboard_fab2(sch_1):page201_i173:\1\" )
			)
			( pin "CF6.2"
				( objectStatus "@baseboard_fab2_lib.baseboard_fab2(sch_1):page201_i173:\2\" )
			)
			( pin "CF7.1"
				( objectStatus "@baseboard_fab2_lib.baseboard_fab2(sch_1):page206_i137:\1\" )
			)
			( pin "CF7.2"
				( objectStatus "@baseboard_fab2_lib.baseboard_fab2(sch_1):page206_i137:\2\" )
			)
			( pin "CF8.1"
				( objectStatus "@baseboard_fab2_lib.baseboard_fab2(sch_1):page206_i138:\1\" )
			)
			( pin "CF8.2"
				( objectStatus "@baseboard_fab2_lib.baseboard_fab2(sch_1):page206_i138:\2\" )
			)
			( pin "CF9.1"
				( objectStatus "@baseboard_fab2_lib.baseboard_fab2(sch_1):page206_i139:\1\" )
			)
			( pin "CF9.2"
				( objectStatus "@baseboard_fab2_lib.baseboard_fab2(sch_1):page206_i139:\2\" )
			)
			( pin "CF10.1"
				( objectStatus "@baseboard_fab2_lib.baseboard_fab2(sch_1):page206_i140:\1\" )
			)
			( pin "CF10.2"
				( objectStatus "@baseboard_fab2_lib.baseboard_fab2(sch_1):page206_i140:\2\" )
			)
			( pin "CF11.1"
				( objectStatus "@baseboard_fab2_lib.baseboard_fab2(sch_1):page206_i141:\1\" )
			)
			( pin "CF11.2"
				( objectStatus "@baseboard_fab2_lib.baseboard_fab2(sch_1):page206_i141:\2\" )
			)
			( pin "CF12.1"
				( objectStatus "@baseboard_fab2_lib.baseboard_fab2(sch_1):page206_i142:\1\" )
			)
			( pin "CF12.2"
				( objectStatus "@baseboard_fab2_lib.baseboard_fab2(sch_1):page206_i142:\2\" )
			)
			( pin "CF13.1"
				( objectStatus "@baseboard_fab2_lib.baseboard_fab2(sch_1):page211_i95:\1\" )
			)
			( pin "CF13.2"
				( objectStatus "@baseboard_fab2_lib.baseboard_fab2(sch_1):page211_i95:\2\" )
			)
			( pin "R6U5.1"
				( objectStatus "@baseboard_fab2_lib.baseboard_fab2(sch_1):page221_i6:a" )
			)
			( pin "R6U5.2"
				( objectStatus "@baseboard_fab2_lib.baseboard_fab2(sch_1):page221_i6:b" )
			)
			( pin "R6U15.1"
				( objectStatus "@baseboard_fab2_lib.baseboard_fab2(sch_1):page221_i5:a" )
			)
			( pin "R6U15.2"
				( objectStatus "@baseboard_fab2_lib.baseboard_fab2(sch_1):page221_i5:b" )
			)
			( pin "CF14.1"
				( objectStatus "@baseboard_fab2_lib.baseboard_fab2(sch_1):page213_i98:\1\" )
			)
			( pin "CF14.2"
				( objectStatus "@baseboard_fab2_lib.baseboard_fab2(sch_1):page213_i98:\2\" )
			)
			( pin "R6L10.1"
				( objectStatus "@baseboard_fab2_lib.baseboard_fab2(sch_1):page222_i6:a" )
			)
			( pin "R6L10.2"
				( objectStatus "@baseboard_fab2_lib.baseboard_fab2(sch_1):page222_i6:b" )
			)
			( pin "R6L4.1"
				( objectStatus "@baseboard_fab2_lib.baseboard_fab2(sch_1):page222_i5:a" )
			)
			( pin "R6L4.2"
				( objectStatus "@baseboard_fab2_lib.baseboard_fab2(sch_1):page222_i5:b" )
			)
			( pin "R6U6.1"
				( objectStatus "@baseboard_fab2_lib.baseboard_fab2(sch_1):page229_i6:a" )
			)
			( pin "R6U6.2"
				( objectStatus "@baseboard_fab2_lib.baseboard_fab2(sch_1):page229_i6:b" )
			)
			( pin "R6U3.1"
				( objectStatus "@baseboard_fab2_lib.baseboard_fab2(sch_1):page229_i5:a" )
			)
			( pin "R6U3.2"
				( objectStatus "@baseboard_fab2_lib.baseboard_fab2(sch_1):page229_i5:b" )
			)
			( pin "R12W13.1"
				( objectStatus "@baseboard_fab2_lib.baseboard_fab2(sch_1):page197_i116:\1\" )
			)
			( pin "R12W13.2"
				( objectStatus "@baseboard_fab2_lib.baseboard_fab2(sch_1):page197_i116:\2\" )
			)
			( pin "CF23.1"
				( objectStatus "@baseboard_fab2_lib.baseboard_fab2(sch_1):page235_i239:\1\" )
			)
			( pin "CF23.2"
				( objectStatus "@baseboard_fab2_lib.baseboard_fab2(sch_1):page235_i239:\2\" )
			)
			( pin "CF24.1"
				( objectStatus "@baseboard_fab2_lib.baseboard_fab2(sch_1):page235_i240:\1\" )
			)
			( pin "CF24.2"
				( objectStatus "@baseboard_fab2_lib.baseboard_fab2(sch_1):page235_i240:\2\" )
			)
			( pin "R25W27.1"
				( objectStatus "@baseboard_fab2_lib.baseboard_fab2(sch_1):page151_i223:\1\" )
			)
			( pin "R25W27.2"
				( objectStatus "@baseboard_fab2_lib.baseboard_fab2(sch_1):page151_i223:\2\" )
			)
			( pin "R25W70.1"
				( objectStatus "@baseboard_fab2_lib.baseboard_fab2(sch_1):page144_i114:a" )
			)
			( pin "R25W70.2"
				( objectStatus "@baseboard_fab2_lib.baseboard_fab2(sch_1):page144_i114:b" )
			)
			( pin "R25W75.1"
				( objectStatus "@baseboard_fab2_lib.baseboard_fab2(sch_1):page144_i118:a" )
			)
			( pin "R25W75.2"
				( objectStatus "@baseboard_fab2_lib.baseboard_fab2(sch_1):page144_i118:b" )
			)
			( pin "C2A16.1"
				( objectStatus "@baseboard_fab2_lib.baseboard_fab2(sch_1):page228_i313:a" )
			)
			( pin "C2A16.2"
				( objectStatus "@baseboard_fab2_lib.baseboard_fab2(sch_1):page228_i313:b" )
			)
			( pin "C8P1.1"
				( objectStatus "@baseboard_fab2_lib.baseboard_fab2(sch_1):page228_i304:a" )
			)
			( pin "C8P1.2"
				( objectStatus "@baseboard_fab2_lib.baseboard_fab2(sch_1):page228_i304:b" )
			)
			( pin "C25W69.1"
				( objectStatus "@baseboard_fab2_lib.baseboard_fab2(sch_1):page149_i17:a" )
			)
			( pin "C25W69.2"
				( objectStatus "@baseboard_fab2_lib.baseboard_fab2(sch_1):page149_i17:b" )
			)
			( pin "C6W1.1"
				( objectStatus "@baseboard_fab2_lib.baseboard_fab2(sch_1):page247_i151:a" )
			)
			( pin "C6W1.2"
				( objectStatus "@baseboard_fab2_lib.baseboard_fab2(sch_1):page247_i151:b" )
			)
			( pin "FB2T1.1"
				( objectStatus "@baseboard_fab2_lib.baseboard_fab2(sch_1):page149_i22:\1\" )
			)
			( pin "FB2T1.2"
				( objectStatus "@baseboard_fab2_lib.baseboard_fab2(sch_1):page149_i22:\2\" )
			)
			( pin "C25W39.1"
				( objectStatus "@baseboard_fab2_lib.baseboard_fab2(sch_1):page149_i25:a" )
			)
			( pin "C25W39.2"
				( objectStatus "@baseboard_fab2_lib.baseboard_fab2(sch_1):page149_i25:b" )
			)
			( pin "C25W50.1"
				( objectStatus "@baseboard_fab2_lib.baseboard_fab2(sch_1):page149_i31:a" )
			)
			( pin "C25W50.2"
				( objectStatus "@baseboard_fab2_lib.baseboard_fab2(sch_1):page149_i31:b" )
			)
			( pin "C25W62.1"
				( objectStatus "@baseboard_fab2_lib.baseboard_fab2(sch_1):page149_i40:a" )
			)
			( pin "C25W62.2"
				( objectStatus "@baseboard_fab2_lib.baseboard_fab2(sch_1):page149_i40:b" )
			)
			( pin "FB2T7.1"
				( objectStatus "@baseboard_fab2_lib.baseboard_fab2(sch_1):page149_i42:\1\" )
			)
			( pin "FB2T7.2"
				( objectStatus "@baseboard_fab2_lib.baseboard_fab2(sch_1):page149_i42:\2\" )
			)
			( pin "C25W36.1"
				( objectStatus "@baseboard_fab2_lib.baseboard_fab2(sch_1):page149_i46:a" )
			)
			( pin "C25W36.2"
				( objectStatus "@baseboard_fab2_lib.baseboard_fab2(sch_1):page149_i46:b" )
			)
			( pin "C25W61.1"
				( objectStatus "@baseboard_fab2_lib.baseboard_fab2(sch_1):page149_i126:a" )
			)
			( pin "C25W61.2"
				( objectStatus "@baseboard_fab2_lib.baseboard_fab2(sch_1):page149_i126:b" )
			)
			( pin "C25W47.1"
				( objectStatus "@baseboard_fab2_lib.baseboard_fab2(sch_1):page149_i50:a" )
			)
			( pin "C25W47.2"
				( objectStatus "@baseboard_fab2_lib.baseboard_fab2(sch_1):page149_i50:b" )
			)
			( pin "C25W46.1"
				( objectStatus "@baseboard_fab2_lib.baseboard_fab2(sch_1):page149_i51:a" )
			)
			( pin "C25W46.2"
				( objectStatus "@baseboard_fab2_lib.baseboard_fab2(sch_1):page149_i51:b" )
			)
			( pin "C25W68.1"
				( objectStatus "@baseboard_fab2_lib.baseboard_fab2(sch_1):page149_i128:a" )
			)
			( pin "C25W68.2"
				( objectStatus "@baseboard_fab2_lib.baseboard_fab2(sch_1):page149_i128:b" )
			)
			( pin "R25W183.1"
				( objectStatus "@baseboard_fab2_lib.baseboard_fab2(sch_1):page268_i36:\1\" )
			)
			( pin "R25W183.2"
				( objectStatus "@baseboard_fab2_lib.baseboard_fab2(sch_1):page268_i36:\2\" )
			)
			( pin "C25W58.1"
				( objectStatus "@baseboard_fab2_lib.baseboard_fab2(sch_1):page149_i125:a" )
			)
			( pin "C25W58.2"
				( objectStatus "@baseboard_fab2_lib.baseboard_fab2(sch_1):page149_i125:b" )
			)
			( pin "C25W59.1"
				( objectStatus "@baseboard_fab2_lib.baseboard_fab2(sch_1):page149_i79:a" )
			)
			( pin "C25W59.2"
				( objectStatus "@baseboard_fab2_lib.baseboard_fab2(sch_1):page149_i79:b" )
			)
			( pin "C25W22.1"
				( objectStatus "@baseboard_fab2_lib.baseboard_fab2(sch_1):page143_i67:a" )
			)
			( pin "C25W22.2"
				( objectStatus "@baseboard_fab2_lib.baseboard_fab2(sch_1):page143_i67:b" )
			)
			( pin "Q1W2.3"
				( objectStatus "@baseboard_fab2_lib.baseboard_fab2(sch_1):page250_i12:drain(0)" )
			)
			( pin "Q1W2.5"
				( objectStatus "@baseboard_fab2_lib.baseboard_fab2(sch_1):page250_i12:gate(0)" )
			)
			( pin "Q1W2.4"
				( objectStatus "@baseboard_fab2_lib.baseboard_fab2(sch_1):page250_i12:source(0)" )
			)
			( pin "FB2T3.1"
				( objectStatus "@baseboard_fab2_lib.baseboard_fab2(sch_1):page149_i85:\1\" )
			)
			( pin "FB2T3.2"
				( objectStatus "@baseboard_fab2_lib.baseboard_fab2(sch_1):page149_i85:\2\" )
			)
			( pin "FB2T4.1"
				( objectStatus "@baseboard_fab2_lib.baseboard_fab2(sch_1):page149_i86:\1\" )
			)
			( pin "FB2T4.2"
				( objectStatus "@baseboard_fab2_lib.baseboard_fab2(sch_1):page149_i86:\2\" )
			)
			( pin "FB2T5.1"
				( objectStatus "@baseboard_fab2_lib.baseboard_fab2(sch_1):page149_i88:\1\" )
			)
			( pin "FB2T5.2"
				( objectStatus "@baseboard_fab2_lib.baseboard_fab2(sch_1):page149_i88:\2\" )
			)
			( pin "RT4.1"
				( objectStatus "@baseboard_fab2_lib.baseboard_fab2(sch_1):page202_i115:\1\" )
			)
			( pin "RT4.2"
				( objectStatus "@baseboard_fab2_lib.baseboard_fab2(sch_1):page202_i115:\2\" )
			)
			( pin "R9P13.1"
				( objectStatus "@baseboard_fab2_lib.baseboard_fab2(sch_1):page200_i249:\1\" )
			)
			( pin "R9P13.2"
				( objectStatus "@baseboard_fab2_lib.baseboard_fab2(sch_1):page200_i249:\2\" )
			)
			( pin "Q9E1.6"
				( objectStatus "@baseboard_fab2_lib.baseboard_fab2(sch_1):page151_i198:drain(0)" )
			)
			( pin "Q9E1.2"
				( objectStatus "@baseboard_fab2_lib.baseboard_fab2(sch_1):page151_i198:gate(0)" )
			)
			( pin "Q9E1.1"
				( objectStatus "@baseboard_fab2_lib.baseboard_fab2(sch_1):page151_i198:source(0)" )
			)
			( pin "R1T30.1"
				( objectStatus "@baseboard_fab2_lib.baseboard_fab2(sch_1):page151_i201:a" )
			)
			( pin "R1T30.2"
				( objectStatus "@baseboard_fab2_lib.baseboard_fab2(sch_1):page151_i201:b" )
			)
			( pin "R1T29.1"
				( objectStatus "@baseboard_fab2_lib.baseboard_fab2(sch_1):page151_i202:a" )
			)
			( pin "R1T29.2"
				( objectStatus "@baseboard_fab2_lib.baseboard_fab2(sch_1):page151_i202:b" )
			)
			( pin "CN8F2.1"
				( objectStatus "@baseboard_fab2_lib.baseboard_fab2(sch_1):page246_i22:a" )
			)
			( pin "CN8F2.2"
				( objectStatus "@baseboard_fab2_lib.baseboard_fab2(sch_1):page246_i22:b" )
			)
			( pin "C25W15.1"
				( objectStatus "@baseboard_fab2_lib.baseboard_fab2(sch_1):page151_i216:a" )
			)
			( pin "C25W15.2"
				( objectStatus "@baseboard_fab2_lib.baseboard_fab2(sch_1):page151_i216:b" )
			)
			( pin "C25W14.1"
				( objectStatus "@baseboard_fab2_lib.baseboard_fab2(sch_1):page151_i215:a" )
			)
			( pin "C25W14.2"
				( objectStatus "@baseboard_fab2_lib.baseboard_fab2(sch_1):page151_i215:b" )
			)
			( pin "U14E3.1"
				( objectStatus "@baseboard_fab2_lib.baseboard_fab2(sch_1):page248_i19:a(0)" )
			)
			( pin "U14E3.2"
				( objectStatus "@baseboard_fab2_lib.baseboard_fab2(sch_1):page248_i19:b(0)" )
			)
			( pin "U14E3.4"
				( objectStatus "@baseboard_fab2_lib.baseboard_fab2(sch_1):page248_i19:y(0)" )
			)
			( pin "RT16.1"
				( objectStatus "@baseboard_fab2_lib.baseboard_fab2(sch_1):page207_i111:\1\" )
			)
			( pin "RT16.2"
				( objectStatus "@baseboard_fab2_lib.baseboard_fab2(sch_1):page207_i111:\2\" )
			)
			( pin "R6W26.1"
				( objectStatus "@baseboard_fab2_lib.baseboard_fab2(sch_1):page248_i24:a" )
			)
			( pin "R6W26.2"
				( objectStatus "@baseboard_fab2_lib.baseboard_fab2(sch_1):page248_i24:b" )
			)
			( pin "R6W27.1"
				( objectStatus "@baseboard_fab2_lib.baseboard_fab2(sch_1):page248_i25:a" )
			)
			( pin "R6W27.2"
				( objectStatus "@baseboard_fab2_lib.baseboard_fab2(sch_1):page248_i25:b" )
			)
			( pin "R9W19.1"
				( objectStatus "@baseboard_fab2_lib.baseboard_fab2(sch_1):page248_i26:a" )
			)
			( pin "R9W19.2"
				( objectStatus "@baseboard_fab2_lib.baseboard_fab2(sch_1):page248_i26:b" )
			)
			( pin "R9W18.1"
				( objectStatus "@baseboard_fab2_lib.baseboard_fab2(sch_1):page248_i27:a" )
			)
			( pin "R9W18.2"
				( objectStatus "@baseboard_fab2_lib.baseboard_fab2(sch_1):page248_i27:b" )
			)
			( pin "C9W8.1"
				( objectStatus "@baseboard_fab2_lib.baseboard_fab2(sch_1):page248_i30:a" )
			)
			( pin "C9W8.2"
				( objectStatus "@baseboard_fab2_lib.baseboard_fab2(sch_1):page248_i30:b" )
			)
			( pin "C9W7.1"
				( objectStatus "@baseboard_fab2_lib.baseboard_fab2(sch_1):page248_i32:a" )
			)
			( pin "C9W7.2"
				( objectStatus "@baseboard_fab2_lib.baseboard_fab2(sch_1):page248_i32:b" )
			)
			( pin "R9W16.1"
				( objectStatus "@baseboard_fab2_lib.baseboard_fab2(sch_1):page248_i34:a" )
			)
			( pin "R9W16.2"
				( objectStatus "@baseboard_fab2_lib.baseboard_fab2(sch_1):page248_i34:b" )
			)
			( pin "R9W17.1"
				( objectStatus "@baseboard_fab2_lib.baseboard_fab2(sch_1):page248_i35:a" )
			)
			( pin "R9W17.2"
				( objectStatus "@baseboard_fab2_lib.baseboard_fab2(sch_1):page248_i35:b" )
			)
			( pin "R9W14.1"
				( objectStatus "@baseboard_fab2_lib.baseboard_fab2(sch_1):page248_i37:a" )
			)
			( pin "R9W14.2"
				( objectStatus "@baseboard_fab2_lib.baseboard_fab2(sch_1):page248_i37:b" )
			)
			( pin "R9W13.1"
				( objectStatus "@baseboard_fab2_lib.baseboard_fab2(sch_1):page248_i38:a" )
			)
			( pin "R9W13.2"
				( objectStatus "@baseboard_fab2_lib.baseboard_fab2(sch_1):page248_i38:b" )
			)
			( pin "R8W1.1"
				( objectStatus "@baseboard_fab2_lib.baseboard_fab2(sch_1):page249_i34:a" )
			)
			( pin "R8W1.2"
				( objectStatus "@baseboard_fab2_lib.baseboard_fab2(sch_1):page249_i34:b" )
			)
			( pin "RT35.1"
				( objectStatus "@baseboard_fab2_lib.baseboard_fab2(sch_1):page216_i152:\1\" )
			)
			( pin "RT35.2"
				( objectStatus "@baseboard_fab2_lib.baseboard_fab2(sch_1):page216_i152:\2\" )
			)
			( pin "R1W3.1"
				( objectStatus "@baseboard_fab2_lib.baseboard_fab2(sch_1):page250_i27:\1\" )
			)
			( pin "R1W3.2"
				( objectStatus "@baseboard_fab2_lib.baseboard_fab2(sch_1):page250_i27:\2\" )
			)
			( pin "Q1W2.6"
				( objectStatus "@baseboard_fab2_lib.baseboard_fab2(sch_1):page250_i24:drain(0)" )
			)
			( pin "Q1W2.2"
				( objectStatus "@baseboard_fab2_lib.baseboard_fab2(sch_1):page250_i24:gate(0)" )
			)
			( pin "Q1W2.1"
				( objectStatus "@baseboard_fab2_lib.baseboard_fab2(sch_1):page250_i24:source(0)" )
			)
			( pin "R1W4.1"
				( objectStatus "@baseboard_fab2_lib.baseboard_fab2(sch_1):page250_i22:a" )
			)
			( pin "R1W4.2"
				( objectStatus "@baseboard_fab2_lib.baseboard_fab2(sch_1):page250_i22:b" )
			)
			( pin "Q1W5.3"
				( objectStatus "@baseboard_fab2_lib.baseboard_fab2(sch_1):page199_i130:drn" )
			)
			( pin "Q1W5.1"
				( objectStatus "@baseboard_fab2_lib.baseboard_fab2(sch_1):page199_i130:gate" )
			)
			( pin "Q1W5.2"
				( objectStatus "@baseboard_fab2_lib.baseboard_fab2(sch_1):page199_i130:src" )
			)
			( pin "R1W1.1"
				( objectStatus "@baseboard_fab2_lib.baseboard_fab2(sch_1):page250_i18:\1\" )
			)
			( pin "R1W1.2"
				( objectStatus "@baseboard_fab2_lib.baseboard_fab2(sch_1):page250_i18:\2\" )
			)
			( pin "R1U23.1"
				( objectStatus "@baseboard_fab2_lib.baseboard_fab2(sch_1):page164_i34:a" )
			)
			( pin "R1U23.2"
				( objectStatus "@baseboard_fab2_lib.baseboard_fab2(sch_1):page164_i34:b" )
			)
			( pin "R1U16.1"
				( objectStatus "@baseboard_fab2_lib.baseboard_fab2(sch_1):page164_i37:a" )
			)
			( pin "R1U16.2"
				( objectStatus "@baseboard_fab2_lib.baseboard_fab2(sch_1):page164_i37:b" )
			)
			( pin "R6W28.1"
				( objectStatus "@baseboard_fab2_lib.baseboard_fab2(sch_1):page247_i112:a" )
			)
			( pin "R6W28.2"
				( objectStatus "@baseboard_fab2_lib.baseboard_fab2(sch_1):page247_i112:b" )
			)
			( pin "R25W120.1"
				( objectStatus "@baseboard_fab2_lib.baseboard_fab2(sch_1):page149_i91:a" )
			)
			( pin "R25W120.2"
				( objectStatus "@baseboard_fab2_lib.baseboard_fab2(sch_1):page149_i91:b" )
			)
			( pin "R2U28.1"
				( objectStatus "@baseboard_fab2_lib.baseboard_fab2(sch_1):page107_i500:a" )
			)
			( pin "R2U28.2"
				( objectStatus "@baseboard_fab2_lib.baseboard_fab2(sch_1):page107_i500:b" )
			)
			( pin "R2U14.1"
				( objectStatus "@baseboard_fab2_lib.baseboard_fab2(sch_1):page107_i499:a" )
			)
			( pin "R2U14.2"
				( objectStatus "@baseboard_fab2_lib.baseboard_fab2(sch_1):page107_i499:b" )
			)
			( pin "R2U26.1"
				( objectStatus "@baseboard_fab2_lib.baseboard_fab2(sch_1):page107_i498:a" )
			)
			( pin "R2U26.2"
				( objectStatus "@baseboard_fab2_lib.baseboard_fab2(sch_1):page107_i498:b" )
			)
			( pin "C3P12.1"
				( objectStatus "@baseboard_fab2_lib.baseboard_fab2(sch_1):page107_i481:a" )
			)
			( pin "C3P12.2"
				( objectStatus "@baseboard_fab2_lib.baseboard_fab2(sch_1):page107_i481:b" )
			)
			( pin "C3P21.1"
				( objectStatus "@baseboard_fab2_lib.baseboard_fab2(sch_1):page107_i480:a" )
			)
			( pin "C3P21.2"
				( objectStatus "@baseboard_fab2_lib.baseboard_fab2(sch_1):page107_i480:b" )
			)
			( pin "C3P24.1"
				( objectStatus "@baseboard_fab2_lib.baseboard_fab2(sch_1):page107_i479:a" )
			)
			( pin "C3P24.2"
				( objectStatus "@baseboard_fab2_lib.baseboard_fab2(sch_1):page107_i479:b" )
			)
			( pin "C3P29.1"
				( objectStatus "@baseboard_fab2_lib.baseboard_fab2(sch_1):page107_i478:a" )
			)
			( pin "C3P29.2"
				( objectStatus "@baseboard_fab2_lib.baseboard_fab2(sch_1):page107_i478:b" )
			)
			( pin "C8F15.1"
				( objectStatus "@baseboard_fab2_lib.baseboard_fab2(sch_1):page185_i142:a" )
			)
			( pin "C8F15.2"
				( objectStatus "@baseboard_fab2_lib.baseboard_fab2(sch_1):page185_i142:b" )
			)
			( pin "C8F13.1"
				( objectStatus "@baseboard_fab2_lib.baseboard_fab2(sch_1):page185_i141:a" )
			)
			( pin "C8F13.2"
				( objectStatus "@baseboard_fab2_lib.baseboard_fab2(sch_1):page185_i141:b" )
			)
			( pin "C8F12.1"
				( objectStatus "@baseboard_fab2_lib.baseboard_fab2(sch_1):page185_i140:a" )
			)
			( pin "C8F12.2"
				( objectStatus "@baseboard_fab2_lib.baseboard_fab2(sch_1):page185_i140:b" )
			)
			( pin "C8F6.1"
				( objectStatus "@baseboard_fab2_lib.baseboard_fab2(sch_1):page185_i138:a" )
			)
			( pin "C8F6.2"
				( objectStatus "@baseboard_fab2_lib.baseboard_fab2(sch_1):page185_i138:b" )
			)
			( pin "Q1W4.3"
				( objectStatus "@baseboard_fab2_lib.baseboard_fab2(sch_1):page250_i8:drain(0)" )
			)
			( pin "Q1W4.5"
				( objectStatus "@baseboard_fab2_lib.baseboard_fab2(sch_1):page250_i8:gate(0)" )
			)
			( pin "Q1W4.4"
				( objectStatus "@baseboard_fab2_lib.baseboard_fab2(sch_1):page250_i8:source(0)" )
			)
			( pin "R1W7.1"
				( objectStatus "@baseboard_fab2_lib.baseboard_fab2(sch_1):page250_i6:a" )
			)
			( pin "R1W7.2"
				( objectStatus "@baseboard_fab2_lib.baseboard_fab2(sch_1):page250_i6:b" )
			)
			( pin "Q1W4.6"
				( objectStatus "@baseboard_fab2_lib.baseboard_fab2(sch_1):page250_i3:drain(0)" )
			)
			( pin "Q1W4.2"
				( objectStatus "@baseboard_fab2_lib.baseboard_fab2(sch_1):page250_i3:gate(0)" )
			)
			( pin "Q1W4.1"
				( objectStatus "@baseboard_fab2_lib.baseboard_fab2(sch_1):page250_i3:source(0)" )
			)
			( pin "R1W6.1"
				( objectStatus "@baseboard_fab2_lib.baseboard_fab2(sch_1):page250_i2:\1\" )
			)
			( pin "R1W6.2"
				( objectStatus "@baseboard_fab2_lib.baseboard_fab2(sch_1):page250_i2:\2\" )
			)
			( pin "R2U16.1"
				( objectStatus "@baseboard_fab2_lib.baseboard_fab2(sch_1):page107_i501:a" )
			)
			( pin "R2U16.2"
				( objectStatus "@baseboard_fab2_lib.baseboard_fab2(sch_1):page107_i501:b" )
			)
			( pin "R2U18.1"
				( objectStatus "@baseboard_fab2_lib.baseboard_fab2(sch_1):page107_i502:a" )
			)
			( pin "R2U18.2"
				( objectStatus "@baseboard_fab2_lib.baseboard_fab2(sch_1):page107_i502:b" )
			)
			( pin "R2U20.1"
				( objectStatus "@baseboard_fab2_lib.baseboard_fab2(sch_1):page107_i503:a" )
			)
			( pin "R2U20.2"
				( objectStatus "@baseboard_fab2_lib.baseboard_fab2(sch_1):page107_i503:b" )
			)
			( pin "R2U22.1"
				( objectStatus "@baseboard_fab2_lib.baseboard_fab2(sch_1):page107_i504:a" )
			)
			( pin "R2U22.2"
				( objectStatus "@baseboard_fab2_lib.baseboard_fab2(sch_1):page107_i504:b" )
			)
			( pin "R2U24.1"
				( objectStatus "@baseboard_fab2_lib.baseboard_fab2(sch_1):page107_i505:a" )
			)
			( pin "R2U24.2"
				( objectStatus "@baseboard_fab2_lib.baseboard_fab2(sch_1):page107_i505:b" )
			)
			( pin "R1U33.1"
				( objectStatus "@baseboard_fab2_lib.baseboard_fab2(sch_1):page169_i171:\1\" )
			)
			( pin "R1U33.2"
				( objectStatus "@baseboard_fab2_lib.baseboard_fab2(sch_1):page169_i171:\2\" )
			)
			( pin "R1U38.1"
				( objectStatus "@baseboard_fab2_lib.baseboard_fab2(sch_1):page169_i172:a" )
			)
			( pin "R1U38.2"
				( objectStatus "@baseboard_fab2_lib.baseboard_fab2(sch_1):page169_i172:b" )
			)
			( pin "R1U27.1"
				( objectStatus "@baseboard_fab2_lib.baseboard_fab2(sch_1):page169_i173:a" )
			)
			( pin "R1U27.2"
				( objectStatus "@baseboard_fab2_lib.baseboard_fab2(sch_1):page169_i173:b" )
			)
			( pin "R9B7.1"
				( objectStatus "@baseboard_fab2_lib.baseboard_fab2(sch_1):page186_i358:\1\" )
			)
			( pin "R9B7.2"
				( objectStatus "@baseboard_fab2_lib.baseboard_fab2(sch_1):page186_i358:\2\" )
			)
			( pin "R2R8.1"
				( objectStatus "@baseboard_fab2_lib.baseboard_fab2(sch_1):page187_i175:\1\" )
			)
			( pin "R2R8.2"
				( objectStatus "@baseboard_fab2_lib.baseboard_fab2(sch_1):page187_i175:\2\" )
			)
			( pin "CT20.1"
				( objectStatus "@baseboard_fab2_lib.baseboard_fab2(sch_1):page208_i105:a" )
			)
			( pin "CT20.2"
				( objectStatus "@baseboard_fab2_lib.baseboard_fab2(sch_1):page208_i105:b" )
			)
			( pin "C5G115.1"
				( objectStatus "@baseboard_fab2_lib.baseboard_fab2(sch_1):page243_i89:a" )
			)
			( pin "C5G115.2"
				( objectStatus "@baseboard_fab2_lib.baseboard_fab2(sch_1):page243_i89:b" )
			)
			( pin "RT28.1"
				( objectStatus "@baseboard_fab2_lib.baseboard_fab2(sch_1):page203_i123:a" )
			)
			( pin "RT28.2"
				( objectStatus "@baseboard_fab2_lib.baseboard_fab2(sch_1):page203_i123:b" )
			)
			( pin "RT25.1"
				( objectStatus "@baseboard_fab2_lib.baseboard_fab2(sch_1):page203_i122:a" )
			)
			( pin "RT25.2"
				( objectStatus "@baseboard_fab2_lib.baseboard_fab2(sch_1):page203_i122:b" )
			)
			( pin "CT5.1"
				( objectStatus "@baseboard_fab2_lib.baseboard_fab2(sch_1):page202_i98:a" )
			)
			( pin "CT5.2"
				( objectStatus "@baseboard_fab2_lib.baseboard_fab2(sch_1):page202_i98:b" )
			)
			( pin "CT3.1"
				( objectStatus "@baseboard_fab2_lib.baseboard_fab2(sch_1):page202_i97:a" )
			)
			( pin "CT3.2"
				( objectStatus "@baseboard_fab2_lib.baseboard_fab2(sch_1):page202_i97:b" )
			)
			( pin "R9W1.1"
				( objectStatus "@baseboard_fab2_lib.baseboard_fab2(sch_1):page186_i356:a" )
			)
			( pin "R9W1.2"
				( objectStatus "@baseboard_fab2_lib.baseboard_fab2(sch_1):page186_i356:b" )
			)
			( pin "R2W1.1"
				( objectStatus "@baseboard_fab2_lib.baseboard_fab2(sch_1):page187_i174:a" )
			)
			( pin "R2W1.2"
				( objectStatus "@baseboard_fab2_lib.baseboard_fab2(sch_1):page187_i174:b" )
			)
			( pin "RT13.1"
				( objectStatus "@baseboard_fab2_lib.baseboard_fab2(sch_1):page208_i121:\1\" )
			)
			( pin "RT13.2"
				( objectStatus "@baseboard_fab2_lib.baseboard_fab2(sch_1):page208_i121:\2\" )
			)
			( pin "RT1.1"
				( objectStatus "@baseboard_fab2_lib.baseboard_fab2(sch_1):page202_i101:a" )
			)
			( pin "RT1.2"
				( objectStatus "@baseboard_fab2_lib.baseboard_fab2(sch_1):page202_i101:b" )
			)
			( pin "RT3.1"
				( objectStatus "@baseboard_fab2_lib.baseboard_fab2(sch_1):page202_i102:a" )
			)
			( pin "RT3.2"
				( objectStatus "@baseboard_fab2_lib.baseboard_fab2(sch_1):page202_i102:b" )
			)
			( pin "RT6.1"
				( objectStatus "@baseboard_fab2_lib.baseboard_fab2(sch_1):page227_i149:\1\" )
			)
			( pin "RT6.2"
				( objectStatus "@baseboard_fab2_lib.baseboard_fab2(sch_1):page227_i149:\2\" )
			)
			( pin "C25W53.1"
				( objectStatus "@baseboard_fab2_lib.baseboard_fab2(sch_1):page149_i92:a" )
			)
			( pin "C25W53.2"
				( objectStatus "@baseboard_fab2_lib.baseboard_fab2(sch_1):page149_i92:b" )
			)
			( pin "C25W56.1"
				( objectStatus "@baseboard_fab2_lib.baseboard_fab2(sch_1):page149_i93:a" )
			)
			( pin "C25W56.2"
				( objectStatus "@baseboard_fab2_lib.baseboard_fab2(sch_1):page149_i93:b" )
			)
			( pin "C25W54.1"
				( objectStatus "@baseboard_fab2_lib.baseboard_fab2(sch_1):page149_i95:a" )
			)
			( pin "C25W54.2"
				( objectStatus "@baseboard_fab2_lib.baseboard_fab2(sch_1):page149_i95:b" )
			)
			( pin "C25W40.1"
				( objectStatus "@baseboard_fab2_lib.baseboard_fab2(sch_1):page149_i96:a" )
			)
			( pin "C25W40.2"
				( objectStatus "@baseboard_fab2_lib.baseboard_fab2(sch_1):page149_i96:b" )
			)
			( pin "C25W41.1"
				( objectStatus "@baseboard_fab2_lib.baseboard_fab2(sch_1):page149_i97:a" )
			)
			( pin "C25W41.2"
				( objectStatus "@baseboard_fab2_lib.baseboard_fab2(sch_1):page149_i97:b" )
			)
			( pin "C25W42.1"
				( objectStatus "@baseboard_fab2_lib.baseboard_fab2(sch_1):page149_i98:a" )
			)
			( pin "C25W42.2"
				( objectStatus "@baseboard_fab2_lib.baseboard_fab2(sch_1):page149_i98:b" )
			)
			( pin "C25W32.1"
				( objectStatus "@baseboard_fab2_lib.baseboard_fab2(sch_1):page149_i99:a" )
			)
			( pin "C25W32.2"
				( objectStatus "@baseboard_fab2_lib.baseboard_fab2(sch_1):page149_i99:b" )
			)
			( pin "C25W43.1"
				( objectStatus "@baseboard_fab2_lib.baseboard_fab2(sch_1):page149_i100:a" )
			)
			( pin "C25W43.2"
				( objectStatus "@baseboard_fab2_lib.baseboard_fab2(sch_1):page149_i100:b" )
			)
			( pin "C25W44.1"
				( objectStatus "@baseboard_fab2_lib.baseboard_fab2(sch_1):page149_i101:a" )
			)
			( pin "C25W44.2"
				( objectStatus "@baseboard_fab2_lib.baseboard_fab2(sch_1):page149_i101:b" )
			)
			( pin "C25W33.1"
				( objectStatus "@baseboard_fab2_lib.baseboard_fab2(sch_1):page149_i102:a" )
			)
			( pin "C25W33.2"
				( objectStatus "@baseboard_fab2_lib.baseboard_fab2(sch_1):page149_i102:b" )
			)
			( pin "C25W23.1"
				( objectStatus "@baseboard_fab2_lib.baseboard_fab2(sch_1):page149_i103:a" )
			)
			( pin "C25W23.2"
				( objectStatus "@baseboard_fab2_lib.baseboard_fab2(sch_1):page149_i103:b" )
			)
			( pin "C25W24.1"
				( objectStatus "@baseboard_fab2_lib.baseboard_fab2(sch_1):page149_i104:a" )
			)
			( pin "C25W24.2"
				( objectStatus "@baseboard_fab2_lib.baseboard_fab2(sch_1):page149_i104:b" )
			)
			( pin "C25W25.1"
				( objectStatus "@baseboard_fab2_lib.baseboard_fab2(sch_1):page149_i105:a" )
			)
			( pin "C25W25.2"
				( objectStatus "@baseboard_fab2_lib.baseboard_fab2(sch_1):page149_i105:b" )
			)
			( pin "C25W26.1"
				( objectStatus "@baseboard_fab2_lib.baseboard_fab2(sch_1):page149_i106:a" )
			)
			( pin "C25W26.2"
				( objectStatus "@baseboard_fab2_lib.baseboard_fab2(sch_1):page149_i106:b" )
			)
			( pin "C25W27.1"
				( objectStatus "@baseboard_fab2_lib.baseboard_fab2(sch_1):page149_i107:a" )
			)
			( pin "C25W27.2"
				( objectStatus "@baseboard_fab2_lib.baseboard_fab2(sch_1):page149_i107:b" )
			)
			( pin "C25W28.1"
				( objectStatus "@baseboard_fab2_lib.baseboard_fab2(sch_1):page149_i108:a" )
			)
			( pin "C25W28.2"
				( objectStatus "@baseboard_fab2_lib.baseboard_fab2(sch_1):page149_i108:b" )
			)
			( pin "C25W60.1"
				( objectStatus "@baseboard_fab2_lib.baseboard_fab2(sch_1):page149_i109:a" )
			)
			( pin "C25W60.2"
				( objectStatus "@baseboard_fab2_lib.baseboard_fab2(sch_1):page149_i109:b" )
			)
			( pin "C25W35.1"
				( objectStatus "@baseboard_fab2_lib.baseboard_fab2(sch_1):page149_i110:a" )
			)
			( pin "C25W35.2"
				( objectStatus "@baseboard_fab2_lib.baseboard_fab2(sch_1):page149_i110:b" )
			)
			( pin "C25W48.1"
				( objectStatus "@baseboard_fab2_lib.baseboard_fab2(sch_1):page149_i112:a" )
			)
			( pin "C25W48.2"
				( objectStatus "@baseboard_fab2_lib.baseboard_fab2(sch_1):page149_i112:b" )
			)
			( pin "C25W37.1"
				( objectStatus "@baseboard_fab2_lib.baseboard_fab2(sch_1):page149_i113:a" )
			)
			( pin "C25W37.2"
				( objectStatus "@baseboard_fab2_lib.baseboard_fab2(sch_1):page149_i113:b" )
			)
			( pin "C25W51.1"
				( objectStatus "@baseboard_fab2_lib.baseboard_fab2(sch_1):page149_i114:a" )
			)
			( pin "C25W51.2"
				( objectStatus "@baseboard_fab2_lib.baseboard_fab2(sch_1):page149_i114:b" )
			)
			( pin "C25W71.1"
				( objectStatus "@baseboard_fab2_lib.baseboard_fab2(sch_1):page149_i115:a" )
			)
			( pin "C25W71.2"
				( objectStatus "@baseboard_fab2_lib.baseboard_fab2(sch_1):page149_i115:b" )
			)
			( pin "C25W66.1"
				( objectStatus "@baseboard_fab2_lib.baseboard_fab2(sch_1):page149_i116:a" )
			)
			( pin "C25W66.2"
				( objectStatus "@baseboard_fab2_lib.baseboard_fab2(sch_1):page149_i116:b" )
			)
			( pin "C25W67.1"
				( objectStatus "@baseboard_fab2_lib.baseboard_fab2(sch_1):page149_i117:a" )
			)
			( pin "C25W67.2"
				( objectStatus "@baseboard_fab2_lib.baseboard_fab2(sch_1):page149_i117:b" )
			)
			( pin "C25W52.1"
				( objectStatus "@baseboard_fab2_lib.baseboard_fab2(sch_1):page149_i118:a" )
			)
			( pin "C25W52.2"
				( objectStatus "@baseboard_fab2_lib.baseboard_fab2(sch_1):page149_i118:b" )
			)
			( pin "R1W10.1"
				( objectStatus "@baseboard_fab2_lib.baseboard_fab2(sch_1):page176_i132:a" )
			)
			( pin "R1W10.2"
				( objectStatus "@baseboard_fab2_lib.baseboard_fab2(sch_1):page176_i132:b" )
			)
			( pin "R1W11.1"
				( objectStatus "@baseboard_fab2_lib.baseboard_fab2(sch_1):page176_i133:a" )
			)
			( pin "R1W11.2"
				( objectStatus "@baseboard_fab2_lib.baseboard_fab2(sch_1):page176_i133:b" )
			)
			( pin "R1W12.1"
				( objectStatus "@baseboard_fab2_lib.baseboard_fab2(sch_1):page176_i137:a" )
			)
			( pin "R1W12.2"
				( objectStatus "@baseboard_fab2_lib.baseboard_fab2(sch_1):page176_i137:b" )
			)
			( pin "R1W13.1"
				( objectStatus "@baseboard_fab2_lib.baseboard_fab2(sch_1):page176_i138:a" )
			)
			( pin "R1W13.2"
				( objectStatus "@baseboard_fab2_lib.baseboard_fab2(sch_1):page176_i138:b" )
			)
			( pin "R3W3.1"
				( objectStatus "@baseboard_fab2_lib.baseboard_fab2(sch_1):page249_i36:a" )
			)
			( pin "R3W3.2"
				( objectStatus "@baseboard_fab2_lib.baseboard_fab2(sch_1):page249_i36:b" )
			)
			( pin "U10W1.2"
				( objectStatus "@baseboard_fab2_lib.baseboard_fab2(sch_1):page251_i19:a" )
			)
			( pin "U10W1.4"
				( objectStatus "@baseboard_fab2_lib.baseboard_fab2(sch_1):page251_i19:y" )
			)
			( pin "C10W3.1"
				( objectStatus "@baseboard_fab2_lib.baseboard_fab2(sch_1):page251_i16:a" )
			)
			( pin "C10W3.2"
				( objectStatus "@baseboard_fab2_lib.baseboard_fab2(sch_1):page251_i16:b" )
			)
			( pin "R10W2.1"
				( objectStatus "@baseboard_fab2_lib.baseboard_fab2(sch_1):page251_i15:a" )
			)
			( pin "R10W2.2"
				( objectStatus "@baseboard_fab2_lib.baseboard_fab2(sch_1):page251_i15:b" )
			)
			( pin "R10W4.1"
				( objectStatus "@baseboard_fab2_lib.baseboard_fab2(sch_1):page251_i14:a" )
			)
			( pin "R10W4.2"
				( objectStatus "@baseboard_fab2_lib.baseboard_fab2(sch_1):page251_i14:b" )
			)
			( pin "R10W1.1"
				( objectStatus "@baseboard_fab2_lib.baseboard_fab2(sch_1):page251_i13:a" )
			)
			( pin "R10W1.2"
				( objectStatus "@baseboard_fab2_lib.baseboard_fab2(sch_1):page251_i13:b" )
			)
			( pin "CR10W1.2"
				( objectStatus "@baseboard_fab2_lib.baseboard_fab2(sch_1):page251_i12:a" )
			)
			( pin "CR10W1.1"
				( objectStatus "@baseboard_fab2_lib.baseboard_fab2(sch_1):page251_i12:c" )
			)
			( pin "R10W3.1"
				( objectStatus "@baseboard_fab2_lib.baseboard_fab2(sch_1):page251_i11:a" )
			)
			( pin "R10W3.2"
				( objectStatus "@baseboard_fab2_lib.baseboard_fab2(sch_1):page251_i11:b" )
			)
			( pin "R10W5.1"
				( objectStatus "@baseboard_fab2_lib.baseboard_fab2(sch_1):page251_i5:a" )
			)
			( pin "R10W5.2"
				( objectStatus "@baseboard_fab2_lib.baseboard_fab2(sch_1):page251_i5:b" )
			)
			( pin "C10W1.1"
				( objectStatus "@baseboard_fab2_lib.baseboard_fab2(sch_1):page251_i3:a" )
			)
			( pin "C10W1.2"
				( objectStatus "@baseboard_fab2_lib.baseboard_fab2(sch_1):page251_i3:b" )
			)
			( pin "C10W2.1"
				( objectStatus "@baseboard_fab2_lib.baseboard_fab2(sch_1):page251_i1:a" )
			)
			( pin "C10W2.2"
				( objectStatus "@baseboard_fab2_lib.baseboard_fab2(sch_1):page251_i1:b" )
			)
			( pin "U2R1.1"
				( objectStatus "@baseboard_fab2_lib.baseboard_fab2(sch_1):page157_i390:\1a\" )
			)
			( pin "U2R1.6"
				( objectStatus "@baseboard_fab2_lib.baseboard_fab2(sch_1):page157_i390:\1y\" )
			)
			( pin "U2R1.3"
				( objectStatus "@baseboard_fab2_lib.baseboard_fab2(sch_1):page157_i390:\2a\" )
			)
			( pin "U2R1.4"
				( objectStatus "@baseboard_fab2_lib.baseboard_fab2(sch_1):page157_i390:\2y\" )
			)
			( pin "U2R1.2"
				( objectStatus "@baseboard_fab2_lib.baseboard_fab2(sch_1):page157_i390:gnd" )
			)
			( pin "U2R1.5"
				( objectStatus "@baseboard_fab2_lib.baseboard_fab2(sch_1):page157_i390:vcc" )
			)
			( pin "R2R10.1"
				( objectStatus "@baseboard_fab2_lib.baseboard_fab2(sch_1):page157_i391:a" )
			)
			( pin "R2R10.2"
				( objectStatus "@baseboard_fab2_lib.baseboard_fab2(sch_1):page157_i391:b" )
			)
			( pin "R9A9.1"
				( objectStatus "@baseboard_fab2_lib.baseboard_fab2(sch_1):page175_i95:a" )
			)
			( pin "R9A9.2"
				( objectStatus "@baseboard_fab2_lib.baseboard_fab2(sch_1):page175_i95:b" )
			)
			( pin "U9A4.1"
				( objectStatus "@baseboard_fab2_lib.baseboard_fab2(sch_1):page175_i97:\1a\" )
			)
			( pin "U9A4.6"
				( objectStatus "@baseboard_fab2_lib.baseboard_fab2(sch_1):page175_i97:\1y\" )
			)
			( pin "U9A4.3"
				( objectStatus "@baseboard_fab2_lib.baseboard_fab2(sch_1):page175_i97:\2a\" )
			)
			( pin "U9A4.4"
				( objectStatus "@baseboard_fab2_lib.baseboard_fab2(sch_1):page175_i97:\2y\" )
			)
			( pin "U9A4.2"
				( objectStatus "@baseboard_fab2_lib.baseboard_fab2(sch_1):page175_i97:gnd" )
			)
			( pin "U9A4.5"
				( objectStatus "@baseboard_fab2_lib.baseboard_fab2(sch_1):page175_i97:vcc" )
			)
			( pin "R1U18.1"
				( objectStatus "@baseboard_fab2_lib.baseboard_fab2(sch_1):page164_i40:a" )
			)
			( pin "R1U18.2"
				( objectStatus "@baseboard_fab2_lib.baseboard_fab2(sch_1):page164_i40:b" )
			)
			( pin "U8F3.1"
				( objectStatus "@baseboard_fab2_lib.baseboard_fab2(sch_1):page156_i340:\1a\" )
			)
			( pin "U8F3.6"
				( objectStatus "@baseboard_fab2_lib.baseboard_fab2(sch_1):page156_i340:\1y\" )
			)
			( pin "U8F3.3"
				( objectStatus "@baseboard_fab2_lib.baseboard_fab2(sch_1):page156_i340:\2a\" )
			)
			( pin "U8F3.4"
				( objectStatus "@baseboard_fab2_lib.baseboard_fab2(sch_1):page156_i340:\2y\" )
			)
			( pin "U8F3.2"
				( objectStatus "@baseboard_fab2_lib.baseboard_fab2(sch_1):page156_i340:gnd" )
			)
			( pin "U8F3.5"
				( objectStatus "@baseboard_fab2_lib.baseboard_fab2(sch_1):page156_i340:vcc" )
			)
			( pin "U8G1.1"
				( objectStatus "@baseboard_fab2_lib.baseboard_fab2(sch_1):page156_i342:\1a\" )
			)
			( pin "U8G1.6"
				( objectStatus "@baseboard_fab2_lib.baseboard_fab2(sch_1):page156_i342:\1y\" )
			)
			( pin "U8G1.3"
				( objectStatus "@baseboard_fab2_lib.baseboard_fab2(sch_1):page156_i342:\2a\" )
			)
			( pin "U8G1.4"
				( objectStatus "@baseboard_fab2_lib.baseboard_fab2(sch_1):page156_i342:\2y\" )
			)
			( pin "U8G1.2"
				( objectStatus "@baseboard_fab2_lib.baseboard_fab2(sch_1):page156_i342:gnd" )
			)
			( pin "U8G1.5"
				( objectStatus "@baseboard_fab2_lib.baseboard_fab2(sch_1):page156_i342:vcc" )
			)
			( pin "C25W57.1"
				( objectStatus "@baseboard_fab2_lib.baseboard_fab2(sch_1):page149_i130:a" )
			)
			( pin "C25W57.2"
				( objectStatus "@baseboard_fab2_lib.baseboard_fab2(sch_1):page149_i130:b" )
			)
			( pin "R9F34.1"
				( objectStatus "@baseboard_fab2_lib.baseboard_fab2(sch_1):page151_i209:a" )
			)
			( pin "R9F34.2"
				( objectStatus "@baseboard_fab2_lib.baseboard_fab2(sch_1):page151_i209:b" )
			)
			( pin "C10W4.1"
				( objectStatus "@baseboard_fab2_lib.baseboard_fab2(sch_1):page251_i21:a" )
			)
			( pin "C10W4.2"
				( objectStatus "@baseboard_fab2_lib.baseboard_fab2(sch_1):page251_i21:b" )
			)
			( pin "R1W14.1"
				( objectStatus "@baseboard_fab2_lib.baseboard_fab2(sch_1):page115_i118:a" )
			)
			( pin "R1W14.2"
				( objectStatus "@baseboard_fab2_lib.baseboard_fab2(sch_1):page115_i118:b" )
			)
			( pin "R1W15.1"
				( objectStatus "@baseboard_fab2_lib.baseboard_fab2(sch_1):page115_i119:a" )
			)
			( pin "R1W15.2"
				( objectStatus "@baseboard_fab2_lib.baseboard_fab2(sch_1):page115_i119:b" )
			)
			( pin "R1W17.1"
				( objectStatus "@baseboard_fab2_lib.baseboard_fab2(sch_1):page115_i120:a" )
			)
			( pin "R1W17.2"
				( objectStatus "@baseboard_fab2_lib.baseboard_fab2(sch_1):page115_i120:b" )
			)
			( pin "R1W16.1"
				( objectStatus "@baseboard_fab2_lib.baseboard_fab2(sch_1):page115_i121:a" )
			)
			( pin "R1W16.2"
				( objectStatus "@baseboard_fab2_lib.baseboard_fab2(sch_1):page115_i121:b" )
			)
			( pin "R1W19.1"
				( objectStatus "@baseboard_fab2_lib.baseboard_fab2(sch_1):page115_i122:a" )
			)
			( pin "R1W19.2"
				( objectStatus "@baseboard_fab2_lib.baseboard_fab2(sch_1):page115_i122:b" )
			)
			( pin "R1W18.1"
				( objectStatus "@baseboard_fab2_lib.baseboard_fab2(sch_1):page115_i123:a" )
			)
			( pin "R1W18.2"
				( objectStatus "@baseboard_fab2_lib.baseboard_fab2(sch_1):page115_i123:b" )
			)
			( pin "R25W123.1"
				( objectStatus "@baseboard_fab2_lib.baseboard_fab2(sch_1):page144_i139:a" )
			)
			( pin "R25W123.2"
				( objectStatus "@baseboard_fab2_lib.baseboard_fab2(sch_1):page144_i139:b" )
			)
			( pin "R25W124.1"
				( objectStatus "@baseboard_fab2_lib.baseboard_fab2(sch_1):page144_i140:a" )
			)
			( pin "R25W124.2"
				( objectStatus "@baseboard_fab2_lib.baseboard_fab2(sch_1):page144_i140:b" )
			)
			( pin "R25W125.1"
				( objectStatus "@baseboard_fab2_lib.baseboard_fab2(sch_1):page144_i141:a" )
			)
			( pin "R25W125.2"
				( objectStatus "@baseboard_fab2_lib.baseboard_fab2(sch_1):page144_i141:b" )
			)
			( pin "C25W72.1"
				( objectStatus "@baseboard_fab2_lib.baseboard_fab2(sch_1):page255_i7:a" )
			)
			( pin "C25W72.2"
				( objectStatus "@baseboard_fab2_lib.baseboard_fab2(sch_1):page255_i7:b" )
			)
			( pin "C25W73.1"
				( objectStatus "@baseboard_fab2_lib.baseboard_fab2(sch_1):page255_i11:a" )
			)
			( pin "C25W73.2"
				( objectStatus "@baseboard_fab2_lib.baseboard_fab2(sch_1):page255_i11:b" )
			)
			( pin "C25W74.1"
				( objectStatus "@baseboard_fab2_lib.baseboard_fab2(sch_1):page255_i12:a" )
			)
			( pin "C25W74.2"
				( objectStatus "@baseboard_fab2_lib.baseboard_fab2(sch_1):page255_i12:b" )
			)
			( pin "C25W77.1"
				( objectStatus "@baseboard_fab2_lib.baseboard_fab2(sch_1):page255_i16:a" )
			)
			( pin "C25W77.2"
				( objectStatus "@baseboard_fab2_lib.baseboard_fab2(sch_1):page255_i16:b" )
			)
			( pin "C25W76.1"
				( objectStatus "@baseboard_fab2_lib.baseboard_fab2(sch_1):page255_i18:a" )
			)
			( pin "C25W76.2"
				( objectStatus "@baseboard_fab2_lib.baseboard_fab2(sch_1):page255_i18:b" )
			)
			( pin "C25W75.1"
				( objectStatus "@baseboard_fab2_lib.baseboard_fab2(sch_1):page255_i21:a" )
			)
			( pin "C25W75.2"
				( objectStatus "@baseboard_fab2_lib.baseboard_fab2(sch_1):page255_i21:b" )
			)
			( pin "R25W128.1"
				( objectStatus "@baseboard_fab2_lib.baseboard_fab2(sch_1):page255_i22:a" )
			)
			( pin "R25W128.2"
				( objectStatus "@baseboard_fab2_lib.baseboard_fab2(sch_1):page255_i22:b" )
			)
			( pin "R25W127.1"
				( objectStatus "@baseboard_fab2_lib.baseboard_fab2(sch_1):page255_i24:a" )
			)
			( pin "R25W127.2"
				( objectStatus "@baseboard_fab2_lib.baseboard_fab2(sch_1):page255_i24:b" )
			)
			( pin "R25W126.1"
				( objectStatus "@baseboard_fab2_lib.baseboard_fab2(sch_1):page255_i26:a" )
			)
			( pin "R25W126.2"
				( objectStatus "@baseboard_fab2_lib.baseboard_fab2(sch_1):page255_i26:b" )
			)
			( pin "R25W129.1"
				( objectStatus "@baseboard_fab2_lib.baseboard_fab2(sch_1):page146_i152:a" )
			)
			( pin "R25W129.2"
				( objectStatus "@baseboard_fab2_lib.baseboard_fab2(sch_1):page146_i152:b" )
			)
			( pin "R25W130.1"
				( objectStatus "@baseboard_fab2_lib.baseboard_fab2(sch_1):page146_i153:a" )
			)
			( pin "R25W130.2"
				( objectStatus "@baseboard_fab2_lib.baseboard_fab2(sch_1):page146_i153:b" )
			)
			( pin "R25W131.1"
				( objectStatus "@baseboard_fab2_lib.baseboard_fab2(sch_1):page255_i30:a" )
			)
			( pin "R25W131.2"
				( objectStatus "@baseboard_fab2_lib.baseboard_fab2(sch_1):page255_i30:b" )
			)
			( pin "R25W132.1"
				( objectStatus "@baseboard_fab2_lib.baseboard_fab2(sch_1):page255_i31:a" )
			)
			( pin "R25W132.2"
				( objectStatus "@baseboard_fab2_lib.baseboard_fab2(sch_1):page255_i31:b" )
			)
			( pin "R25W133.1"
				( objectStatus "@baseboard_fab2_lib.baseboard_fab2(sch_1):page255_i34:a" )
			)
			( pin "R25W133.2"
				( objectStatus "@baseboard_fab2_lib.baseboard_fab2(sch_1):page255_i34:b" )
			)
			( pin "C25W78.1"
				( objectStatus "@baseboard_fab2_lib.baseboard_fab2(sch_1):page255_i35:a" )
			)
			( pin "C25W78.2"
				( objectStatus "@baseboard_fab2_lib.baseboard_fab2(sch_1):page255_i35:b" )
			)
			( pin "R25W136.1"
				( objectStatus "@baseboard_fab2_lib.baseboard_fab2(sch_1):page255_i38:a" )
			)
			( pin "R25W136.2"
				( objectStatus "@baseboard_fab2_lib.baseboard_fab2(sch_1):page255_i38:b" )
			)
			( pin "C25W79.1"
				( objectStatus "@baseboard_fab2_lib.baseboard_fab2(sch_1):page255_i39:a" )
			)
			( pin "C25W79.2"
				( objectStatus "@baseboard_fab2_lib.baseboard_fab2(sch_1):page255_i39:b" )
			)
			( pin "R25W134.1"
				( objectStatus "@baseboard_fab2_lib.baseboard_fab2(sch_1):page255_i43:a" )
			)
			( pin "R25W134.2"
				( objectStatus "@baseboard_fab2_lib.baseboard_fab2(sch_1):page255_i43:b" )
			)
			( pin "R25W135.1"
				( objectStatus "@baseboard_fab2_lib.baseboard_fab2(sch_1):page255_i44:a" )
			)
			( pin "R25W135.2"
				( objectStatus "@baseboard_fab2_lib.baseboard_fab2(sch_1):page255_i44:b" )
			)
			( pin "R6W49.1"
				( objectStatus "@baseboard_fab2_lib.baseboard_fab2(sch_1):page168_i48:a" )
			)
			( pin "R6W49.2"
				( objectStatus "@baseboard_fab2_lib.baseboard_fab2(sch_1):page168_i48:b" )
			)
			( pin "R9P15.1"
				( objectStatus "@baseboard_fab2_lib.baseboard_fab2(sch_1):page200_i243:a" )
			)
			( pin "R9P15.2"
				( objectStatus "@baseboard_fab2_lib.baseboard_fab2(sch_1):page200_i243:b" )
			)
			( pin "R1D10.1"
				( objectStatus "@baseboard_fab2_lib.baseboard_fab2(sch_1):page200_i244:a" )
			)
			( pin "R1D10.2"
				( objectStatus "@baseboard_fab2_lib.baseboard_fab2(sch_1):page200_i244:b" )
			)
			( pin "JA9G1.1"
				( objectStatus "@baseboard_fab2_lib.baseboard_fab2(sch_1):page141_i129:\1\" )
			)
			( pin "JA9G1.2"
				( objectStatus "@baseboard_fab2_lib.baseboard_fab2(sch_1):page141_i129:\2\" )
			)
			( pin "JA9G1.L1"
				( objectStatus "@baseboard_fab2_lib.baseboard_fab2(sch_1):page141_i129:l1" )
			)
			( pin "JA9G1.L2"
				( objectStatus "@baseboard_fab2_lib.baseboard_fab2(sch_1):page141_i129:l2" )
			)
			( pin "JA9G1.L3"
				( objectStatus "@baseboard_fab2_lib.baseboard_fab2(sch_1):page141_i129:l3" )
			)
			( pin "JA9G1.L4"
				( objectStatus "@baseboard_fab2_lib.baseboard_fab2(sch_1):page141_i129:l4" )
			)
			( pin "JA9G1.R1"
				( objectStatus "@baseboard_fab2_lib.baseboard_fab2(sch_1):page141_i129:r1" )
			)
			( pin "JA9G1.R2"
				( objectStatus "@baseboard_fab2_lib.baseboard_fab2(sch_1):page141_i129:r2" )
			)
			( pin "JA9G1.R3"
				( objectStatus "@baseboard_fab2_lib.baseboard_fab2(sch_1):page141_i129:r3" )
			)
			( pin "JA9G1.R4"
				( objectStatus "@baseboard_fab2_lib.baseboard_fab2(sch_1):page141_i129:r4" )
			)
			( pin "JA9G1.R5"
				( objectStatus "@baseboard_fab2_lib.baseboard_fab2(sch_1):page141_i129:r5" )
			)
			( pin "JA9G1.R6"
				( objectStatus "@baseboard_fab2_lib.baseboard_fab2(sch_1):page141_i129:r6" )
			)
			( pin "JA9G1.R7"
				( objectStatus "@baseboard_fab2_lib.baseboard_fab2(sch_1):page141_i129:r7" )
			)
			( pin "JA9G1.R8"
				( objectStatus "@baseboard_fab2_lib.baseboard_fab2(sch_1):page141_i129:r8" )
			)
			( pin "JA9G1.R9"
				( objectStatus "@baseboard_fab2_lib.baseboard_fab2(sch_1):page141_i129:r9" )
			)
			( pin "JA9G1.R10"
				( objectStatus "@baseboard_fab2_lib.baseboard_fab2(sch_1):page141_i129:r10" )
			)
			( pin "JA9G1.R11"
				( objectStatus "@baseboard_fab2_lib.baseboard_fab2(sch_1):page141_i129:r11" )
			)
			( pin "F9B1.1"
				( objectStatus "@baseboard_fab2_lib.baseboard_fab2(sch_1):page172_i66:a(0)" )
			)
			( pin "F9B1.2"
				( objectStatus "@baseboard_fab2_lib.baseboard_fab2(sch_1):page172_i66:b(0)" )
			)
			( pin "R25W138.1"
				( objectStatus "@baseboard_fab2_lib.baseboard_fab2(sch_1):page255_i49:a" )
			)
			( pin "R25W138.2"
				( objectStatus "@baseboard_fab2_lib.baseboard_fab2(sch_1):page255_i49:b" )
			)
			( pin "C25W81.1"
				( objectStatus "@baseboard_fab2_lib.baseboard_fab2(sch_1):page255_i60:a" )
			)
			( pin "C25W81.2"
				( objectStatus "@baseboard_fab2_lib.baseboard_fab2(sch_1):page255_i60:b" )
			)
			( pin "R25W139.1"
				( objectStatus "@baseboard_fab2_lib.baseboard_fab2(sch_1):page255_i59:a" )
			)
			( pin "R25W139.2"
				( objectStatus "@baseboard_fab2_lib.baseboard_fab2(sch_1):page255_i59:b" )
			)
			( pin "C25W82.1"
				( objectStatus "@baseboard_fab2_lib.baseboard_fab2(sch_1):page255_i62:a" )
			)
			( pin "C25W82.2"
				( objectStatus "@baseboard_fab2_lib.baseboard_fab2(sch_1):page255_i62:b" )
			)
			( pin "C25P83.1"
				( objectStatus "@baseboard_fab2_lib.baseboard_fab2(sch_1):page255_i74:a" )
			)
			( pin "C25P83.2"
				( objectStatus "@baseboard_fab2_lib.baseboard_fab2(sch_1):page255_i74:b" )
			)
			( pin "L25W1.1"
				( objectStatus "@baseboard_fab2_lib.baseboard_fab2(sch_1):page255_i76:\1\" )
			)
			( pin "L25W1.2"
				( objectStatus "@baseboard_fab2_lib.baseboard_fab2(sch_1):page255_i76:\2\" )
			)
			( pin "L25W2.1"
				( objectStatus "@baseboard_fab2_lib.baseboard_fab2(sch_1):page255_i77:\1\" )
			)
			( pin "L25W2.2"
				( objectStatus "@baseboard_fab2_lib.baseboard_fab2(sch_1):page255_i77:\2\" )
			)
			( pin "L25W3.1"
				( objectStatus "@baseboard_fab2_lib.baseboard_fab2(sch_1):page255_i78:\1\" )
			)
			( pin "L25W3.2"
				( objectStatus "@baseboard_fab2_lib.baseboard_fab2(sch_1):page255_i78:\2\" )
			)
			( pin "U1B2.5"
				( objectStatus "@baseboard_fab2_lib.baseboard_fab2(sch_1):page163_i28:en" )
			)
			( pin "U1B2.4"
				( objectStatus "@baseboard_fab2_lib.baseboard_fab2(sch_1):page163_i28:gnd" )
			)
			( pin "U1B2.2"
				( objectStatus "@baseboard_fab2_lib.baseboard_fab2(sch_1):page163_i28:scla" )
			)
			( pin "U1B2.7"
				( objectStatus "@baseboard_fab2_lib.baseboard_fab2(sch_1):page163_i28:sclb" )
			)
			( pin "U1B2.3"
				( objectStatus "@baseboard_fab2_lib.baseboard_fab2(sch_1):page163_i28:sdaa" )
			)
			( pin "U1B2.6"
				( objectStatus "@baseboard_fab2_lib.baseboard_fab2(sch_1):page163_i28:sdab" )
			)
			( pin "U1B2.1"
				( objectStatus "@baseboard_fab2_lib.baseboard_fab2(sch_1):page163_i28:vcca" )
			)
			( pin "U1B2.8"
				( objectStatus "@baseboard_fab2_lib.baseboard_fab2(sch_1):page163_i28:vccb" )
			)
			( pin "U6W2.5"
				( objectStatus "@baseboard_fab2_lib.baseboard_fab2(sch_1):page247_i118:en" )
			)
			( pin "U6W2.4"
				( objectStatus "@baseboard_fab2_lib.baseboard_fab2(sch_1):page247_i118:gnd" )
			)
			( pin "U6W2.2"
				( objectStatus "@baseboard_fab2_lib.baseboard_fab2(sch_1):page247_i118:scla" )
			)
			( pin "U6W2.7"
				( objectStatus "@baseboard_fab2_lib.baseboard_fab2(sch_1):page247_i118:sclb" )
			)
			( pin "U6W2.3"
				( objectStatus "@baseboard_fab2_lib.baseboard_fab2(sch_1):page247_i118:sdaa" )
			)
			( pin "U6W2.6"
				( objectStatus "@baseboard_fab2_lib.baseboard_fab2(sch_1):page247_i118:sdab" )
			)
			( pin "U6W2.1"
				( objectStatus "@baseboard_fab2_lib.baseboard_fab2(sch_1):page247_i118:vcca" )
			)
			( pin "U6W2.8"
				( objectStatus "@baseboard_fab2_lib.baseboard_fab2(sch_1):page247_i118:vccb" )
			)
			( pin "U1W2.5"
				( objectStatus "@baseboard_fab2_lib.baseboard_fab2(sch_1):page248_i49:en" )
			)
			( pin "U1W2.4"
				( objectStatus "@baseboard_fab2_lib.baseboard_fab2(sch_1):page248_i49:gnd" )
			)
			( pin "U1W2.2"
				( objectStatus "@baseboard_fab2_lib.baseboard_fab2(sch_1):page248_i49:scla" )
			)
			( pin "U1W2.7"
				( objectStatus "@baseboard_fab2_lib.baseboard_fab2(sch_1):page248_i49:sclb" )
			)
			( pin "U1W2.3"
				( objectStatus "@baseboard_fab2_lib.baseboard_fab2(sch_1):page248_i49:sdaa" )
			)
			( pin "U1W2.6"
				( objectStatus "@baseboard_fab2_lib.baseboard_fab2(sch_1):page248_i49:sdab" )
			)
			( pin "U1W2.1"
				( objectStatus "@baseboard_fab2_lib.baseboard_fab2(sch_1):page248_i49:vcca" )
			)
			( pin "U1W2.8"
				( objectStatus "@baseboard_fab2_lib.baseboard_fab2(sch_1):page248_i49:vccb" )
			)
			( pin "C2M4.1"
				( objectStatus "@baseboard_fab2_lib.baseboard_fab2(sch_1):page116_i238:a" )
			)
			( pin "C2M4.2"
				( objectStatus "@baseboard_fab2_lib.baseboard_fab2(sch_1):page116_i238:b" )
			)
			( pin "C2M3.1"
				( objectStatus "@baseboard_fab2_lib.baseboard_fab2(sch_1):page116_i239:a" )
			)
			( pin "C2M3.2"
				( objectStatus "@baseboard_fab2_lib.baseboard_fab2(sch_1):page116_i239:b" )
			)
			( pin "R7C4.1"
				( objectStatus "@baseboard_fab2_lib.baseboard_fab2(sch_1):page114_i191:a" )
			)
			( pin "R7C4.2"
				( objectStatus "@baseboard_fab2_lib.baseboard_fab2(sch_1):page114_i191:b" )
			)
			( pin "R7C2.1"
				( objectStatus "@baseboard_fab2_lib.baseboard_fab2(sch_1):page114_i192:a" )
			)
			( pin "R7C2.2"
				( objectStatus "@baseboard_fab2_lib.baseboard_fab2(sch_1):page114_i192:b" )
			)
			( pin "R8D16.1"
				( objectStatus "@baseboard_fab2_lib.baseboard_fab2(sch_1):page125_i85:a" )
			)
			( pin "R8D16.2"
				( objectStatus "@baseboard_fab2_lib.baseboard_fab2(sch_1):page125_i85:b" )
			)
			( pin "R7D1.1"
				( objectStatus "@baseboard_fab2_lib.baseboard_fab2(sch_1):page125_i86:a" )
			)
			( pin "R7D1.2"
				( objectStatus "@baseboard_fab2_lib.baseboard_fab2(sch_1):page125_i86:b" )
			)
			( pin "RT27.1"
				( objectStatus "@baseboard_fab2_lib.baseboard_fab2(sch_1):page203_i135:\1\" )
			)
			( pin "RT27.2"
				( objectStatus "@baseboard_fab2_lib.baseboard_fab2(sch_1):page203_i135:\2\" )
			)
			( pin "RT26.1"
				( objectStatus "@baseboard_fab2_lib.baseboard_fab2(sch_1):page203_i134:\1\" )
			)
			( pin "RT26.2"
				( objectStatus "@baseboard_fab2_lib.baseboard_fab2(sch_1):page203_i134:\2\" )
			)
			( pin "C22W2.1"
				( objectStatus "@baseboard_fab2_lib.baseboard_fab2(sch_1):page225_i247:\1\" )
			)
			( pin "C22W2.2"
				( objectStatus "@baseboard_fab2_lib.baseboard_fab2(sch_1):page225_i247:\2\" )
			)
			( pin "C22W4.1"
				( objectStatus "@baseboard_fab2_lib.baseboard_fab2(sch_1):page225_i251:\1\" )
			)
			( pin "C22W4.2"
				( objectStatus "@baseboard_fab2_lib.baseboard_fab2(sch_1):page225_i251:\2\" )
			)
			( pin "R6W50.1"
				( objectStatus "@baseboard_fab2_lib.baseboard_fab2(sch_1):page176_i178:a" )
			)
			( pin "R6W50.2"
				( objectStatus "@baseboard_fab2_lib.baseboard_fab2(sch_1):page176_i178:b" )
			)
			( pin "C4G5.1"
				( objectStatus "@baseboard_fab2_lib.baseboard_fab2(sch_1):page233_i280:\1\" )
			)
			( pin "C4G5.2"
				( objectStatus "@baseboard_fab2_lib.baseboard_fab2(sch_1):page233_i280:\2\" )
			)
			( pin "C22W7.1"
				( objectStatus "@baseboard_fab2_lib.baseboard_fab2(sch_1):page232_i311:\1\" )
			)
			( pin "C22W7.2"
				( objectStatus "@baseboard_fab2_lib.baseboard_fab2(sch_1):page232_i311:\2\" )
			)
			( pin "C22W9.1"
				( objectStatus "@baseboard_fab2_lib.baseboard_fab2(sch_1):page241_i95:\1\" )
			)
			( pin "C22W9.2"
				( objectStatus "@baseboard_fab2_lib.baseboard_fab2(sch_1):page241_i95:\2\" )
			)
			( pin "C22W8.1"
				( objectStatus "@baseboard_fab2_lib.baseboard_fab2(sch_1):page241_i96:\1\" )
			)
			( pin "C22W8.2"
				( objectStatus "@baseboard_fab2_lib.baseboard_fab2(sch_1):page241_i96:\2\" )
			)
			( pin "C7E12.1"
				( objectStatus "@baseboard_fab2_lib.baseboard_fab2(sch_1):page241_i98:\1\" )
			)
			( pin "C7E12.2"
				( objectStatus "@baseboard_fab2_lib.baseboard_fab2(sch_1):page241_i98:\2\" )
			)
			( pin "C9F1.1"
				( objectStatus "@baseboard_fab2_lib.baseboard_fab2(sch_1):page240_i181:\1\" )
			)
			( pin "C9F1.2"
				( objectStatus "@baseboard_fab2_lib.baseboard_fab2(sch_1):page240_i181:\2\" )
			)
			( pin "C22W10.1"
				( objectStatus "@baseboard_fab2_lib.baseboard_fab2(sch_1):page231_i225:\1\" )
			)
			( pin "C22W10.2"
				( objectStatus "@baseboard_fab2_lib.baseboard_fab2(sch_1):page231_i225:\2\" )
			)
			( pin "C7F7.1"
				( objectStatus "@baseboard_fab2_lib.baseboard_fab2(sch_1):page231_i226:\1\" )
			)
			( pin "C7F7.2"
				( objectStatus "@baseboard_fab2_lib.baseboard_fab2(sch_1):page231_i226:\2\" )
			)
			( pin "C22W12.1"
				( objectStatus "@baseboard_fab2_lib.baseboard_fab2(sch_1):page240_i186:\1\" )
			)
			( pin "C22W12.2"
				( objectStatus "@baseboard_fab2_lib.baseboard_fab2(sch_1):page240_i186:\2\" )
			)
			( pin "C22W14.1"
				( objectStatus "@baseboard_fab2_lib.baseboard_fab2(sch_1):page214_i152:\1\" )
			)
			( pin "C22W14.2"
				( objectStatus "@baseboard_fab2_lib.baseboard_fab2(sch_1):page214_i152:\2\" )
			)
			( pin "C22W15.1"
				( objectStatus "@baseboard_fab2_lib.baseboard_fab2(sch_1):page214_i154:\1\" )
			)
			( pin "C22W15.2"
				( objectStatus "@baseboard_fab2_lib.baseboard_fab2(sch_1):page214_i154:\2\" )
			)
			( pin "C22W18.1"
				( objectStatus "@baseboard_fab2_lib.baseboard_fab2(sch_1):page214_i156:\1\" )
			)
			( pin "C22W18.2"
				( objectStatus "@baseboard_fab2_lib.baseboard_fab2(sch_1):page214_i156:\2\" )
			)
			( pin "C22W17.1"
				( objectStatus "@baseboard_fab2_lib.baseboard_fab2(sch_1):page214_i158:\1\" )
			)
			( pin "C22W17.2"
				( objectStatus "@baseboard_fab2_lib.baseboard_fab2(sch_1):page214_i158:\2\" )
			)
			( pin "C22W16.1"
				( objectStatus "@baseboard_fab2_lib.baseboard_fab2(sch_1):page214_i160:\1\" )
			)
			( pin "C22W16.2"
				( objectStatus "@baseboard_fab2_lib.baseboard_fab2(sch_1):page214_i160:\2\" )
			)
			( pin "C4E8.1"
				( objectStatus "@baseboard_fab2_lib.baseboard_fab2(sch_1):page214_i161:\1\" )
			)
			( pin "C4E8.2"
				( objectStatus "@baseboard_fab2_lib.baseboard_fab2(sch_1):page214_i161:\2\" )
			)
			( pin "C4E9.1"
				( objectStatus "@baseboard_fab2_lib.baseboard_fab2(sch_1):page214_i164:\1\" )
			)
			( pin "C4E9.2"
				( objectStatus "@baseboard_fab2_lib.baseboard_fab2(sch_1):page214_i164:\2\" )
			)
			( pin "C22W21.1"
				( objectStatus "@baseboard_fab2_lib.baseboard_fab2(sch_1):page214_i166:\1\" )
			)
			( pin "C22W21.2"
				( objectStatus "@baseboard_fab2_lib.baseboard_fab2(sch_1):page214_i166:\2\" )
			)
			( pin "C22W20.1"
				( objectStatus "@baseboard_fab2_lib.baseboard_fab2(sch_1):page214_i168:\1\" )
			)
			( pin "C22W20.2"
				( objectStatus "@baseboard_fab2_lib.baseboard_fab2(sch_1):page214_i168:\2\" )
			)
			( pin "C22W19.1"
				( objectStatus "@baseboard_fab2_lib.baseboard_fab2(sch_1):page214_i169:\1\" )
			)
			( pin "C22W19.2"
				( objectStatus "@baseboard_fab2_lib.baseboard_fab2(sch_1):page214_i169:\2\" )
			)
			( pin "C22W25.1"
				( objectStatus "@baseboard_fab2_lib.baseboard_fab2(sch_1):page236_i162:\1\" )
			)
			( pin "C22W25.2"
				( objectStatus "@baseboard_fab2_lib.baseboard_fab2(sch_1):page236_i162:\2\" )
			)
			( pin "C22W27.1"
				( objectStatus "@baseboard_fab2_lib.baseboard_fab2(sch_1):page236_i163:\1\" )
			)
			( pin "C22W27.2"
				( objectStatus "@baseboard_fab2_lib.baseboard_fab2(sch_1):page236_i163:\2\" )
			)
			( pin "C22W26.1"
				( objectStatus "@baseboard_fab2_lib.baseboard_fab2(sch_1):page236_i165:\1\" )
			)
			( pin "C22W26.2"
				( objectStatus "@baseboard_fab2_lib.baseboard_fab2(sch_1):page236_i165:\2\" )
			)
			( pin "C22W22.1"
				( objectStatus "@baseboard_fab2_lib.baseboard_fab2(sch_1):page236_i171:\1\" )
			)
			( pin "C22W22.2"
				( objectStatus "@baseboard_fab2_lib.baseboard_fab2(sch_1):page236_i171:\2\" )
			)
			( pin "C7A14.1"
				( objectStatus "@baseboard_fab2_lib.baseboard_fab2(sch_1):page236_i172:\1\" )
			)
			( pin "C7A14.2"
				( objectStatus "@baseboard_fab2_lib.baseboard_fab2(sch_1):page236_i172:\2\" )
			)
			( pin "C22W31.1"
				( objectStatus "@baseboard_fab2_lib.baseboard_fab2(sch_1):page212_i129:\1\" )
			)
			( pin "C22W31.2"
				( objectStatus "@baseboard_fab2_lib.baseboard_fab2(sch_1):page212_i129:\2\" )
			)
			( pin "C7C8.1"
				( objectStatus "@baseboard_fab2_lib.baseboard_fab2(sch_1):page212_i130:\1\" )
			)
			( pin "C7C8.2"
				( objectStatus "@baseboard_fab2_lib.baseboard_fab2(sch_1):page212_i130:\2\" )
			)
			( pin "C22W30.1"
				( objectStatus "@baseboard_fab2_lib.baseboard_fab2(sch_1):page212_i132:\1\" )
			)
			( pin "C22W30.2"
				( objectStatus "@baseboard_fab2_lib.baseboard_fab2(sch_1):page212_i132:\2\" )
			)
			( pin "C22W29.1"
				( objectStatus "@baseboard_fab2_lib.baseboard_fab2(sch_1):page212_i134:\1\" )
			)
			( pin "C22W29.2"
				( objectStatus "@baseboard_fab2_lib.baseboard_fab2(sch_1):page212_i134:\2\" )
			)
			( pin "C22W28.1"
				( objectStatus "@baseboard_fab2_lib.baseboard_fab2(sch_1):page212_i136:\1\" )
			)
			( pin "C22W28.2"
				( objectStatus "@baseboard_fab2_lib.baseboard_fab2(sch_1):page212_i136:\2\" )
			)
			( pin "C7C7.1"
				( objectStatus "@baseboard_fab2_lib.baseboard_fab2(sch_1):page212_i138:\1\" )
			)
			( pin "C7C7.2"
				( objectStatus "@baseboard_fab2_lib.baseboard_fab2(sch_1):page212_i138:\2\" )
			)
			( pin "R8D13.1"
				( objectStatus "@baseboard_fab2_lib.baseboard_fab2(sch_1):page125_i87:a" )
			)
			( pin "R8D13.2"
				( objectStatus "@baseboard_fab2_lib.baseboard_fab2(sch_1):page125_i87:b" )
			)
			( pin "C22W34.1"
				( objectStatus "@baseboard_fab2_lib.baseboard_fab2(sch_1):page139_i244:\1\" )
			)
			( pin "C22W34.2"
				( objectStatus "@baseboard_fab2_lib.baseboard_fab2(sch_1):page139_i244:\2\" )
			)
			( pin "C9F2.1"
				( objectStatus "@baseboard_fab2_lib.baseboard_fab2(sch_1):page139_i245:\1\" )
			)
			( pin "C9F2.2"
				( objectStatus "@baseboard_fab2_lib.baseboard_fab2(sch_1):page139_i245:\2\" )
			)
			( pin "C22W35.1"
				( objectStatus "@baseboard_fab2_lib.baseboard_fab2(sch_1):page139_i246:\1\" )
			)
			( pin "C22W35.2"
				( objectStatus "@baseboard_fab2_lib.baseboard_fab2(sch_1):page139_i246:\2\" )
			)
			( pin "C9E6.1"
				( objectStatus "@baseboard_fab2_lib.baseboard_fab2(sch_1):page139_i248:\1\" )
			)
			( pin "C9E6.2"
				( objectStatus "@baseboard_fab2_lib.baseboard_fab2(sch_1):page139_i248:\2\" )
			)
			( pin "R2N10.1"
				( objectStatus "@baseboard_fab2_lib.baseboard_fab2(sch_1):page126_i27:a" )
			)
			( pin "R2N10.2"
				( objectStatus "@baseboard_fab2_lib.baseboard_fab2(sch_1):page126_i27:b" )
			)
			( pin "Q1W1.3"
				( objectStatus "@baseboard_fab2_lib.baseboard_fab2(sch_1):page250_i29:drn" )
			)
			( pin "Q1W1.1"
				( objectStatus "@baseboard_fab2_lib.baseboard_fab2(sch_1):page250_i29:gate" )
			)
			( pin "Q1W1.2"
				( objectStatus "@baseboard_fab2_lib.baseboard_fab2(sch_1):page250_i29:src" )
			)
			( pin "R12W10.1"
				( objectStatus "@baseboard_fab2_lib.baseboard_fab2(sch_1):page197_i109:\1\" )
			)
			( pin "R12W10.2"
				( objectStatus "@baseboard_fab2_lib.baseboard_fab2(sch_1):page197_i109:\2\" )
			)
			( pin "U6W1.21"
				( objectStatus "@baseboard_fab2_lib.baseboard_fab2(sch_1):page247_i120:a0" )
			)
			( pin "U6W1.2"
				( objectStatus "@baseboard_fab2_lib.baseboard_fab2(sch_1):page247_i120:a1" )
			)
			( pin "U6W1.3"
				( objectStatus "@baseboard_fab2_lib.baseboard_fab2(sch_1):page247_i120:a2" )
			)
			( pin "U6W1.12"
				( objectStatus "@baseboard_fab2_lib.baseboard_fab2(sch_1):page247_i120:gnd" )
			)
			( pin "U6W1.1"
				( objectStatus "@baseboard_fab2_lib.baseboard_fab2(sch_1):page247_i120:\int#\" )
			)
			( pin "U6W1.4"
				( objectStatus "@baseboard_fab2_lib.baseboard_fab2(sch_1):page247_i120:p00" )
			)
			( pin "U6W1.5"
				( objectStatus "@baseboard_fab2_lib.baseboard_fab2(sch_1):page247_i120:p01" )
			)
			( pin "U6W1.6"
				( objectStatus "@baseboard_fab2_lib.baseboard_fab2(sch_1):page247_i120:p02" )
			)
			( pin "U6W1.7"
				( objectStatus "@baseboard_fab2_lib.baseboard_fab2(sch_1):page247_i120:p03" )
			)
			( pin "U6W1.8"
				( objectStatus "@baseboard_fab2_lib.baseboard_fab2(sch_1):page247_i120:p04" )
			)
			( pin "U6W1.9"
				( objectStatus "@baseboard_fab2_lib.baseboard_fab2(sch_1):page247_i120:p05" )
			)
			( pin "U6W1.10"
				( objectStatus "@baseboard_fab2_lib.baseboard_fab2(sch_1):page247_i120:p06" )
			)
			( pin "U6W1.11"
				( objectStatus "@baseboard_fab2_lib.baseboard_fab2(sch_1):page247_i120:p07" )
			)
			( pin "U6W1.13"
				( objectStatus "@baseboard_fab2_lib.baseboard_fab2(sch_1):page247_i120:p10" )
			)
			( pin "U6W1.14"
				( objectStatus "@baseboard_fab2_lib.baseboard_fab2(sch_1):page247_i120:p11" )
			)
			( pin "U6W1.15"
				( objectStatus "@baseboard_fab2_lib.baseboard_fab2(sch_1):page247_i120:p12" )
			)
			( pin "U6W1.16"
				( objectStatus "@baseboard_fab2_lib.baseboard_fab2(sch_1):page247_i120:p13" )
			)
			( pin "U6W1.17"
				( objectStatus "@baseboard_fab2_lib.baseboard_fab2(sch_1):page247_i120:p14" )
			)
			( pin "U6W1.18"
				( objectStatus "@baseboard_fab2_lib.baseboard_fab2(sch_1):page247_i120:p15" )
			)
			( pin "U6W1.19"
				( objectStatus "@baseboard_fab2_lib.baseboard_fab2(sch_1):page247_i120:p16" )
			)
			( pin "U6W1.20"
				( objectStatus "@baseboard_fab2_lib.baseboard_fab2(sch_1):page247_i120:p17" )
			)
			( pin "U6W1.22"
				( objectStatus "@baseboard_fab2_lib.baseboard_fab2(sch_1):page247_i120:scl" )
			)
			( pin "U6W1.23"
				( objectStatus "@baseboard_fab2_lib.baseboard_fab2(sch_1):page247_i120:sda" )
			)
			( pin "U6W1.24"
				( objectStatus "@baseboard_fab2_lib.baseboard_fab2(sch_1):page247_i120:vcc" )
			)
			( pin "C6W10.1"
				( objectStatus "@baseboard_fab2_lib.baseboard_fab2(sch_1):page176_i139:a" )
			)
			( pin "C6W10.2"
				( objectStatus "@baseboard_fab2_lib.baseboard_fab2(sch_1):page176_i139:b" )
			)
			( pin "R7P14.1"
				( objectStatus "@baseboard_fab2_lib.baseboard_fab2(sch_1):page90_i100:a" )
			)
			( pin "R7P14.2"
				( objectStatus "@baseboard_fab2_lib.baseboard_fab2(sch_1):page90_i100:b" )
			)
			( pin "R5D4.1"
				( objectStatus "@baseboard_fab2_lib.baseboard_fab2(sch_1):page90_i96:a" )
			)
			( pin "R5D4.2"
				( objectStatus "@baseboard_fab2_lib.baseboard_fab2(sch_1):page90_i96:b" )
			)
			( pin "R1D14.1"
				( objectStatus "@baseboard_fab2_lib.baseboard_fab2(sch_1):page200_i246:a" )
			)
			( pin "R1D14.2"
				( objectStatus "@baseboard_fab2_lib.baseboard_fab2(sch_1):page200_i246:b" )
			)
			( pin "Q25W4.6"
				( objectStatus "@baseboard_fab2_lib.baseboard_fab2(sch_1):page255_i95:drain(0)" )
			)
			( pin "Q25W4.2"
				( objectStatus "@baseboard_fab2_lib.baseboard_fab2(sch_1):page255_i95:gate(0)" )
			)
			( pin "Q25W4.1"
				( objectStatus "@baseboard_fab2_lib.baseboard_fab2(sch_1):page255_i95:source(0)" )
			)
			( pin "Q25W4.3"
				( objectStatus "@baseboard_fab2_lib.baseboard_fab2(sch_1):page255_i96:drain(0)" )
			)
			( pin "Q25W4.5"
				( objectStatus "@baseboard_fab2_lib.baseboard_fab2(sch_1):page255_i96:gate(0)" )
			)
			( pin "Q25W4.4"
				( objectStatus "@baseboard_fab2_lib.baseboard_fab2(sch_1):page255_i96:source(0)" )
			)
			( pin "R5W2.1"
				( objectStatus "@baseboard_fab2_lib.baseboard_fab2(sch_1):page113_i273:a" )
			)
			( pin "R5W2.2"
				( objectStatus "@baseboard_fab2_lib.baseboard_fab2(sch_1):page113_i273:b" )
			)
			( pin "R5W1.1"
				( objectStatus "@baseboard_fab2_lib.baseboard_fab2(sch_1):page113_i272:a" )
			)
			( pin "R5W1.2"
				( objectStatus "@baseboard_fab2_lib.baseboard_fab2(sch_1):page113_i272:b" )
			)
			( pin "R6M8.1"
				( objectStatus "@baseboard_fab2_lib.baseboard_fab2(sch_1):page113_i271:a" )
			)
			( pin "R6M8.2"
				( objectStatus "@baseboard_fab2_lib.baseboard_fab2(sch_1):page113_i271:b" )
			)
			( pin "R4R6.1"
				( objectStatus "@baseboard_fab2_lib.baseboard_fab2(sch_1):page113_i270:a" )
			)
			( pin "R4R6.2"
				( objectStatus "@baseboard_fab2_lib.baseboard_fab2(sch_1):page113_i270:b" )
			)
			( pin "R7W1.1"
				( objectStatus "@baseboard_fab2_lib.baseboard_fab2(sch_1):page118_i167:a" )
			)
			( pin "R7W1.2"
				( objectStatus "@baseboard_fab2_lib.baseboard_fab2(sch_1):page118_i167:b" )
			)
			( pin "J1B4.1"
				( objectStatus "@baseboard_fab2_lib.baseboard_fab2(sch_1):page199_i131:\1\" )
			)
			( pin "J1B4.2"
				( objectStatus "@baseboard_fab2_lib.baseboard_fab2(sch_1):page199_i131:\2\" )
			)
			( pin "J1B4.3"
				( objectStatus "@baseboard_fab2_lib.baseboard_fab2(sch_1):page199_i131:\3\" )
			)
			( pin "CR30W1.1"
				( objectStatus "@baseboard_fab2_lib.baseboard_fab2(sch_1):page253_i5:ac0" )
			)
			( pin "CR30W1.2"
				( objectStatus "@baseboard_fab2_lib.baseboard_fab2(sch_1):page253_i5:ac1" )
			)
			( pin "CR30W1.4"
				( objectStatus "@baseboard_fab2_lib.baseboard_fab2(sch_1):page253_i5:ac2" )
			)
			( pin "CR30W1.5"
				( objectStatus "@baseboard_fab2_lib.baseboard_fab2(sch_1):page253_i5:ac3" )
			)
			( pin "CR30W1.3"
				( objectStatus "@baseboard_fab2_lib.baseboard_fab2(sch_1):page253_i5:gnd(0)" )
			)
			( pin "CR30W1.9"
				( objectStatus "@baseboard_fab2_lib.baseboard_fab2(sch_1):page253_i5:out0" )
			)
			( pin "CR30W1.8"
				( objectStatus "@baseboard_fab2_lib.baseboard_fab2(sch_1):page253_i5:out1" )
			)
			( pin "CR30W1.7"
				( objectStatus "@baseboard_fab2_lib.baseboard_fab2(sch_1):page253_i5:out2" )
			)
			( pin "CR30W1.6"
				( objectStatus "@baseboard_fab2_lib.baseboard_fab2(sch_1):page253_i5:out3" )
			)
			( pin "L30W2.1"
				( objectStatus "@baseboard_fab2_lib.baseboard_fab2(sch_1):page253_i11:\1\" )
			)
			( pin "L30W2.2"
				( objectStatus "@baseboard_fab2_lib.baseboard_fab2(sch_1):page253_i11:\2\" )
			)
			( pin "L30W2.3"
				( objectStatus "@baseboard_fab2_lib.baseboard_fab2(sch_1):page253_i11:\3\" )
			)
			( pin "L30W2.4"
				( objectStatus "@baseboard_fab2_lib.baseboard_fab2(sch_1):page253_i11:\4\" )
			)
			( pin "R30W2.1"
				( objectStatus "@baseboard_fab2_lib.baseboard_fab2(sch_1):page253_i12:a" )
			)
			( pin "R30W2.2"
				( objectStatus "@baseboard_fab2_lib.baseboard_fab2(sch_1):page253_i12:b" )
			)
			( pin "R30W1.1"
				( objectStatus "@baseboard_fab2_lib.baseboard_fab2(sch_1):page253_i13:a" )
			)
			( pin "R30W1.2"
				( objectStatus "@baseboard_fab2_lib.baseboard_fab2(sch_1):page253_i13:b" )
			)
			( pin "R30W4.1"
				( objectStatus "@baseboard_fab2_lib.baseboard_fab2(sch_1):page253_i14:a" )
			)
			( pin "R30W4.2"
				( objectStatus "@baseboard_fab2_lib.baseboard_fab2(sch_1):page253_i14:b" )
			)
			( pin "R30W3.1"
				( objectStatus "@baseboard_fab2_lib.baseboard_fab2(sch_1):page253_i15:a" )
			)
			( pin "R30W3.2"
				( objectStatus "@baseboard_fab2_lib.baseboard_fab2(sch_1):page253_i15:b" )
			)
			( pin "L30W1.1"
				( objectStatus "@baseboard_fab2_lib.baseboard_fab2(sch_1):page253_i16:\1\" )
			)
			( pin "L30W1.2"
				( objectStatus "@baseboard_fab2_lib.baseboard_fab2(sch_1):page253_i16:\2\" )
			)
			( pin "L30W1.3"
				( objectStatus "@baseboard_fab2_lib.baseboard_fab2(sch_1):page253_i16:\3\" )
			)
			( pin "L30W1.4"
				( objectStatus "@baseboard_fab2_lib.baseboard_fab2(sch_1):page253_i16:\4\" )
			)
			( pin "C30W2.1"
				( objectStatus "@baseboard_fab2_lib.baseboard_fab2(sch_1):page253_i19:a" )
			)
			( pin "C30W2.2"
				( objectStatus "@baseboard_fab2_lib.baseboard_fab2(sch_1):page253_i19:b" )
			)
			( pin "C30W1.1"
				( objectStatus "@baseboard_fab2_lib.baseboard_fab2(sch_1):page253_i20:a" )
			)
			( pin "C30W1.2"
				( objectStatus "@baseboard_fab2_lib.baseboard_fab2(sch_1):page253_i20:b" )
			)
			( pin "U25W7.2"
				( objectStatus "@baseboard_fab2_lib.baseboard_fab2(sch_1):page255_i111:a" )
			)
			( pin "U25W7.3"
				( objectStatus "@baseboard_fab2_lib.baseboard_fab2(sch_1):page255_i111:gnd" )
			)
			( pin "U25W7.1"
				( objectStatus "@baseboard_fab2_lib.baseboard_fab2(sch_1):page255_i111:\oe#\" )
			)
			( pin "U25W7.5"
				( objectStatus "@baseboard_fab2_lib.baseboard_fab2(sch_1):page255_i111:vcc" )
			)
			( pin "U25W7.4"
				( objectStatus "@baseboard_fab2_lib.baseboard_fab2(sch_1):page255_i111:y" )
			)
			( pin "U25W8.2"
				( objectStatus "@baseboard_fab2_lib.baseboard_fab2(sch_1):page255_i112:a" )
			)
			( pin "U25W8.3"
				( objectStatus "@baseboard_fab2_lib.baseboard_fab2(sch_1):page255_i112:gnd" )
			)
			( pin "U25W8.1"
				( objectStatus "@baseboard_fab2_lib.baseboard_fab2(sch_1):page255_i112:\oe#\" )
			)
			( pin "U25W8.5"
				( objectStatus "@baseboard_fab2_lib.baseboard_fab2(sch_1):page255_i112:vcc" )
			)
			( pin "U25W8.4"
				( objectStatus "@baseboard_fab2_lib.baseboard_fab2(sch_1):page255_i112:y" )
			)
			( pin "C25W90.1"
				( objectStatus "@baseboard_fab2_lib.baseboard_fab2(sch_1):page255_i118:a" )
			)
			( pin "C25W90.2"
				( objectStatus "@baseboard_fab2_lib.baseboard_fab2(sch_1):page255_i118:b" )
			)
			( pin "D25W8.A"
				( objectStatus "@baseboard_fab2_lib.baseboard_fab2(sch_1):page255_i128:anode" )
			)
			( pin "D25W8.K"
				( objectStatus "@baseboard_fab2_lib.baseboard_fab2(sch_1):page255_i128:cathode" )
			)
			( pin "CR25W1.1"
				( objectStatus "@baseboard_fab2_lib.baseboard_fab2(sch_1):page255_i129:ac0" )
			)
			( pin "CR25W1.2"
				( objectStatus "@baseboard_fab2_lib.baseboard_fab2(sch_1):page255_i129:ac1" )
			)
			( pin "CR25W1.4"
				( objectStatus "@baseboard_fab2_lib.baseboard_fab2(sch_1):page255_i129:ac2" )
			)
			( pin "CR25W1.5"
				( objectStatus "@baseboard_fab2_lib.baseboard_fab2(sch_1):page255_i129:ac3" )
			)
			( pin "CR25W1.3"
				( objectStatus "@baseboard_fab2_lib.baseboard_fab2(sch_1):page255_i129:gnd(0)" )
			)
			( pin "CR25W1.9"
				( objectStatus "@baseboard_fab2_lib.baseboard_fab2(sch_1):page255_i129:out0" )
			)
			( pin "CR25W1.8"
				( objectStatus "@baseboard_fab2_lib.baseboard_fab2(sch_1):page255_i129:out1" )
			)
			( pin "CR25W1.7"
				( objectStatus "@baseboard_fab2_lib.baseboard_fab2(sch_1):page255_i129:out2" )
			)
			( pin "CR25W1.6"
				( objectStatus "@baseboard_fab2_lib.baseboard_fab2(sch_1):page255_i129:out3" )
			)
			( pin "CR25W2.1"
				( objectStatus "@baseboard_fab2_lib.baseboard_fab2(sch_1):page255_i131:ac0" )
			)
			( pin "CR25W2.2"
				( objectStatus "@baseboard_fab2_lib.baseboard_fab2(sch_1):page255_i131:ac1" )
			)
			( pin "CR25W2.4"
				( objectStatus "@baseboard_fab2_lib.baseboard_fab2(sch_1):page255_i131:ac2" )
			)
			( pin "CR25W2.5"
				( objectStatus "@baseboard_fab2_lib.baseboard_fab2(sch_1):page255_i131:ac3" )
			)
			( pin "CR25W2.3"
				( objectStatus "@baseboard_fab2_lib.baseboard_fab2(sch_1):page255_i131:gnd(0)" )
			)
			( pin "CR25W2.9"
				( objectStatus "@baseboard_fab2_lib.baseboard_fab2(sch_1):page255_i131:out0" )
			)
			( pin "CR25W2.8"
				( objectStatus "@baseboard_fab2_lib.baseboard_fab2(sch_1):page255_i131:out1" )
			)
			( pin "CR25W2.7"
				( objectStatus "@baseboard_fab2_lib.baseboard_fab2(sch_1):page255_i131:out2" )
			)
			( pin "CR25W2.6"
				( objectStatus "@baseboard_fab2_lib.baseboard_fab2(sch_1):page255_i131:out3" )
			)
			( pin "C25P80.1"
				( objectStatus "@baseboard_fab2_lib.baseboard_fab2(sch_1):page255_i134:a" )
			)
			( pin "C25P80.2"
				( objectStatus "@baseboard_fab2_lib.baseboard_fab2(sch_1):page255_i134:b" )
			)
			( pin "C1W16.1"
				( objectStatus "@baseboard_fab2_lib.baseboard_fab2(sch_1):page199_i132:a" )
			)
			( pin "C1W16.2"
				( objectStatus "@baseboard_fab2_lib.baseboard_fab2(sch_1):page199_i132:b" )
			)
			( pin "R1W20.1"
				( objectStatus "@baseboard_fab2_lib.baseboard_fab2(sch_1):page199_i134:a" )
			)
			( pin "R1W20.2"
				( objectStatus "@baseboard_fab2_lib.baseboard_fab2(sch_1):page199_i134:b" )
			)
			( pin "R1W21.1"
				( objectStatus "@baseboard_fab2_lib.baseboard_fab2(sch_1):page199_i135:a" )
			)
			( pin "R1W21.2"
				( objectStatus "@baseboard_fab2_lib.baseboard_fab2(sch_1):page199_i135:b" )
			)
			( pin "R9F55.1"
				( objectStatus "@baseboard_fab2_lib.baseboard_fab2(sch_1):page183_i3:a" )
			)
			( pin "R9F55.2"
				( objectStatus "@baseboard_fab2_lib.baseboard_fab2(sch_1):page183_i3:b" )
			)
			( pin "R25W121.1"
				( objectStatus "@baseboard_fab2_lib.baseboard_fab2(sch_1):page145_i163:a" )
			)
			( pin "R25W121.2"
				( objectStatus "@baseboard_fab2_lib.baseboard_fab2(sch_1):page145_i163:b" )
			)
			( pin "R25W122.1"
				( objectStatus "@baseboard_fab2_lib.baseboard_fab2(sch_1):page145_i164:a" )
			)
			( pin "R25W122.2"
				( objectStatus "@baseboard_fab2_lib.baseboard_fab2(sch_1):page145_i164:b" )
			)
			( pin "J2W1.H1"
				( objectStatus "@baseboard_fab2_lib.baseboard_fab2(sch_1):page172_i67:h1" )
			)
			( pin "J2W1.H2"
				( objectStatus "@baseboard_fab2_lib.baseboard_fab2(sch_1):page172_i67:h2" )
			)
			( pin "J2W1.NP1"
				( objectStatus "@baseboard_fab2_lib.baseboard_fab2(sch_1):page172_i67:np1" )
			)
			( pin "J2W1.NP2"
				( objectStatus "@baseboard_fab2_lib.baseboard_fab2(sch_1):page172_i67:np2" )
			)
			( pin "J2W1.P1"
				( objectStatus "@baseboard_fab2_lib.baseboard_fab2(sch_1):page172_i67:p1" )
			)
			( pin "J2W1.P2"
				( objectStatus "@baseboard_fab2_lib.baseboard_fab2(sch_1):page172_i67:p2" )
			)
			( pin "J2W1.P3"
				( objectStatus "@baseboard_fab2_lib.baseboard_fab2(sch_1):page172_i67:p3" )
			)
			( pin "J2W1.P4"
				( objectStatus "@baseboard_fab2_lib.baseboard_fab2(sch_1):page172_i67:p4" )
			)
			( pin "J2W1.P5"
				( objectStatus "@baseboard_fab2_lib.baseboard_fab2(sch_1):page172_i67:p5" )
			)
			( pin "J2W1.P6"
				( objectStatus "@baseboard_fab2_lib.baseboard_fab2(sch_1):page172_i67:p6" )
			)
			( pin "J2W1.S1"
				( objectStatus "@baseboard_fab2_lib.baseboard_fab2(sch_1):page172_i67:s1" )
			)
			( pin "J2W1.S2"
				( objectStatus "@baseboard_fab2_lib.baseboard_fab2(sch_1):page172_i67:s2" )
			)
			( pin "J2W1.S3"
				( objectStatus "@baseboard_fab2_lib.baseboard_fab2(sch_1):page172_i67:s3" )
			)
			( pin "J2W1.S4"
				( objectStatus "@baseboard_fab2_lib.baseboard_fab2(sch_1):page172_i67:s4" )
			)
			( pin "J2W1.S5"
				( objectStatus "@baseboard_fab2_lib.baseboard_fab2(sch_1):page172_i67:s5" )
			)
			( pin "J2W1.S6"
				( objectStatus "@baseboard_fab2_lib.baseboard_fab2(sch_1):page172_i67:s6" )
			)
			( pin "J2W1.S7"
				( objectStatus "@baseboard_fab2_lib.baseboard_fab2(sch_1):page172_i67:s7" )
			)
			( pin "J2W2.H1"
				( objectStatus "@baseboard_fab2_lib.baseboard_fab2(sch_1):page172_i68:h1" )
			)
			( pin "J2W2.H2"
				( objectStatus "@baseboard_fab2_lib.baseboard_fab2(sch_1):page172_i68:h2" )
			)
			( pin "J2W2.NP1"
				( objectStatus "@baseboard_fab2_lib.baseboard_fab2(sch_1):page172_i68:np1" )
			)
			( pin "J2W2.NP2"
				( objectStatus "@baseboard_fab2_lib.baseboard_fab2(sch_1):page172_i68:np2" )
			)
			( pin "J2W2.P1"
				( objectStatus "@baseboard_fab2_lib.baseboard_fab2(sch_1):page172_i68:p1" )
			)
			( pin "J2W2.P2"
				( objectStatus "@baseboard_fab2_lib.baseboard_fab2(sch_1):page172_i68:p2" )
			)
			( pin "J2W2.P3"
				( objectStatus "@baseboard_fab2_lib.baseboard_fab2(sch_1):page172_i68:p3" )
			)
			( pin "J2W2.P4"
				( objectStatus "@baseboard_fab2_lib.baseboard_fab2(sch_1):page172_i68:p4" )
			)
			( pin "J2W2.P5"
				( objectStatus "@baseboard_fab2_lib.baseboard_fab2(sch_1):page172_i68:p5" )
			)
			( pin "J2W2.P6"
				( objectStatus "@baseboard_fab2_lib.baseboard_fab2(sch_1):page172_i68:p6" )
			)
			( pin "J2W2.S1"
				( objectStatus "@baseboard_fab2_lib.baseboard_fab2(sch_1):page172_i68:s1" )
			)
			( pin "J2W2.S2"
				( objectStatus "@baseboard_fab2_lib.baseboard_fab2(sch_1):page172_i68:s2" )
			)
			( pin "J2W2.S3"
				( objectStatus "@baseboard_fab2_lib.baseboard_fab2(sch_1):page172_i68:s3" )
			)
			( pin "J2W2.S4"
				( objectStatus "@baseboard_fab2_lib.baseboard_fab2(sch_1):page172_i68:s4" )
			)
			( pin "J2W2.S5"
				( objectStatus "@baseboard_fab2_lib.baseboard_fab2(sch_1):page172_i68:s5" )
			)
			( pin "J2W2.S6"
				( objectStatus "@baseboard_fab2_lib.baseboard_fab2(sch_1):page172_i68:s6" )
			)
			( pin "J2W2.S7"
				( objectStatus "@baseboard_fab2_lib.baseboard_fab2(sch_1):page172_i68:s7" )
			)
			( pin "R9G2.1"
				( objectStatus "@baseboard_fab2_lib.baseboard_fab2(sch_1):page141_i134:a" )
			)
			( pin "R9G2.2"
				( objectStatus "@baseboard_fab2_lib.baseboard_fab2(sch_1):page141_i134:b" )
			)
			( pin "R9G3.1"
				( objectStatus "@baseboard_fab2_lib.baseboard_fab2(sch_1):page141_i135:a" )
			)
			( pin "R9G3.2"
				( objectStatus "@baseboard_fab2_lib.baseboard_fab2(sch_1):page141_i135:b" )
			)
			( pin "C9G3.1"
				( objectStatus "@baseboard_fab2_lib.baseboard_fab2(sch_1):page141_i138:a" )
			)
			( pin "C9G3.2"
				( objectStatus "@baseboard_fab2_lib.baseboard_fab2(sch_1):page141_i138:b" )
			)
			( pin "C9G1.1"
				( objectStatus "@baseboard_fab2_lib.baseboard_fab2(sch_1):page141_i140:a" )
			)
			( pin "C9G1.2"
				( objectStatus "@baseboard_fab2_lib.baseboard_fab2(sch_1):page141_i140:b" )
			)
			( pin "C9G2.1"
				( objectStatus "@baseboard_fab2_lib.baseboard_fab2(sch_1):page141_i152:a" )
			)
			( pin "C9G2.2"
				( objectStatus "@baseboard_fab2_lib.baseboard_fab2(sch_1):page141_i152:b" )
			)
			( pin "R9G4.1"
				( objectStatus "@baseboard_fab2_lib.baseboard_fab2(sch_1):page141_i156:a" )
			)
			( pin "R9G4.2"
				( objectStatus "@baseboard_fab2_lib.baseboard_fab2(sch_1):page141_i156:b" )
			)
			( pin "R9G1.1"
				( objectStatus "@baseboard_fab2_lib.baseboard_fab2(sch_1):page141_i157:a" )
			)
			( pin "R9G1.2"
				( objectStatus "@baseboard_fab2_lib.baseboard_fab2(sch_1):page141_i157:b" )
			)
			( pin "C9F22.1"
				( objectStatus "@baseboard_fab2_lib.baseboard_fab2(sch_1):page141_i159:a" )
			)
			( pin "C9F22.2"
				( objectStatus "@baseboard_fab2_lib.baseboard_fab2(sch_1):page141_i159:b" )
			)
			( pin "L4E1.2"
				( objectStatus "@baseboard_fab2_lib.baseboard_fab2(sch_1):page202_i109:f" )
			)
			( pin "L4E1.1"
				( objectStatus "@baseboard_fab2_lib.baseboard_fab2(sch_1):page202_i109:s" )
			)
			( pin "L4D1.2"
				( objectStatus "@baseboard_fab2_lib.baseboard_fab2(sch_1):page203_i131:f" )
			)
			( pin "L4D1.1"
				( objectStatus "@baseboard_fab2_lib.baseboard_fab2(sch_1):page203_i131:s" )
			)
			( pin "L1D2.2"
				( objectStatus "@baseboard_fab2_lib.baseboard_fab2(sch_1):page208_i116:f" )
			)
			( pin "L1D2.1"
				( objectStatus "@baseboard_fab2_lib.baseboard_fab2(sch_1):page208_i116:s" )
			)
			( pin "L1D1.2"
				( objectStatus "@baseboard_fab2_lib.baseboard_fab2(sch_1):page208_i117:f" )
			)
			( pin "L1D1.1"
				( objectStatus "@baseboard_fab2_lib.baseboard_fab2(sch_1):page208_i117:s" )
			)
			( pin "C4A14.1"
				( objectStatus "@baseboard_fab2_lib.baseboard_fab2(sch_1):page230_i36:a" )
			)
			( pin "C4A14.2"
				( objectStatus "@baseboard_fab2_lib.baseboard_fab2(sch_1):page230_i36:b" )
			)
			( pin "C6L5.1"
				( objectStatus "@baseboard_fab2_lib.baseboard_fab2(sch_1):page230_i35:a" )
			)
			( pin "C6L5.2"
				( objectStatus "@baseboard_fab2_lib.baseboard_fab2(sch_1):page230_i35:b" )
			)
			( pin "R4A4.1"
				( objectStatus "@baseboard_fab2_lib.baseboard_fab2(sch_1):page230_i32:a" )
			)
			( pin "R4A4.2"
				( objectStatus "@baseboard_fab2_lib.baseboard_fab2(sch_1):page230_i32:b" )
			)
			( pin "C8M12.1"
				( objectStatus "@baseboard_fab2_lib.baseboard_fab2(sch_1):page230_i24:a" )
			)
			( pin "C8M12.2"
				( objectStatus "@baseboard_fab2_lib.baseboard_fab2(sch_1):page230_i24:b" )
			)
			( pin "C4A3.1"
				( objectStatus "@baseboard_fab2_lib.baseboard_fab2(sch_1):page230_i23:a" )
			)
			( pin "C4A3.2"
				( objectStatus "@baseboard_fab2_lib.baseboard_fab2(sch_1):page230_i23:b" )
			)
			( pin "J25W1.1"
				( objectStatus "@baseboard_fab2_lib.baseboard_fab2(sch_1):page255_i136:\1\" )
			)
			( pin "J25W1.2"
				( objectStatus "@baseboard_fab2_lib.baseboard_fab2(sch_1):page255_i136:\2\" )
			)
			( pin "J25W1.3"
				( objectStatus "@baseboard_fab2_lib.baseboard_fab2(sch_1):page255_i136:\3\" )
			)
			( pin "J25W1.4"
				( objectStatus "@baseboard_fab2_lib.baseboard_fab2(sch_1):page255_i136:\4\" )
			)
			( pin "J25W1.5"
				( objectStatus "@baseboard_fab2_lib.baseboard_fab2(sch_1):page255_i136:\5\" )
			)
			( pin "J25W1.6"
				( objectStatus "@baseboard_fab2_lib.baseboard_fab2(sch_1):page255_i136:\6\" )
			)
			( pin "J25W1.7"
				( objectStatus "@baseboard_fab2_lib.baseboard_fab2(sch_1):page255_i136:\7\" )
			)
			( pin "J25W1.8"
				( objectStatus "@baseboard_fab2_lib.baseboard_fab2(sch_1):page255_i136:\8\" )
			)
			( pin "J25W1.9"
				( objectStatus "@baseboard_fab2_lib.baseboard_fab2(sch_1):page255_i136:\9\" )
			)
			( pin "J25W1.10"
				( objectStatus "@baseboard_fab2_lib.baseboard_fab2(sch_1):page255_i136:\10\" )
			)
			( pin "J25W1.11"
				( objectStatus "@baseboard_fab2_lib.baseboard_fab2(sch_1):page255_i136:\11\" )
			)
			( pin "J25W1.12"
				( objectStatus "@baseboard_fab2_lib.baseboard_fab2(sch_1):page255_i136:\12\" )
			)
			( pin "J25W1.13"
				( objectStatus "@baseboard_fab2_lib.baseboard_fab2(sch_1):page255_i136:\13\" )
			)
			( pin "J25W1.PTH1"
				( objectStatus "@baseboard_fab2_lib.baseboard_fab2(sch_1):page255_i136:pth1" )
			)
			( pin "J25W1.PTH2"
				( objectStatus "@baseboard_fab2_lib.baseboard_fab2(sch_1):page255_i136:pth2" )
			)
			( pin "F8B1.1"
				( objectStatus "@baseboard_fab2_lib.baseboard_fab2(sch_1):page172_i71:\1\" )
			)
			( pin "F8B1.2"
				( objectStatus "@baseboard_fab2_lib.baseboard_fab2(sch_1):page172_i71:\2\" )
			)
			( pin "C8F14.1"
				( objectStatus "@baseboard_fab2_lib.baseboard_fab2(sch_1):page240_i189:\1\" )
			)
			( pin "C8F14.2"
				( objectStatus "@baseboard_fab2_lib.baseboard_fab2(sch_1):page240_i189:\2\" )
			)
			( pin "R25W143.1"
				( objectStatus "@baseboard_fab2_lib.baseboard_fab2(sch_1):page147_i159:a" )
			)
			( pin "R25W143.2"
				( objectStatus "@baseboard_fab2_lib.baseboard_fab2(sch_1):page147_i159:b" )
			)
			( pin "L8F1.1"
				( objectStatus "@baseboard_fab2_lib.baseboard_fab2(sch_1):page240_i188:\1\" )
			)
			( pin "L8F1.2"
				( objectStatus "@baseboard_fab2_lib.baseboard_fab2(sch_1):page240_i188:\2\" )
			)
			( pin "C8F8.1"
				( objectStatus "@baseboard_fab2_lib.baseboard_fab2(sch_1):page240_i190:\1\" )
			)
			( pin "C8F8.2"
				( objectStatus "@baseboard_fab2_lib.baseboard_fab2(sch_1):page240_i190:\2\" )
			)
			( pin "J8F1.1"
				( objectStatus "@baseboard_fab2_lib.baseboard_fab2(sch_1):page185_i143:\1\" )
			)
			( pin "J8F1.2"
				( objectStatus "@baseboard_fab2_lib.baseboard_fab2(sch_1):page185_i143:\2\" )
			)
			( pin "J8F1.3"
				( objectStatus "@baseboard_fab2_lib.baseboard_fab2(sch_1):page185_i143:\3\" )
			)
			( pin "J8F1.4"
				( objectStatus "@baseboard_fab2_lib.baseboard_fab2(sch_1):page185_i143:\4\" )
			)
			( pin "J8F1.5"
				( objectStatus "@baseboard_fab2_lib.baseboard_fab2(sch_1):page185_i143:\5\" )
			)
			( pin "J8F1.6"
				( objectStatus "@baseboard_fab2_lib.baseboard_fab2(sch_1):page185_i143:\6\" )
			)
			( pin "J8F1.7"
				( objectStatus "@baseboard_fab2_lib.baseboard_fab2(sch_1):page185_i143:\7\" )
			)
			( pin "J8F1.8"
				( objectStatus "@baseboard_fab2_lib.baseboard_fab2(sch_1):page185_i143:\8\" )
			)
			( pin "J8F1.9"
				( objectStatus "@baseboard_fab2_lib.baseboard_fab2(sch_1):page185_i143:\9\" )
			)
			( pin "J8F1.10"
				( objectStatus "@baseboard_fab2_lib.baseboard_fab2(sch_1):page185_i143:\10\" )
			)
			( pin "J8F1.11"
				( objectStatus "@baseboard_fab2_lib.baseboard_fab2(sch_1):page185_i143:\11\" )
			)
			( pin "J8F1.12"
				( objectStatus "@baseboard_fab2_lib.baseboard_fab2(sch_1):page185_i143:\12\" )
			)
			( pin "J8F1.13"
				( objectStatus "@baseboard_fab2_lib.baseboard_fab2(sch_1):page185_i143:\13\" )
			)
			( pin "J8F1.14"
				( objectStatus "@baseboard_fab2_lib.baseboard_fab2(sch_1):page185_i143:\14\" )
			)
			( pin "J8F1.15"
				( objectStatus "@baseboard_fab2_lib.baseboard_fab2(sch_1):page185_i143:\15\" )
			)
			( pin "J8F1.16"
				( objectStatus "@baseboard_fab2_lib.baseboard_fab2(sch_1):page185_i143:\16\" )
			)
			( pin "J8F1.17"
				( objectStatus "@baseboard_fab2_lib.baseboard_fab2(sch_1):page185_i143:\17\" )
			)
			( pin "J8F1.18"
				( objectStatus "@baseboard_fab2_lib.baseboard_fab2(sch_1):page185_i143:\18\" )
			)
			( pin "J8F1.19"
				( objectStatus "@baseboard_fab2_lib.baseboard_fab2(sch_1):page185_i143:\19\" )
			)
			( pin "J8F1.20"
				( objectStatus "@baseboard_fab2_lib.baseboard_fab2(sch_1):page185_i143:\20\" )
			)
			( pin "J8F1.21"
				( objectStatus "@baseboard_fab2_lib.baseboard_fab2(sch_1):page185_i143:\21\" )
			)
			( pin "J8F1.22"
				( objectStatus "@baseboard_fab2_lib.baseboard_fab2(sch_1):page185_i143:\22\" )
			)
			( pin "J8F1.23"
				( objectStatus "@baseboard_fab2_lib.baseboard_fab2(sch_1):page185_i143:\23\" )
			)
			( pin "J8F1.24"
				( objectStatus "@baseboard_fab2_lib.baseboard_fab2(sch_1):page185_i143:\24\" )
			)
			( pin "J8F1.25"
				( objectStatus "@baseboard_fab2_lib.baseboard_fab2(sch_1):page185_i143:\25\" )
			)
			( pin "J8F1.26"
				( objectStatus "@baseboard_fab2_lib.baseboard_fab2(sch_1):page185_i143:\26\" )
			)
			( pin "J8F1.27"
				( objectStatus "@baseboard_fab2_lib.baseboard_fab2(sch_1):page185_i143:\27\" )
			)
			( pin "J8F1.28"
				( objectStatus "@baseboard_fab2_lib.baseboard_fab2(sch_1):page185_i143:\28\" )
			)
			( pin "J8F1.29"
				( objectStatus "@baseboard_fab2_lib.baseboard_fab2(sch_1):page185_i143:\29\" )
			)
			( pin "J8F1.30"
				( objectStatus "@baseboard_fab2_lib.baseboard_fab2(sch_1):page185_i143:\30\" )
			)
			( pin "J8F1.31"
				( objectStatus "@baseboard_fab2_lib.baseboard_fab2(sch_1):page185_i143:\31\" )
			)
			( pin "J8F1.32"
				( objectStatus "@baseboard_fab2_lib.baseboard_fab2(sch_1):page185_i143:\32\" )
			)
			( pin "J8F1.33"
				( objectStatus "@baseboard_fab2_lib.baseboard_fab2(sch_1):page185_i143:\33\" )
			)
			( pin "J8F1.34"
				( objectStatus "@baseboard_fab2_lib.baseboard_fab2(sch_1):page185_i143:\34\" )
			)
			( pin "J8F1.35"
				( objectStatus "@baseboard_fab2_lib.baseboard_fab2(sch_1):page185_i143:\35\" )
			)
			( pin "J8F1.36"
				( objectStatus "@baseboard_fab2_lib.baseboard_fab2(sch_1):page185_i143:\36\" )
			)
			( pin "J8F1.37"
				( objectStatus "@baseboard_fab2_lib.baseboard_fab2(sch_1):page185_i143:\37\" )
			)
			( pin "J8F1.38"
				( objectStatus "@baseboard_fab2_lib.baseboard_fab2(sch_1):page185_i143:\38\" )
			)
			( pin "J8F1.39"
				( objectStatus "@baseboard_fab2_lib.baseboard_fab2(sch_1):page185_i143:\39\" )
			)
			( pin "J8F1.40"
				( objectStatus "@baseboard_fab2_lib.baseboard_fab2(sch_1):page185_i143:\40\" )
			)
			( pin "J8F1.41"
				( objectStatus "@baseboard_fab2_lib.baseboard_fab2(sch_1):page185_i143:\41\" )
			)
			( pin "J8F1.42"
				( objectStatus "@baseboard_fab2_lib.baseboard_fab2(sch_1):page185_i143:\42\" )
			)
			( pin "J8F1.43"
				( objectStatus "@baseboard_fab2_lib.baseboard_fab2(sch_1):page185_i143:\43\" )
			)
			( pin "J8F1.44"
				( objectStatus "@baseboard_fab2_lib.baseboard_fab2(sch_1):page185_i143:\44\" )
			)
			( pin "J8F1.45"
				( objectStatus "@baseboard_fab2_lib.baseboard_fab2(sch_1):page185_i143:\45\" )
			)
			( pin "J8F1.46"
				( objectStatus "@baseboard_fab2_lib.baseboard_fab2(sch_1):page185_i143:\46\" )
			)
			( pin "J8F1.47"
				( objectStatus "@baseboard_fab2_lib.baseboard_fab2(sch_1):page185_i143:\47\" )
			)
			( pin "J8F1.48"
				( objectStatus "@baseboard_fab2_lib.baseboard_fab2(sch_1):page185_i143:\48\" )
			)
			( pin "J8F1.49"
				( objectStatus "@baseboard_fab2_lib.baseboard_fab2(sch_1):page185_i143:\49\" )
			)
			( pin "J8F1.50"
				( objectStatus "@baseboard_fab2_lib.baseboard_fab2(sch_1):page185_i143:\50\" )
			)
			( pin "J8F1.51"
				( objectStatus "@baseboard_fab2_lib.baseboard_fab2(sch_1):page185_i143:\51\" )
			)
			( pin "J8F1.52"
				( objectStatus "@baseboard_fab2_lib.baseboard_fab2(sch_1):page185_i143:\52\" )
			)
			( pin "J8F1.53"
				( objectStatus "@baseboard_fab2_lib.baseboard_fab2(sch_1):page185_i143:\53\" )
			)
			( pin "J8F1.54"
				( objectStatus "@baseboard_fab2_lib.baseboard_fab2(sch_1):page185_i143:\54\" )
			)
			( pin "J8F1.55"
				( objectStatus "@baseboard_fab2_lib.baseboard_fab2(sch_1):page185_i143:\55\" )
			)
			( pin "J8F1.56"
				( objectStatus "@baseboard_fab2_lib.baseboard_fab2(sch_1):page185_i143:\56\" )
			)
			( pin "J8F1.57"
				( objectStatus "@baseboard_fab2_lib.baseboard_fab2(sch_1):page185_i143:\57\" )
			)
			( pin "J8F1.58"
				( objectStatus "@baseboard_fab2_lib.baseboard_fab2(sch_1):page185_i143:\58\" )
			)
			( pin "J8F1.67"
				( objectStatus "@baseboard_fab2_lib.baseboard_fab2(sch_1):page185_i143:\67\" )
			)
			( pin "J8F1.68"
				( objectStatus "@baseboard_fab2_lib.baseboard_fab2(sch_1):page185_i143:\68\" )
			)
			( pin "J8F1.69"
				( objectStatus "@baseboard_fab2_lib.baseboard_fab2(sch_1):page185_i143:\69\" )
			)
			( pin "J8F1.70"
				( objectStatus "@baseboard_fab2_lib.baseboard_fab2(sch_1):page185_i143:\70\" )
			)
			( pin "J8F1.71"
				( objectStatus "@baseboard_fab2_lib.baseboard_fab2(sch_1):page185_i143:\71\" )
			)
			( pin "J8F1.72"
				( objectStatus "@baseboard_fab2_lib.baseboard_fab2(sch_1):page185_i143:\72\" )
			)
			( pin "J8F1.73"
				( objectStatus "@baseboard_fab2_lib.baseboard_fab2(sch_1):page185_i143:\73\" )
			)
			( pin "J8F1.74"
				( objectStatus "@baseboard_fab2_lib.baseboard_fab2(sch_1):page185_i143:\74\" )
			)
			( pin "J8F1.75"
				( objectStatus "@baseboard_fab2_lib.baseboard_fab2(sch_1):page185_i143:\75\" )
			)
			( pin "J8F1.76"
				( objectStatus "@baseboard_fab2_lib.baseboard_fab2(sch_1):page185_i143:\76\" )
			)
			( pin "J8F1.77"
				( objectStatus "@baseboard_fab2_lib.baseboard_fab2(sch_1):page185_i143:\77\" )
			)
			( pin "J8F1.NP1"
				( objectStatus "@baseboard_fab2_lib.baseboard_fab2(sch_1):page185_i143:np1" )
			)
			( pin "J8F1.NP2"
				( objectStatus "@baseboard_fab2_lib.baseboard_fab2(sch_1):page185_i143:np2" )
			)
			( pin "C2T11.1"
				( objectStatus "@baseboard_fab2_lib.baseboard_fab2(sch_1):page185_i167:a" )
			)
			( pin "C2T11.2"
				( objectStatus "@baseboard_fab2_lib.baseboard_fab2(sch_1):page185_i167:b" )
			)
			( pin "C2T10.1"
				( objectStatus "@baseboard_fab2_lib.baseboard_fab2(sch_1):page185_i168:a" )
			)
			( pin "C2T10.2"
				( objectStatus "@baseboard_fab2_lib.baseboard_fab2(sch_1):page185_i168:b" )
			)
			( pin "R1W22.1"
				( objectStatus "@baseboard_fab2_lib.baseboard_fab2(sch_1):page101_i134:a" )
			)
			( pin "R1W22.2"
				( objectStatus "@baseboard_fab2_lib.baseboard_fab2(sch_1):page101_i134:b" )
			)
			( pin "R1W23.1"
				( objectStatus "@baseboard_fab2_lib.baseboard_fab2(sch_1):page101_i135:a" )
			)
			( pin "R1W23.2"
				( objectStatus "@baseboard_fab2_lib.baseboard_fab2(sch_1):page101_i135:b" )
			)
			( pin "R1W24.1"
				( objectStatus "@baseboard_fab2_lib.baseboard_fab2(sch_1):page101_i138:a" )
			)
			( pin "R1W24.2"
				( objectStatus "@baseboard_fab2_lib.baseboard_fab2(sch_1):page101_i138:b" )
			)
			( pin "C1W17.1"
				( objectStatus "@baseboard_fab2_lib.baseboard_fab2(sch_1):page101_i139:a" )
			)
			( pin "C1W17.2"
				( objectStatus "@baseboard_fab2_lib.baseboard_fab2(sch_1):page101_i139:b" )
			)
			( pin "R1W25.1"
				( objectStatus "@baseboard_fab2_lib.baseboard_fab2(sch_1):page101_i140:a" )
			)
			( pin "R1W25.2"
				( objectStatus "@baseboard_fab2_lib.baseboard_fab2(sch_1):page101_i140:b" )
			)
			( pin "CR10W3.2"
				( objectStatus "@baseboard_fab2_lib.baseboard_fab2(sch_1):page251_i26:a" )
			)
			( pin "CR10W3.1"
				( objectStatus "@baseboard_fab2_lib.baseboard_fab2(sch_1):page251_i26:c" )
			)
			( pin "R8F27.1"
				( objectStatus "@baseboard_fab2_lib.baseboard_fab2(sch_1):page101_i142:a" )
			)
			( pin "R8F27.2"
				( objectStatus "@baseboard_fab2_lib.baseboard_fab2(sch_1):page101_i142:b" )
			)
			( pin "R8G25.1"
				( objectStatus "@baseboard_fab2_lib.baseboard_fab2(sch_1):page101_i144:a" )
			)
			( pin "R8G25.2"
				( objectStatus "@baseboard_fab2_lib.baseboard_fab2(sch_1):page101_i144:b" )
			)
			( pin "R8G1.1"
				( objectStatus "@baseboard_fab2_lib.baseboard_fab2(sch_1):page101_i145:a" )
			)
			( pin "R8G1.2"
				( objectStatus "@baseboard_fab2_lib.baseboard_fab2(sch_1):page101_i145:b" )
			)
			( pin "R25W148.1"
				( objectStatus "@baseboard_fab2_lib.baseboard_fab2(sch_1):page150_i216:a" )
			)
			( pin "R25W148.2"
				( objectStatus "@baseboard_fab2_lib.baseboard_fab2(sch_1):page150_i216:b" )
			)
			( pin "R1W26.1"
				( objectStatus "@baseboard_fab2_lib.baseboard_fab2(sch_1):page190_i349:a" )
			)
			( pin "R1W26.2"
				( objectStatus "@baseboard_fab2_lib.baseboard_fab2(sch_1):page190_i349:b" )
			)
			( pin "R4E4.1"
				( objectStatus "@baseboard_fab2_lib.baseboard_fab2(sch_1):page201_i187:a" )
			)
			( pin "R4E4.2"
				( objectStatus "@baseboard_fab2_lib.baseboard_fab2(sch_1):page201_i187:b" )
			)
			( pin "R8W2.1"
				( objectStatus "@baseboard_fab2_lib.baseboard_fab2(sch_1):page235_i247:a" )
			)
			( pin "R8W2.2"
				( objectStatus "@baseboard_fab2_lib.baseboard_fab2(sch_1):page235_i247:b" )
			)
			( pin "R8W3.1"
				( objectStatus "@baseboard_fab2_lib.baseboard_fab2(sch_1):page235_i248:a" )
			)
			( pin "R8W3.2"
				( objectStatus "@baseboard_fab2_lib.baseboard_fab2(sch_1):page235_i248:b" )
			)
			( pin "R7F8.1"
				( objectStatus "@baseboard_fab2_lib.baseboard_fab2(sch_1):page231_i229:a" )
			)
			( pin "R7F8.2"
				( objectStatus "@baseboard_fab2_lib.baseboard_fab2(sch_1):page231_i229:b" )
			)
			( pin "R1W27.1"
				( objectStatus "@baseboard_fab2_lib.baseboard_fab2(sch_1):page190_i351:a" )
			)
			( pin "R1W27.2"
				( objectStatus "@baseboard_fab2_lib.baseboard_fab2(sch_1):page190_i351:b" )
			)
			( pin "R25W144.1"
				( objectStatus "@baseboard_fab2_lib.baseboard_fab2(sch_1):page145_i173:a" )
			)
			( pin "R25W144.2"
				( objectStatus "@baseboard_fab2_lib.baseboard_fab2(sch_1):page145_i173:b" )
			)
			( pin "R1W28.1"
				( objectStatus "@baseboard_fab2_lib.baseboard_fab2(sch_1):page191_i197:a" )
			)
			( pin "R1W28.2"
				( objectStatus "@baseboard_fab2_lib.baseboard_fab2(sch_1):page191_i197:b" )
			)
			( pin "R25W145.1"
				( objectStatus "@baseboard_fab2_lib.baseboard_fab2(sch_1):page145_i175:a" )
			)
			( pin "R25W145.2"
				( objectStatus "@baseboard_fab2_lib.baseboard_fab2(sch_1):page145_i175:b" )
			)
			( pin "R1W29.1"
				( objectStatus "@baseboard_fab2_lib.baseboard_fab2(sch_1):page191_i198:a" )
			)
			( pin "R1W29.2"
				( objectStatus "@baseboard_fab2_lib.baseboard_fab2(sch_1):page191_i198:b" )
			)
			( pin "R1W30.1"
				( objectStatus "@baseboard_fab2_lib.baseboard_fab2(sch_1):page118_i168:a" )
			)
			( pin "R1W30.2"
				( objectStatus "@baseboard_fab2_lib.baseboard_fab2(sch_1):page118_i168:b" )
			)
			( pin "R25W105.1"
				( objectStatus "@baseboard_fab2_lib.baseboard_fab2(sch_1):page150_i196:a" )
			)
			( pin "R25W105.2"
				( objectStatus "@baseboard_fab2_lib.baseboard_fab2(sch_1):page150_i196:b" )
			)
			( pin "R8F13.1"
				( objectStatus "@baseboard_fab2_lib.baseboard_fab2(sch_1):page162_i35:a" )
			)
			( pin "R8F13.2"
				( objectStatus "@baseboard_fab2_lib.baseboard_fab2(sch_1):page162_i35:b" )
			)
			( pin "R25W146.1"
				( objectStatus "@baseboard_fab2_lib.baseboard_fab2(sch_1):page150_i199:a" )
			)
			( pin "R25W146.2"
				( objectStatus "@baseboard_fab2_lib.baseboard_fab2(sch_1):page150_i199:b" )
			)
			( pin "R25W98.1"
				( objectStatus "@baseboard_fab2_lib.baseboard_fab2(sch_1):page150_i209:a" )
			)
			( pin "R25W98.2"
				( objectStatus "@baseboard_fab2_lib.baseboard_fab2(sch_1):page150_i209:b" )
			)
			( pin "R25W99.1"
				( objectStatus "@baseboard_fab2_lib.baseboard_fab2(sch_1):page150_i210:a" )
			)
			( pin "R25W99.2"
				( objectStatus "@baseboard_fab2_lib.baseboard_fab2(sch_1):page150_i210:b" )
			)
			( pin "R25W100.1"
				( objectStatus "@baseboard_fab2_lib.baseboard_fab2(sch_1):page150_i211:a" )
			)
			( pin "R25W100.2"
				( objectStatus "@baseboard_fab2_lib.baseboard_fab2(sch_1):page150_i211:b" )
			)
			( pin "R25W140.1"
				( objectStatus "@baseboard_fab2_lib.baseboard_fab2(sch_1):page144_i148:a" )
			)
			( pin "R25W140.2"
				( objectStatus "@baseboard_fab2_lib.baseboard_fab2(sch_1):page144_i148:b" )
			)
			( pin "R25W103.1"
				( objectStatus "@baseboard_fab2_lib.baseboard_fab2(sch_1):page150_i214:a" )
			)
			( pin "R25W103.2"
				( objectStatus "@baseboard_fab2_lib.baseboard_fab2(sch_1):page150_i214:b" )
			)
			( pin "R25W104.1"
				( objectStatus "@baseboard_fab2_lib.baseboard_fab2(sch_1):page150_i215:a" )
			)
			( pin "R25W104.2"
				( objectStatus "@baseboard_fab2_lib.baseboard_fab2(sch_1):page150_i215:b" )
			)
			( pin "R25W114.1"
				( objectStatus "@baseboard_fab2_lib.baseboard_fab2(sch_1):page150_i218:a" )
			)
			( pin "R25W114.2"
				( objectStatus "@baseboard_fab2_lib.baseboard_fab2(sch_1):page150_i218:b" )
			)
			( pin "R25W149.1"
				( objectStatus "@baseboard_fab2_lib.baseboard_fab2(sch_1):page150_i219:a" )
			)
			( pin "R25W149.2"
				( objectStatus "@baseboard_fab2_lib.baseboard_fab2(sch_1):page150_i219:b" )
			)
			( pin "R9P28.1"
				( objectStatus "@baseboard_fab2_lib.baseboard_fab2(sch_1):page199_i138:a" )
			)
			( pin "R9P28.2"
				( objectStatus "@baseboard_fab2_lib.baseboard_fab2(sch_1):page199_i138:b" )
			)
			( pin "R25W150.1"
				( objectStatus "@baseboard_fab2_lib.baseboard_fab2(sch_1):page150_i229:a" )
			)
			( pin "R25W150.2"
				( objectStatus "@baseboard_fab2_lib.baseboard_fab2(sch_1):page150_i229:b" )
			)
			( pin "R25W110.1"
				( objectStatus "@baseboard_fab2_lib.baseboard_fab2(sch_1):page150_i233:a" )
			)
			( pin "R25W110.2"
				( objectStatus "@baseboard_fab2_lib.baseboard_fab2(sch_1):page150_i233:b" )
			)
			( pin "R25W152.1"
				( objectStatus "@baseboard_fab2_lib.baseboard_fab2(sch_1):page150_i234:a" )
			)
			( pin "R25W152.2"
				( objectStatus "@baseboard_fab2_lib.baseboard_fab2(sch_1):page150_i234:b" )
			)
			( pin "R25W109.1"
				( objectStatus "@baseboard_fab2_lib.baseboard_fab2(sch_1):page150_i236:a" )
			)
			( pin "R25W109.2"
				( objectStatus "@baseboard_fab2_lib.baseboard_fab2(sch_1):page150_i236:b" )
			)
			( pin "R25W119.1"
				( objectStatus "@baseboard_fab2_lib.baseboard_fab2(sch_1):page151_i210:a" )
			)
			( pin "R25W119.2"
				( objectStatus "@baseboard_fab2_lib.baseboard_fab2(sch_1):page151_i210:b" )
			)
			( pin "U25W9.2"
				( objectStatus "@baseboard_fab2_lib.baseboard_fab2(sch_1):page157_i394:a" )
			)
			( pin "U25W9.4"
				( objectStatus "@baseboard_fab2_lib.baseboard_fab2(sch_1):page157_i394:y" )
			)
			( pin "R25W153.1"
				( objectStatus "@baseboard_fab2_lib.baseboard_fab2(sch_1):page157_i396:a" )
			)
			( pin "R25W153.2"
				( objectStatus "@baseboard_fab2_lib.baseboard_fab2(sch_1):page157_i396:b" )
			)
			( pin "R8B24.1"
				( objectStatus "@baseboard_fab2_lib.baseboard_fab2(sch_1):page138_i186:a" )
			)
			( pin "R8B24.2"
				( objectStatus "@baseboard_fab2_lib.baseboard_fab2(sch_1):page138_i186:b" )
			)
			( pin "R8B26.1"
				( objectStatus "@baseboard_fab2_lib.baseboard_fab2(sch_1):page138_i187:a" )
			)
			( pin "R8B26.2"
				( objectStatus "@baseboard_fab2_lib.baseboard_fab2(sch_1):page138_i187:b" )
			)
			( pin "J1E1.1_1"
				( objectStatus "@baseboard_fab2_lib.baseboard_fab2(sch_1):page195_i114:\1_1\" )
			)
			( pin "J1E1.1_2"
				( objectStatus "@baseboard_fab2_lib.baseboard_fab2(sch_1):page195_i114:\1_2\" )
			)
			( pin "J1E1.1_3"
				( objectStatus "@baseboard_fab2_lib.baseboard_fab2(sch_1):page195_i114:\1_3\" )
			)
			( pin "J1E1.2_1"
				( objectStatus "@baseboard_fab2_lib.baseboard_fab2(sch_1):page195_i114:\2_1\" )
			)
			( pin "J1E1.2_2"
				( objectStatus "@baseboard_fab2_lib.baseboard_fab2(sch_1):page195_i114:\2_2\" )
			)
			( pin "J1E1.2_3"
				( objectStatus "@baseboard_fab2_lib.baseboard_fab2(sch_1):page195_i114:\2_3\" )
			)
			( pin "J1E1.3_1"
				( objectStatus "@baseboard_fab2_lib.baseboard_fab2(sch_1):page195_i114:\3_1\" )
			)
			( pin "J1E1.3_2"
				( objectStatus "@baseboard_fab2_lib.baseboard_fab2(sch_1):page195_i114:\3_2\" )
			)
			( pin "J1E1.3_3"
				( objectStatus "@baseboard_fab2_lib.baseboard_fab2(sch_1):page195_i114:\3_3\" )
			)
			( pin "J1E1.4_1"
				( objectStatus "@baseboard_fab2_lib.baseboard_fab2(sch_1):page195_i114:\4_1\" )
			)
			( pin "J1E1.4_2"
				( objectStatus "@baseboard_fab2_lib.baseboard_fab2(sch_1):page195_i114:\4_2\" )
			)
			( pin "J1E1.4_3"
				( objectStatus "@baseboard_fab2_lib.baseboard_fab2(sch_1):page195_i114:\4_3\" )
			)
			( pin "J1E1.NP1"
				( objectStatus "@baseboard_fab2_lib.baseboard_fab2(sch_1):page195_i114:np1" )
			)
			( pin "J1D1.1_1"
				( objectStatus "@baseboard_fab2_lib.baseboard_fab2(sch_1):page195_i115:\1_1\" )
			)
			( pin "J1D1.1_2"
				( objectStatus "@baseboard_fab2_lib.baseboard_fab2(sch_1):page195_i115:\1_2\" )
			)
			( pin "J1D1.1_3"
				( objectStatus "@baseboard_fab2_lib.baseboard_fab2(sch_1):page195_i115:\1_3\" )
			)
			( pin "J1D1.2_1"
				( objectStatus "@baseboard_fab2_lib.baseboard_fab2(sch_1):page195_i115:\2_1\" )
			)
			( pin "J1D1.2_2"
				( objectStatus "@baseboard_fab2_lib.baseboard_fab2(sch_1):page195_i115:\2_2\" )
			)
			( pin "J1D1.2_3"
				( objectStatus "@baseboard_fab2_lib.baseboard_fab2(sch_1):page195_i115:\2_3\" )
			)
			( pin "J1D1.3_1"
				( objectStatus "@baseboard_fab2_lib.baseboard_fab2(sch_1):page195_i115:\3_1\" )
			)
			( pin "J1D1.3_2"
				( objectStatus "@baseboard_fab2_lib.baseboard_fab2(sch_1):page195_i115:\3_2\" )
			)
			( pin "J1D1.3_3"
				( objectStatus "@baseboard_fab2_lib.baseboard_fab2(sch_1):page195_i115:\3_3\" )
			)
			( pin "J1D1.4_1"
				( objectStatus "@baseboard_fab2_lib.baseboard_fab2(sch_1):page195_i115:\4_1\" )
			)
			( pin "J1D1.4_2"
				( objectStatus "@baseboard_fab2_lib.baseboard_fab2(sch_1):page195_i115:\4_2\" )
			)
			( pin "J1D1.4_3"
				( objectStatus "@baseboard_fab2_lib.baseboard_fab2(sch_1):page195_i115:\4_3\" )
			)
			( pin "J1D1.NP1"
				( objectStatus "@baseboard_fab2_lib.baseboard_fab2(sch_1):page195_i115:np1" )
			)
			( pin "J30W1.A5"
				( objectStatus "@baseboard_fab2_lib.baseboard_fab2(sch_1):page253_i26:cc1" )
			)
			( pin "J30W1.B5"
				( objectStatus "@baseboard_fab2_lib.baseboard_fab2(sch_1):page253_i26:cc2" )
			)
			( pin "J30W1.A7"
				( objectStatus "@baseboard_fab2_lib.baseboard_fab2(sch_1):page253_i26:dn1" )
			)
			( pin "J30W1.B7"
				( objectStatus "@baseboard_fab2_lib.baseboard_fab2(sch_1):page253_i26:dn2" )
			)
			( pin "J30W1.A6"
				( objectStatus "@baseboard_fab2_lib.baseboard_fab2(sch_1):page253_i26:dp1" )
			)
			( pin "J30W1.B6"
				( objectStatus "@baseboard_fab2_lib.baseboard_fab2(sch_1):page253_i26:dp2" )
			)
			( pin "J30W1.A1"
				( objectStatus "@baseboard_fab2_lib.baseboard_fab2(sch_1):page253_i26:gnd(0)" )
			)
			( pin "J30W1.A12"
				( objectStatus "@baseboard_fab2_lib.baseboard_fab2(sch_1):page253_i26:gnd(1)" )
			)
			( pin "J30W1.B1"
				( objectStatus "@baseboard_fab2_lib.baseboard_fab2(sch_1):page253_i26:gnd(2)" )
			)
			( pin "J30W1.B12"
				( objectStatus "@baseboard_fab2_lib.baseboard_fab2(sch_1):page253_i26:gnd(3)" )
			)
			( pin "J30W1.NP1"
				( objectStatus "@baseboard_fab2_lib.baseboard_fab2(sch_1):page253_i26:np1" )
			)
			( pin "J30W1.NP2"
				( objectStatus "@baseboard_fab2_lib.baseboard_fab2(sch_1):page253_i26:np2" )
			)
			( pin "J30W1.PTH1"
				( objectStatus "@baseboard_fab2_lib.baseboard_fab2(sch_1):page253_i26:pth1" )
			)
			( pin "J30W1.PTH2"
				( objectStatus "@baseboard_fab2_lib.baseboard_fab2(sch_1):page253_i26:pth2" )
			)
			( pin "J30W1.PTH3"
				( objectStatus "@baseboard_fab2_lib.baseboard_fab2(sch_1):page253_i26:pth3" )
			)
			( pin "J30W1.PTH4"
				( objectStatus "@baseboard_fab2_lib.baseboard_fab2(sch_1):page253_i26:pth4" )
			)
			( pin "J30W1.PTH5"
				( objectStatus "@baseboard_fab2_lib.baseboard_fab2(sch_1):page253_i26:pth5" )
			)
			( pin "J30W1.PTH6"
				( objectStatus "@baseboard_fab2_lib.baseboard_fab2(sch_1):page253_i26:pth6" )
			)
			( pin "J30W1.PTH7"
				( objectStatus "@baseboard_fab2_lib.baseboard_fab2(sch_1):page253_i26:pth7" )
			)
			( pin "J30W1.PTH8"
				( objectStatus "@baseboard_fab2_lib.baseboard_fab2(sch_1):page253_i26:pth8" )
			)
			( pin "J30W1.A8"
				( objectStatus "@baseboard_fab2_lib.baseboard_fab2(sch_1):page253_i26:sbu1" )
			)
			( pin "J30W1.B8"
				( objectStatus "@baseboard_fab2_lib.baseboard_fab2(sch_1):page253_i26:sbu2" )
			)
			( pin "J30W1.B10"
				( objectStatus "@baseboard_fab2_lib.baseboard_fab2(sch_1):page253_i26:ssrxn1" )
			)
			( pin "J30W1.A10"
				( objectStatus "@baseboard_fab2_lib.baseboard_fab2(sch_1):page253_i26:ssrxn2" )
			)
			( pin "J30W1.B11"
				( objectStatus "@baseboard_fab2_lib.baseboard_fab2(sch_1):page253_i26:ssrxp1" )
			)
			( pin "J30W1.A11"
				( objectStatus "@baseboard_fab2_lib.baseboard_fab2(sch_1):page253_i26:ssrxp2" )
			)
			( pin "J30W1.A3"
				( objectStatus "@baseboard_fab2_lib.baseboard_fab2(sch_1):page253_i26:sstxn1" )
			)
			( pin "J30W1.B3"
				( objectStatus "@baseboard_fab2_lib.baseboard_fab2(sch_1):page253_i26:sstxn2" )
			)
			( pin "J30W1.A2"
				( objectStatus "@baseboard_fab2_lib.baseboard_fab2(sch_1):page253_i26:sstxp1" )
			)
			( pin "J30W1.B2"
				( objectStatus "@baseboard_fab2_lib.baseboard_fab2(sch_1):page253_i26:sstxp2" )
			)
			( pin "J30W1.A4"
				( objectStatus "@baseboard_fab2_lib.baseboard_fab2(sch_1):page253_i26:vbus(0)" )
			)
			( pin "J30W1.A9"
				( objectStatus "@baseboard_fab2_lib.baseboard_fab2(sch_1):page253_i26:vbus(1)" )
			)
			( pin "J30W1.B4"
				( objectStatus "@baseboard_fab2_lib.baseboard_fab2(sch_1):page253_i26:vbus(2)" )
			)
			( pin "J30W1.B9"
				( objectStatus "@baseboard_fab2_lib.baseboard_fab2(sch_1):page253_i26:vbus(3)" )
			)
			( pin "C4A13.1"
				( objectStatus "@baseboard_fab2_lib.baseboard_fab2(sch_1):page230_i20:a" )
			)
			( pin "C4A13.2"
				( objectStatus "@baseboard_fab2_lib.baseboard_fab2(sch_1):page230_i20:b" )
			)
			( pin "R6L8.1"
				( objectStatus "@baseboard_fab2_lib.baseboard_fab2(sch_1):page230_i13:a" )
			)
			( pin "R6L8.2"
				( objectStatus "@baseboard_fab2_lib.baseboard_fab2(sch_1):page230_i13:b" )
			)
			( pin "C4A8.1"
				( objectStatus "@baseboard_fab2_lib.baseboard_fab2(sch_1):page230_i12:a" )
			)
			( pin "C4A8.2"
				( objectStatus "@baseboard_fab2_lib.baseboard_fab2(sch_1):page230_i12:b" )
			)
			( pin "C4A7.1"
				( objectStatus "@baseboard_fab2_lib.baseboard_fab2(sch_1):page230_i10:a" )
			)
			( pin "C4A7.2"
				( objectStatus "@baseboard_fab2_lib.baseboard_fab2(sch_1):page230_i10:b" )
			)
			( pin "R6L6.1"
				( objectStatus "@baseboard_fab2_lib.baseboard_fab2(sch_1):page230_i6:a" )
			)
			( pin "R6L6.2"
				( objectStatus "@baseboard_fab2_lib.baseboard_fab2(sch_1):page230_i6:b" )
			)
			( pin "R6L5.1"
				( objectStatus "@baseboard_fab2_lib.baseboard_fab2(sch_1):page230_i5:a" )
			)
			( pin "R6L5.2"
				( objectStatus "@baseboard_fab2_lib.baseboard_fab2(sch_1):page230_i5:b" )
			)
			( pin "R4A3.1"
				( objectStatus "@baseboard_fab2_lib.baseboard_fab2(sch_1):page230_i4:a" )
			)
			( pin "R4A3.2"
				( objectStatus "@baseboard_fab2_lib.baseboard_fab2(sch_1):page230_i4:b" )
			)
			( pin "C4A6.1"
				( objectStatus "@baseboard_fab2_lib.baseboard_fab2(sch_1):page230_i2:a" )
			)
			( pin "C4A6.2"
				( objectStatus "@baseboard_fab2_lib.baseboard_fab2(sch_1):page230_i2:b" )
			)
			( pin "R4E9.1"
				( objectStatus "@baseboard_fab2_lib.baseboard_fab2(sch_1):page201_i189:a" )
			)
			( pin "R4E9.2"
				( objectStatus "@baseboard_fab2_lib.baseboard_fab2(sch_1):page201_i189:b" )
			)
			( pin "R3N15.1"
				( objectStatus "@baseboard_fab2_lib.baseboard_fab2(sch_1):page133_i368:a" )
			)
			( pin "R3N15.2"
				( objectStatus "@baseboard_fab2_lib.baseboard_fab2(sch_1):page133_i368:b" )
			)
			( pin "R3N16.1"
				( objectStatus "@baseboard_fab2_lib.baseboard_fab2(sch_1):page133_i369:a" )
			)
			( pin "R3N16.2"
				( objectStatus "@baseboard_fab2_lib.baseboard_fab2(sch_1):page133_i369:b" )
			)
			( pin "R3P5.1"
				( objectStatus "@baseboard_fab2_lib.baseboard_fab2(sch_1):page133_i366:a" )
			)
			( pin "R3P5.2"
				( objectStatus "@baseboard_fab2_lib.baseboard_fab2(sch_1):page133_i366:b" )
			)
			( pin "R3P6.1"
				( objectStatus "@baseboard_fab2_lib.baseboard_fab2(sch_1):page133_i367:a" )
			)
			( pin "R3P6.2"
				( objectStatus "@baseboard_fab2_lib.baseboard_fab2(sch_1):page133_i367:b" )
			)
			( pin "C9N12.1"
				( objectStatus "@baseboard_fab2_lib.baseboard_fab2(sch_1):page182_i37:a" )
			)
			( pin "C9N12.2"
				( objectStatus "@baseboard_fab2_lib.baseboard_fab2(sch_1):page182_i37:b" )
			)
			( pin "C9N2.1"
				( objectStatus "@baseboard_fab2_lib.baseboard_fab2(sch_1):page182_i36:a" )
			)
			( pin "C9N2.2"
				( objectStatus "@baseboard_fab2_lib.baseboard_fab2(sch_1):page182_i36:b" )
			)
			( pin "R1C11.1"
				( objectStatus "@baseboard_fab2_lib.baseboard_fab2(sch_1):page182_i10:a" )
			)
			( pin "R1C11.2"
				( objectStatus "@baseboard_fab2_lib.baseboard_fab2(sch_1):page182_i10:b" )
			)
			( pin "R1C10.1"
				( objectStatus "@baseboard_fab2_lib.baseboard_fab2(sch_1):page182_i9:a" )
			)
			( pin "R1C10.2"
				( objectStatus "@baseboard_fab2_lib.baseboard_fab2(sch_1):page182_i9:b" )
			)
			( pin "R1C9.1"
				( objectStatus "@baseboard_fab2_lib.baseboard_fab2(sch_1):page182_i8:a" )
			)
			( pin "R1C9.2"
				( objectStatus "@baseboard_fab2_lib.baseboard_fab2(sch_1):page182_i8:b" )
			)
			( pin "R1F9.1"
				( objectStatus "@baseboard_fab2_lib.baseboard_fab2(sch_1):page182_i7:a" )
			)
			( pin "R1F9.2"
				( objectStatus "@baseboard_fab2_lib.baseboard_fab2(sch_1):page182_i7:b" )
			)
			( pin "R1C31.1"
				( objectStatus "@baseboard_fab2_lib.baseboard_fab2(sch_1):page182_i6:a" )
			)
			( pin "R1C31.2"
				( objectStatus "@baseboard_fab2_lib.baseboard_fab2(sch_1):page182_i6:b" )
			)
			( pin "RN8F1.1"
				( objectStatus "@baseboard_fab2_lib.baseboard_fab2(sch_1):page137_i142:a" )
			)
			( pin "RN8F1.2"
				( objectStatus "@baseboard_fab2_lib.baseboard_fab2(sch_1):page137_i142:b" )
			)
			( pin "R6W2.1"
				( objectStatus "@baseboard_fab2_lib.baseboard_fab2(sch_1):page137_i144:a" )
			)
			( pin "R6W2.2"
				( objectStatus "@baseboard_fab2_lib.baseboard_fab2(sch_1):page137_i144:b" )
			)
			( pin "C7G4.1"
				( objectStatus "@baseboard_fab2_lib.baseboard_fab2(sch_1):page215_i14:a" )
			)
			( pin "C7G4.2"
				( objectStatus "@baseboard_fab2_lib.baseboard_fab2(sch_1):page215_i14:b" )
			)
			( pin "RF15.1"
				( objectStatus "@baseboard_fab2_lib.baseboard_fab2(sch_1):page215_i15:a" )
			)
			( pin "RF15.2"
				( objectStatus "@baseboard_fab2_lib.baseboard_fab2(sch_1):page215_i15:b" )
			)
			( pin "CF15.1"
				( objectStatus "@baseboard_fab2_lib.baseboard_fab2(sch_1):page215_i16:\1\" )
			)
			( pin "CF15.2"
				( objectStatus "@baseboard_fab2_lib.baseboard_fab2(sch_1):page215_i16:\2\" )
			)
			( pin "R9M6.1"
				( objectStatus "@baseboard_fab2_lib.baseboard_fab2(sch_1):page226_i70:a" )
			)
			( pin "R9M6.2"
				( objectStatus "@baseboard_fab2_lib.baseboard_fab2(sch_1):page226_i70:b" )
			)
			( pin "R2L25.1"
				( objectStatus "@baseboard_fab2_lib.baseboard_fab2(sch_1):page235_i252:a" )
			)
			( pin "R2L25.2"
				( objectStatus "@baseboard_fab2_lib.baseboard_fab2(sch_1):page235_i252:b" )
			)
			( pin "C7G3.1"
				( objectStatus "@baseboard_fab2_lib.baseboard_fab2(sch_1):page215_i22:a" )
			)
			( pin "C7G3.2"
				( objectStatus "@baseboard_fab2_lib.baseboard_fab2(sch_1):page215_i22:b" )
			)
			( pin "R7A10.1"
				( objectStatus "@baseboard_fab2_lib.baseboard_fab2(sch_1):page218_i73:a" )
			)
			( pin "R7A10.2"
				( objectStatus "@baseboard_fab2_lib.baseboard_fab2(sch_1):page218_i73:b" )
			)
			( pin "CF16.1"
				( objectStatus "@baseboard_fab2_lib.baseboard_fab2(sch_1):page215_i26:\1\" )
			)
			( pin "CF16.2"
				( objectStatus "@baseboard_fab2_lib.baseboard_fab2(sch_1):page215_i26:\2\" )
			)
			( pin "RF16.1"
				( objectStatus "@baseboard_fab2_lib.baseboard_fab2(sch_1):page215_i27:a" )
			)
			( pin "RF16.2"
				( objectStatus "@baseboard_fab2_lib.baseboard_fab2(sch_1):page215_i27:b" )
			)
			( pin "R7G24.1"
				( objectStatus "@baseboard_fab2_lib.baseboard_fab2(sch_1):page215_i28:a" )
			)
			( pin "R7G24.2"
				( objectStatus "@baseboard_fab2_lib.baseboard_fab2(sch_1):page215_i28:b" )
			)
			( pin "R7F20.1"
				( objectStatus "@baseboard_fab2_lib.baseboard_fab2(sch_1):page215_i29:a" )
			)
			( pin "R7F20.2"
				( objectStatus "@baseboard_fab2_lib.baseboard_fab2(sch_1):page215_i29:b" )
			)
			( pin "R3T13.1"
				( objectStatus "@baseboard_fab2_lib.baseboard_fab2(sch_1):page215_i33:a" )
			)
			( pin "R3T13.2"
				( objectStatus "@baseboard_fab2_lib.baseboard_fab2(sch_1):page215_i33:b" )
			)
			( pin "C7F17.1"
				( objectStatus "@baseboard_fab2_lib.baseboard_fab2(sch_1):page215_i34:a" )
			)
			( pin "C7F17.2"
				( objectStatus "@baseboard_fab2_lib.baseboard_fab2(sch_1):page215_i34:b" )
			)
			( pin "C7F18.1"
				( objectStatus "@baseboard_fab2_lib.baseboard_fab2(sch_1):page215_i35:a" )
			)
			( pin "C7F18.2"
				( objectStatus "@baseboard_fab2_lib.baseboard_fab2(sch_1):page215_i35:b" )
			)
			( pin "C7F15.1"
				( objectStatus "@baseboard_fab2_lib.baseboard_fab2(sch_1):page215_i38:a" )
			)
			( pin "C7F15.2"
				( objectStatus "@baseboard_fab2_lib.baseboard_fab2(sch_1):page215_i38:b" )
			)
			( pin "C7F16.1"
				( objectStatus "@baseboard_fab2_lib.baseboard_fab2(sch_1):page215_i40:a" )
			)
			( pin "C7F16.2"
				( objectStatus "@baseboard_fab2_lib.baseboard_fab2(sch_1):page215_i40:b" )
			)
			( pin "R7G2.1"
				( objectStatus "@baseboard_fab2_lib.baseboard_fab2(sch_1):page215_i41:a" )
			)
			( pin "R7G2.2"
				( objectStatus "@baseboard_fab2_lib.baseboard_fab2(sch_1):page215_i41:b" )
			)
			( pin "C7F14.1"
				( objectStatus "@baseboard_fab2_lib.baseboard_fab2(sch_1):page215_i44:a" )
			)
			( pin "C7F14.2"
				( objectStatus "@baseboard_fab2_lib.baseboard_fab2(sch_1):page215_i44:b" )
			)
			( pin "R12W26.1"
				( objectStatus "@baseboard_fab2_lib.baseboard_fab2(sch_1):page215_i45:a" )
			)
			( pin "R12W26.2"
				( objectStatus "@baseboard_fab2_lib.baseboard_fab2(sch_1):page215_i45:b" )
			)
			( pin "R12W28.1"
				( objectStatus "@baseboard_fab2_lib.baseboard_fab2(sch_1):page218_i75:a" )
			)
			( pin "R12W28.2"
				( objectStatus "@baseboard_fab2_lib.baseboard_fab2(sch_1):page218_i75:b" )
			)
			( pin "R7G4.1"
				( objectStatus "@baseboard_fab2_lib.baseboard_fab2(sch_1):page215_i49:a" )
			)
			( pin "R7G4.2"
				( objectStatus "@baseboard_fab2_lib.baseboard_fab2(sch_1):page215_i49:b" )
			)
			( pin "R7F27.1"
				( objectStatus "@baseboard_fab2_lib.baseboard_fab2(sch_1):page215_i50:a" )
			)
			( pin "R7F27.2"
				( objectStatus "@baseboard_fab2_lib.baseboard_fab2(sch_1):page215_i50:b" )
			)
			( pin "R7F22.1"
				( objectStatus "@baseboard_fab2_lib.baseboard_fab2(sch_1):page215_i51:a" )
			)
			( pin "R7F22.2"
				( objectStatus "@baseboard_fab2_lib.baseboard_fab2(sch_1):page215_i51:b" )
			)
			( pin "R7F23.1"
				( objectStatus "@baseboard_fab2_lib.baseboard_fab2(sch_1):page215_i53:a" )
			)
			( pin "R7F23.2"
				( objectStatus "@baseboard_fab2_lib.baseboard_fab2(sch_1):page215_i53:b" )
			)
			( pin "R12W27.1"
				( objectStatus "@baseboard_fab2_lib.baseboard_fab2(sch_1):page215_i54:a" )
			)
			( pin "R12W27.2"
				( objectStatus "@baseboard_fab2_lib.baseboard_fab2(sch_1):page215_i54:b" )
			)
			( pin "R7F24.1"
				( objectStatus "@baseboard_fab2_lib.baseboard_fab2(sch_1):page215_i56:a" )
			)
			( pin "R7F24.2"
				( objectStatus "@baseboard_fab2_lib.baseboard_fab2(sch_1):page215_i56:b" )
			)
			( pin "R7A9.1"
				( objectStatus "@baseboard_fab2_lib.baseboard_fab2(sch_1):page218_i76:a" )
			)
			( pin "R7A9.2"
				( objectStatus "@baseboard_fab2_lib.baseboard_fab2(sch_1):page218_i76:b" )
			)
			( pin "R3U2.1"
				( objectStatus "@baseboard_fab2_lib.baseboard_fab2(sch_1):page215_i58:a" )
			)
			( pin "R3U2.2"
				( objectStatus "@baseboard_fab2_lib.baseboard_fab2(sch_1):page215_i58:b" )
			)
			( pin "EU7G1.21"
				( objectStatus "@baseboard_fab2_lib.baseboard_fab2(sch_1):page215_i69:airef1" )
			)
			( pin "EU7G1.23"
				( objectStatus "@baseboard_fab2_lib.baseboard_fab2(sch_1):page215_i69:airef2" )
			)
			( pin "EU7G1.25"
				( objectStatus "@baseboard_fab2_lib.baseboard_fab2(sch_1):page215_i69:airef3" )
			)
			( pin "EU7G1.22"
				( objectStatus "@baseboard_fab2_lib.baseboard_fab2(sch_1):page215_i69:aisen1" )
			)
			( pin "EU7G1.24"
				( objectStatus "@baseboard_fab2_lib.baseboard_fab2(sch_1):page215_i69:aisen2" )
			)
			( pin "EU7G1.26"
				( objectStatus "@baseboard_fab2_lib.baseboard_fab2(sch_1):page215_i69:aisen3" )
			)
			( pin "EU7G1.5"
				( objectStatus "@baseboard_fab2_lib.baseboard_fab2(sch_1):page215_i69:apwm1" )
			)
			( pin "EU7G1.4"
				( objectStatus "@baseboard_fab2_lib.baseboard_fab2(sch_1):page215_i69:apwm2" )
			)
			( pin "EU7G1.3"
				( objectStatus "@baseboard_fab2_lib.baseboard_fab2(sch_1):page215_i69:apwm3" )
			)
			( pin "EU7G1.35"
				( objectStatus "@baseboard_fab2_lib.baseboard_fab2(sch_1):page215_i69:atsen" )
			)
			( pin "EU7G1.20"
				( objectStatus "@baseboard_fab2_lib.baseboard_fab2(sch_1):page215_i69:avref" )
			)
			( pin "EU7G1.10"
				( objectStatus "@baseboard_fab2_lib.baseboard_fab2(sch_1):page215_i69:avren" )
			)
			( pin "EU7G1.9"
				( objectStatus "@baseboard_fab2_lib.baseboard_fab2(sch_1):page215_i69:avrrdy" )
			)
			( pin "EU7G1.19"
				( objectStatus "@baseboard_fab2_lib.baseboard_fab2(sch_1):page215_i69:avsen" )
			)
			( pin "EU7G1.31"
				( objectStatus "@baseboard_fab2_lib.baseboard_fab2(sch_1):page215_i69:biref1" )
			)
			( pin "EU7G1.32"
				( objectStatus "@baseboard_fab2_lib.baseboard_fab2(sch_1):page215_i69:bisen1" )
			)
			( pin "EU7G1.1"
				( objectStatus "@baseboard_fab2_lib.baseboard_fab2(sch_1):page215_i69:bpwm1" )
			)
			( pin "EU7G1.34"
				( objectStatus "@baseboard_fab2_lib.baseboard_fab2(sch_1):page215_i69:btsen" )
			)
			( pin "EU7G1.30"
				( objectStatus "@baseboard_fab2_lib.baseboard_fab2(sch_1):page215_i69:bvref" )
			)
			( pin "EU7G1.29"
				( objectStatus "@baseboard_fab2_lib.baseboard_fab2(sch_1):page215_i69:bvsen" )
			)
			( pin "EU7G1.2"
				( objectStatus "@baseboard_fab2_lib.baseboard_fab2(sch_1):page215_i69:dnc(0)" )
			)
			( pin "EU7G1.28"
				( objectStatus "@baseboard_fab2_lib.baseboard_fab2(sch_1):page215_i69:dnc(1)" )
			)
			( pin "EU7G1.27"
				( objectStatus "@baseboard_fab2_lib.baseboard_fab2(sch_1):page215_i69:gnd" )
			)
			( pin "EU7G1.38"
				( objectStatus "@baseboard_fab2_lib.baseboard_fab2(sch_1):page215_i69:iinsen" )
			)
			( pin "EU7G1.13"
				( objectStatus "@baseboard_fab2_lib.baseboard_fab2(sch_1):page215_i69:mp0" )
			)
			( pin "EU7G1.14"
				( objectStatus "@baseboard_fab2_lib.baseboard_fab2(sch_1):page215_i69:mp1" )
			)
			( pin "EU7G1.18"
				( objectStatus "@baseboard_fab2_lib.baseboard_fab2(sch_1):page215_i69:mp2" )
			)
			( pin "EU7G1.12"
				( objectStatus "@baseboard_fab2_lib.baseboard_fab2(sch_1):page215_i69:pinalrt_n" )
			)
			( pin "EU7G1.8"
				( objectStatus "@baseboard_fab2_lib.baseboard_fab2(sch_1):page215_i69:reset_n" )
			)
			( pin "EU7G1.7"
				( objectStatus "@baseboard_fab2_lib.baseboard_fab2(sch_1):page215_i69:scl" )
			)
			( pin "EU7G1.6"
				( objectStatus "@baseboard_fab2_lib.baseboard_fab2(sch_1):page215_i69:sda" )
			)
			( pin "EU7G1.41"
				( objectStatus "@baseboard_fab2_lib.baseboard_fab2(sch_1):page215_i69:thpad" )
			)
			( pin "EU7G1.17"
				( objectStatus "@baseboard_fab2_lib.baseboard_fab2(sch_1):page215_i69:valrt_n" )
			)
			( pin "EU7G1.15"
				( objectStatus "@baseboard_fab2_lib.baseboard_fab2(sch_1):page215_i69:vclk" )
			)
			( pin "EU7G1.40"
				( objectStatus "@baseboard_fab2_lib.baseboard_fab2(sch_1):page215_i69:vd12" )
			)
			( pin "EU7G1.39"
				( objectStatus "@baseboard_fab2_lib.baseboard_fab2(sch_1):page215_i69:vdd" )
			)
			( pin "EU7G1.16"
				( objectStatus "@baseboard_fab2_lib.baseboard_fab2(sch_1):page215_i69:vdio" )
			)
			( pin "EU7G1.37"
				( objectStatus "@baseboard_fab2_lib.baseboard_fab2(sch_1):page215_i69:vinsen" )
			)
			( pin "EU7G1.11"
				( objectStatus "@baseboard_fab2_lib.baseboard_fab2(sch_1):page215_i69:vrhot_n" )
			)
			( pin "EU7G1.36"
				( objectStatus "@baseboard_fab2_lib.baseboard_fab2(sch_1):page215_i69:xaddr1" )
			)
			( pin "EU7G1.33"
				( objectStatus "@baseboard_fab2_lib.baseboard_fab2(sch_1):page215_i69:xaddr2" )
			)
			( pin "R12W19.1"
				( objectStatus "@baseboard_fab2_lib.baseboard_fab2(sch_1):page197_i37:a" )
			)
			( pin "R12W19.2"
				( objectStatus "@baseboard_fab2_lib.baseboard_fab2(sch_1):page197_i37:b" )
			)
			( pin "C12W3.1"
				( objectStatus "@baseboard_fab2_lib.baseboard_fab2(sch_1):page197_i42:a" )
			)
			( pin "C12W3.2"
				( objectStatus "@baseboard_fab2_lib.baseboard_fab2(sch_1):page197_i42:b" )
			)
			( pin "Q12W1.4"
				( objectStatus "@baseboard_fab2_lib.baseboard_fab2(sch_1):page197_i43:\drain#4\" )
			)
			( pin "Q12W1.6"
				( objectStatus "@baseboard_fab2_lib.baseboard_fab2(sch_1):page197_i43:\drain#6\" )
			)
			( pin "Q12W1.1"
				( objectStatus "@baseboard_fab2_lib.baseboard_fab2(sch_1):page197_i43:\gate#1\" )
			)
			( pin "Q12W1.3"
				( objectStatus "@baseboard_fab2_lib.baseboard_fab2(sch_1):page197_i43:\gate#3\" )
			)
			( pin "Q12W1.2"
				( objectStatus "@baseboard_fab2_lib.baseboard_fab2(sch_1):page197_i43:\source#2\" )
			)
			( pin "Q12W1.5"
				( objectStatus "@baseboard_fab2_lib.baseboard_fab2(sch_1):page197_i43:\source#5\" )
			)
			( pin "R12W4.1"
				( objectStatus "@baseboard_fab2_lib.baseboard_fab2(sch_1):page197_i45:a" )
			)
			( pin "R12W4.2"
				( objectStatus "@baseboard_fab2_lib.baseboard_fab2(sch_1):page197_i45:b" )
			)
			( pin "R12W8.1"
				( objectStatus "@baseboard_fab2_lib.baseboard_fab2(sch_1):page197_i113:\1\" )
			)
			( pin "R12W8.2"
				( objectStatus "@baseboard_fab2_lib.baseboard_fab2(sch_1):page197_i113:\2\" )
			)
			( pin "C8F18.1"
				( objectStatus "@baseboard_fab2_lib.baseboard_fab2(sch_1):page101_i147:a" )
			)
			( pin "C8F18.2"
				( objectStatus "@baseboard_fab2_lib.baseboard_fab2(sch_1):page101_i147:b" )
			)
			( pin "R1F3.1"
				( objectStatus "@baseboard_fab2_lib.baseboard_fab2(sch_1):page197_i50:a" )
			)
			( pin "R1F3.2"
				( objectStatus "@baseboard_fab2_lib.baseboard_fab2(sch_1):page197_i50:b" )
			)
			( pin "R12W14.1"
				( objectStatus "@baseboard_fab2_lib.baseboard_fab2(sch_1):page197_i53:a" )
			)
			( pin "R12W14.2"
				( objectStatus "@baseboard_fab2_lib.baseboard_fab2(sch_1):page197_i53:b" )
			)
			( pin "C9T8.1"
				( objectStatus "@baseboard_fab2_lib.baseboard_fab2(sch_1):page197_i56:a" )
			)
			( pin "C9T8.2"
				( objectStatus "@baseboard_fab2_lib.baseboard_fab2(sch_1):page197_i56:b" )
			)
			( pin "C1A4.1"
				( objectStatus "@baseboard_fab2_lib.baseboard_fab2(sch_1):page197_i60:a" )
			)
			( pin "C1A4.2"
				( objectStatus "@baseboard_fab2_lib.baseboard_fab2(sch_1):page197_i60:b" )
			)
			( pin "C9U11.1"
				( objectStatus "@baseboard_fab2_lib.baseboard_fab2(sch_1):page197_i63:a" )
			)
			( pin "C9U11.2"
				( objectStatus "@baseboard_fab2_lib.baseboard_fab2(sch_1):page197_i63:b" )
			)
			( pin "C9U8.1"
				( objectStatus "@baseboard_fab2_lib.baseboard_fab2(sch_1):page197_i66:a" )
			)
			( pin "C9U8.2"
				( objectStatus "@baseboard_fab2_lib.baseboard_fab2(sch_1):page197_i66:b" )
			)
			( pin "C6U18.1"
				( objectStatus "@baseboard_fab2_lib.baseboard_fab2(sch_1):page197_i69:a" )
			)
			( pin "C6U18.2"
				( objectStatus "@baseboard_fab2_lib.baseboard_fab2(sch_1):page197_i69:b" )
			)
			( pin "C6T2.1"
				( objectStatus "@baseboard_fab2_lib.baseboard_fab2(sch_1):page197_i71:a" )
			)
			( pin "C6T2.2"
				( objectStatus "@baseboard_fab2_lib.baseboard_fab2(sch_1):page197_i71:b" )
			)
			( pin "C1B7.1"
				( objectStatus "@baseboard_fab2_lib.baseboard_fab2(sch_1):page197_i72:a" )
			)
			( pin "C1B7.2"
				( objectStatus "@baseboard_fab2_lib.baseboard_fab2(sch_1):page197_i72:b" )
			)
			( pin "C1A16.1"
				( objectStatus "@baseboard_fab2_lib.baseboard_fab2(sch_1):page197_i75:a" )
			)
			( pin "C1A16.2"
				( objectStatus "@baseboard_fab2_lib.baseboard_fab2(sch_1):page197_i75:b" )
			)
			( pin "C4B11.1"
				( objectStatus "@baseboard_fab2_lib.baseboard_fab2(sch_1):page197_i78:a" )
			)
			( pin "C4B11.2"
				( objectStatus "@baseboard_fab2_lib.baseboard_fab2(sch_1):page197_i78:b" )
			)
			( pin "C4A4.1"
				( objectStatus "@baseboard_fab2_lib.baseboard_fab2(sch_1):page197_i81:a" )
			)
			( pin "C4A4.2"
				( objectStatus "@baseboard_fab2_lib.baseboard_fab2(sch_1):page197_i81:b" )
			)
			( pin "C6U10.1"
				( objectStatus "@baseboard_fab2_lib.baseboard_fab2(sch_1):page197_i84:a" )
			)
			( pin "C6U10.2"
				( objectStatus "@baseboard_fab2_lib.baseboard_fab2(sch_1):page197_i84:b" )
			)
			( pin "C4A17.1"
				( objectStatus "@baseboard_fab2_lib.baseboard_fab2(sch_1):page197_i88:a" )
			)
			( pin "C4A17.2"
				( objectStatus "@baseboard_fab2_lib.baseboard_fab2(sch_1):page197_i88:b" )
			)
			( pin "Q12W3.4"
				( objectStatus "@baseboard_fab2_lib.baseboard_fab2(sch_1):page197_i91:\drain#4\" )
			)
			( pin "Q12W3.6"
				( objectStatus "@baseboard_fab2_lib.baseboard_fab2(sch_1):page197_i91:\drain#6\" )
			)
			( pin "Q12W3.1"
				( objectStatus "@baseboard_fab2_lib.baseboard_fab2(sch_1):page197_i91:\gate#1\" )
			)
			( pin "Q12W3.3"
				( objectStatus "@baseboard_fab2_lib.baseboard_fab2(sch_1):page197_i91:\gate#3\" )
			)
			( pin "Q12W3.2"
				( objectStatus "@baseboard_fab2_lib.baseboard_fab2(sch_1):page197_i91:\source#2\" )
			)
			( pin "Q12W3.5"
				( objectStatus "@baseboard_fab2_lib.baseboard_fab2(sch_1):page197_i91:\source#5\" )
			)
			( pin "R9T9.1"
				( objectStatus "@baseboard_fab2_lib.baseboard_fab2(sch_1):page181_i4:a" )
			)
			( pin "R9T9.2"
				( objectStatus "@baseboard_fab2_lib.baseboard_fab2(sch_1):page181_i4:b" )
			)
			( pin "CR1F4.2"
				( objectStatus "@baseboard_fab2_lib.baseboard_fab2(sch_1):page181_i5:a" )
			)
			( pin "CR1F4.1"
				( objectStatus "@baseboard_fab2_lib.baseboard_fab2(sch_1):page181_i5:c" )
			)
			( pin "R1F8.1"
				( objectStatus "@baseboard_fab2_lib.baseboard_fab2(sch_1):page181_i22:a" )
			)
			( pin "R1F8.2"
				( objectStatus "@baseboard_fab2_lib.baseboard_fab2(sch_1):page181_i22:b" )
			)
			( pin "R9T1.1"
				( objectStatus "@baseboard_fab2_lib.baseboard_fab2(sch_1):page181_i26:a" )
			)
			( pin "R9T1.2"
				( objectStatus "@baseboard_fab2_lib.baseboard_fab2(sch_1):page181_i26:b" )
			)
			( pin "R9R12.1"
				( objectStatus "@baseboard_fab2_lib.baseboard_fab2(sch_1):page181_i27:a" )
			)
			( pin "R9R12.2"
				( objectStatus "@baseboard_fab2_lib.baseboard_fab2(sch_1):page181_i27:b" )
			)
			( pin "R9F63.1"
				( objectStatus "@baseboard_fab2_lib.baseboard_fab2(sch_1):page181_i28:a" )
			)
			( pin "R9F63.2"
				( objectStatus "@baseboard_fab2_lib.baseboard_fab2(sch_1):page181_i28:b" )
			)
			( pin "R9F64.1"
				( objectStatus "@baseboard_fab2_lib.baseboard_fab2(sch_1):page181_i29:a" )
			)
			( pin "R9F64.2"
				( objectStatus "@baseboard_fab2_lib.baseboard_fab2(sch_1):page181_i29:b" )
			)
			( pin "R9F70.1"
				( objectStatus "@baseboard_fab2_lib.baseboard_fab2(sch_1):page181_i30:a" )
			)
			( pin "R9F70.2"
				( objectStatus "@baseboard_fab2_lib.baseboard_fab2(sch_1):page181_i30:b" )
			)
			( pin "R9R10.1"
				( objectStatus "@baseboard_fab2_lib.baseboard_fab2(sch_1):page181_i31:a" )
			)
			( pin "R9R10.2"
				( objectStatus "@baseboard_fab2_lib.baseboard_fab2(sch_1):page181_i31:b" )
			)
			( pin "R9R9.1"
				( objectStatus "@baseboard_fab2_lib.baseboard_fab2(sch_1):page181_i32:a" )
			)
			( pin "R9R9.2"
				( objectStatus "@baseboard_fab2_lib.baseboard_fab2(sch_1):page181_i32:b" )
			)
			( pin "R9F67.1"
				( objectStatus "@baseboard_fab2_lib.baseboard_fab2(sch_1):page181_i33:a" )
			)
			( pin "R9F67.2"
				( objectStatus "@baseboard_fab2_lib.baseboard_fab2(sch_1):page181_i33:b" )
			)
			( pin "C8E1.1"
				( objectStatus "@baseboard_fab2_lib.baseboard_fab2(sch_1):page181_i34:a" )
			)
			( pin "C8E1.2"
				( objectStatus "@baseboard_fab2_lib.baseboard_fab2(sch_1):page181_i34:b" )
			)
			( pin "CR1F3.2"
				( objectStatus "@baseboard_fab2_lib.baseboard_fab2(sch_1):page181_i37:a" )
			)
			( pin "CR1F3.1"
				( objectStatus "@baseboard_fab2_lib.baseboard_fab2(sch_1):page181_i37:c" )
			)
			( pin "C2R6.1"
				( objectStatus "@baseboard_fab2_lib.baseboard_fab2(sch_1):page181_i40:a" )
			)
			( pin "C2R6.2"
				( objectStatus "@baseboard_fab2_lib.baseboard_fab2(sch_1):page181_i40:b" )
			)
			( pin "Q9T1.1"
				( objectStatus "@baseboard_fab2_lib.baseboard_fab2(sch_1):page181_i42:b" )
			)
			( pin "Q9T1.3"
				( objectStatus "@baseboard_fab2_lib.baseboard_fab2(sch_1):page181_i42:c" )
			)
			( pin "Q9T1.2"
				( objectStatus "@baseboard_fab2_lib.baseboard_fab2(sch_1):page181_i42:e" )
			)
			( pin "U8E1.9"
				( objectStatus "@baseboard_fab2_lib.baseboard_fab2(sch_1):page181_i60:a(0)" )
			)
			( pin "U8E1.10"
				( objectStatus "@baseboard_fab2_lib.baseboard_fab2(sch_1):page181_i60:b(0)" )
			)
			( pin "U8E1.8"
				( objectStatus "@baseboard_fab2_lib.baseboard_fab2(sch_1):page181_i60:y(0)" )
			)
			( pin "R8E5.1"
				( objectStatus "@baseboard_fab2_lib.baseboard_fab2(sch_1):page181_i63:a" )
			)
			( pin "R8E5.2"
				( objectStatus "@baseboard_fab2_lib.baseboard_fab2(sch_1):page181_i63:b" )
			)
			( pin "R9T3.1"
				( objectStatus "@baseboard_fab2_lib.baseboard_fab2(sch_1):page181_i64:a" )
			)
			( pin "R9T3.2"
				( objectStatus "@baseboard_fab2_lib.baseboard_fab2(sch_1):page181_i64:b" )
			)
			( pin "R9T6.1"
				( objectStatus "@baseboard_fab2_lib.baseboard_fab2(sch_1):page181_i68:a" )
			)
			( pin "R9T6.2"
				( objectStatus "@baseboard_fab2_lib.baseboard_fab2(sch_1):page181_i68:b" )
			)
			( pin "C1F14.1"
				( objectStatus "@baseboard_fab2_lib.baseboard_fab2(sch_1):page181_i70:a" )
			)
			( pin "C1F14.2"
				( objectStatus "@baseboard_fab2_lib.baseboard_fab2(sch_1):page181_i70:b" )
			)
			( pin "C1F17.1"
				( objectStatus "@baseboard_fab2_lib.baseboard_fab2(sch_1):page181_i71:a" )
			)
			( pin "C1F17.2"
				( objectStatus "@baseboard_fab2_lib.baseboard_fab2(sch_1):page181_i71:b" )
			)
			( pin "C1F18.1"
				( objectStatus "@baseboard_fab2_lib.baseboard_fab2(sch_1):page181_i72:a" )
			)
			( pin "C1F18.2"
				( objectStatus "@baseboard_fab2_lib.baseboard_fab2(sch_1):page181_i72:b" )
			)
			( pin "C1F8.1"
				( objectStatus "@baseboard_fab2_lib.baseboard_fab2(sch_1):page181_i73:a" )
			)
			( pin "C1F8.2"
				( objectStatus "@baseboard_fab2_lib.baseboard_fab2(sch_1):page181_i73:b" )
			)
			( pin "C1F11.1"
				( objectStatus "@baseboard_fab2_lib.baseboard_fab2(sch_1):page181_i74:a" )
			)
			( pin "C1F11.2"
				( objectStatus "@baseboard_fab2_lib.baseboard_fab2(sch_1):page181_i74:b" )
			)
			( pin "C1F12.1"
				( objectStatus "@baseboard_fab2_lib.baseboard_fab2(sch_1):page181_i75:a" )
			)
			( pin "C1F12.2"
				( objectStatus "@baseboard_fab2_lib.baseboard_fab2(sch_1):page181_i75:b" )
			)
			( pin "C1F3.1"
				( objectStatus "@baseboard_fab2_lib.baseboard_fab2(sch_1):page181_i76:a" )
			)
			( pin "C1F3.2"
				( objectStatus "@baseboard_fab2_lib.baseboard_fab2(sch_1):page181_i76:b" )
			)
			( pin "C1F5.1"
				( objectStatus "@baseboard_fab2_lib.baseboard_fab2(sch_1):page181_i77:a" )
			)
			( pin "C1F5.2"
				( objectStatus "@baseboard_fab2_lib.baseboard_fab2(sch_1):page181_i77:b" )
			)
			( pin "C1F15.1"
				( objectStatus "@baseboard_fab2_lib.baseboard_fab2(sch_1):page181_i78:a" )
			)
			( pin "C1F15.2"
				( objectStatus "@baseboard_fab2_lib.baseboard_fab2(sch_1):page181_i78:b" )
			)
			( pin "C1F16.1"
				( objectStatus "@baseboard_fab2_lib.baseboard_fab2(sch_1):page181_i79:a" )
			)
			( pin "C1F16.2"
				( objectStatus "@baseboard_fab2_lib.baseboard_fab2(sch_1):page181_i79:b" )
			)
			( pin "R7D9.1"
				( objectStatus "@baseboard_fab2_lib.baseboard_fab2(sch_1):page181_i80:a" )
			)
			( pin "R7D9.2"
				( objectStatus "@baseboard_fab2_lib.baseboard_fab2(sch_1):page181_i80:b" )
			)
			( pin "R3P61.1"
				( objectStatus "@baseboard_fab2_lib.baseboard_fab2(sch_1):page181_i81:a" )
			)
			( pin "R3P61.2"
				( objectStatus "@baseboard_fab2_lib.baseboard_fab2(sch_1):page181_i81:b" )
			)
			( pin "R7D5.1"
				( objectStatus "@baseboard_fab2_lib.baseboard_fab2(sch_1):page181_i82:a" )
			)
			( pin "R7D5.2"
				( objectStatus "@baseboard_fab2_lib.baseboard_fab2(sch_1):page181_i82:b" )
			)
			( pin "C1F20.1"
				( objectStatus "@baseboard_fab2_lib.baseboard_fab2(sch_1):page181_i86:a" )
			)
			( pin "C1F20.2"
				( objectStatus "@baseboard_fab2_lib.baseboard_fab2(sch_1):page181_i86:b" )
			)
			( pin "C1F10.1"
				( objectStatus "@baseboard_fab2_lib.baseboard_fab2(sch_1):page181_i87:a" )
			)
			( pin "C1F10.2"
				( objectStatus "@baseboard_fab2_lib.baseboard_fab2(sch_1):page181_i87:b" )
			)
			( pin "C1F6.1"
				( objectStatus "@baseboard_fab2_lib.baseboard_fab2(sch_1):page181_i88:a" )
			)
			( pin "C1F6.2"
				( objectStatus "@baseboard_fab2_lib.baseboard_fab2(sch_1):page181_i88:b" )
			)
			( pin "C1F13.1"
				( objectStatus "@baseboard_fab2_lib.baseboard_fab2(sch_1):page181_i89:a" )
			)
			( pin "C1F13.2"
				( objectStatus "@baseboard_fab2_lib.baseboard_fab2(sch_1):page181_i89:b" )
			)
			( pin "C1F2.1"
				( objectStatus "@baseboard_fab2_lib.baseboard_fab2(sch_1):page181_i90:a" )
			)
			( pin "C1F2.2"
				( objectStatus "@baseboard_fab2_lib.baseboard_fab2(sch_1):page181_i90:b" )
			)
			( pin "C1F4.1"
				( objectStatus "@baseboard_fab2_lib.baseboard_fab2(sch_1):page181_i91:a" )
			)
			( pin "C1F4.2"
				( objectStatus "@baseboard_fab2_lib.baseboard_fab2(sch_1):page181_i91:b" )
			)
			( pin "J1F3.1"
				( objectStatus "@baseboard_fab2_lib.baseboard_fab2(sch_1):page181_i106:io1" )
			)
			( pin "J1F3.2"
				( objectStatus "@baseboard_fab2_lib.baseboard_fab2(sch_1):page181_i106:io2" )
			)
			( pin "J1F3.3"
				( objectStatus "@baseboard_fab2_lib.baseboard_fab2(sch_1):page181_i106:io3" )
			)
			( pin "J1F3.4"
				( objectStatus "@baseboard_fab2_lib.baseboard_fab2(sch_1):page181_i106:io4" )
			)
			( pin "J1F3.5"
				( objectStatus "@baseboard_fab2_lib.baseboard_fab2(sch_1):page181_i106:io5" )
			)
			( pin "J1F3.6"
				( objectStatus "@baseboard_fab2_lib.baseboard_fab2(sch_1):page181_i106:io6" )
			)
			( pin "J1F3.7"
				( objectStatus "@baseboard_fab2_lib.baseboard_fab2(sch_1):page181_i106:io7" )
			)
			( pin "J1F3.8"
				( objectStatus "@baseboard_fab2_lib.baseboard_fab2(sch_1):page181_i106:io8" )
			)
			( pin "J1C1.H3"
				( objectStatus "@baseboard_fab2_lib.baseboard_fab2(sch_1):page182_i79:com_rx" )
			)
			( pin "J1C1.G3"
				( objectStatus "@baseboard_fab2_lib.baseboard_fab2(sch_1):page182_i79:com_tx" )
			)
			( pin "J1C1.F4"
				( objectStatus "@baseboard_fab2_lib.baseboard_fab2(sch_1):page182_i79:fan_pwm0" )
			)
			( pin "J1C1.D4"
				( objectStatus "@baseboard_fab2_lib.baseboard_fab2(sch_1):page182_i79:fan_tach0" )
			)
			( pin "J1C1.C4"
				( objectStatus "@baseboard_fab2_lib.baseboard_fab2(sch_1):page182_i79:fan_tach1" )
			)
			( pin "J1C1.B4"
				( objectStatus "@baseboard_fab2_lib.baseboard_fab2(sch_1):page182_i79:fan_tach2" )
			)
			( pin "J1C1.A4"
				( objectStatus "@baseboard_fab2_lib.baseboard_fab2(sch_1):page182_i79:fan_tach3" )
			)
			( pin "J1C1.A2"
				( objectStatus "@baseboard_fab2_lib.baseboard_fab2(sch_1):page182_i79:gnd1" )
			)
			( pin "J1C1.A8"
				( objectStatus "@baseboard_fab2_lib.baseboard_fab2(sch_1):page182_i79:gnd2" )
			)
			( pin "J1C1.C1"
				( objectStatus "@baseboard_fab2_lib.baseboard_fab2(sch_1):page182_i79:gnd3" )
			)
			( pin "J1C1.C3"
				( objectStatus "@baseboard_fab2_lib.baseboard_fab2(sch_1):page182_i79:gnd4" )
			)
			( pin "J1C1.C5"
				( objectStatus "@baseboard_fab2_lib.baseboard_fab2(sch_1):page182_i79:gnd5" )
			)
			( pin "J1C1.C7"
				( objectStatus "@baseboard_fab2_lib.baseboard_fab2(sch_1):page182_i79:gnd6" )
			)
			( pin "J1C1.D2"
				( objectStatus "@baseboard_fab2_lib.baseboard_fab2(sch_1):page182_i79:gnd7" )
			)
			( pin "J1C1.D6"
				( objectStatus "@baseboard_fab2_lib.baseboard_fab2(sch_1):page182_i79:gnd8" )
			)
			( pin "J1C1.D8"
				( objectStatus "@baseboard_fab2_lib.baseboard_fab2(sch_1):page182_i79:gnd9" )
			)
			( pin "J1C1.F1"
				( objectStatus "@baseboard_fab2_lib.baseboard_fab2(sch_1):page182_i79:gnd10" )
			)
			( pin "J1C1.F3"
				( objectStatus "@baseboard_fab2_lib.baseboard_fab2(sch_1):page182_i79:gnd11" )
			)
			( pin "J1C1.F7"
				( objectStatus "@baseboard_fab2_lib.baseboard_fab2(sch_1):page182_i79:gnd12" )
			)
			( pin "J1C1.G2"
				( objectStatus "@baseboard_fab2_lib.baseboard_fab2(sch_1):page182_i79:gnd13" )
			)
			( pin "J1C1.G4"
				( objectStatus "@baseboard_fab2_lib.baseboard_fab2(sch_1):page182_i79:gnd14" )
			)
			( pin "J1C1.G6"
				( objectStatus "@baseboard_fab2_lib.baseboard_fab2(sch_1):page182_i79:gnd15" )
			)
			( pin "J1C1.G8"
				( objectStatus "@baseboard_fab2_lib.baseboard_fab2(sch_1):page182_i79:gnd16" )
			)
			( pin "J1C1.I1"
				( objectStatus "@baseboard_fab2_lib.baseboard_fab2(sch_1):page182_i79:gnd17" )
			)
			( pin "J1C1.I7"
				( objectStatus "@baseboard_fab2_lib.baseboard_fab2(sch_1):page182_i79:gnd18" )
			)
			( pin "J1C1.J2"
				( objectStatus "@baseboard_fab2_lib.baseboard_fab2(sch_1):page182_i79:j2" )
			)
			( pin "J1C1.J4"
				( objectStatus "@baseboard_fab2_lib.baseboard_fab2(sch_1):page182_i79:j4" )
			)
			( pin "J1C1.J6"
				( objectStatus "@baseboard_fab2_lib.baseboard_fab2(sch_1):page182_i79:j6" )
			)
			( pin "J1C1.J8"
				( objectStatus "@baseboard_fab2_lib.baseboard_fab2(sch_1):page182_i79:j8" )
			)
			( pin "J1C1.E4"
				( objectStatus "@baseboard_fab2_lib.baseboard_fab2(sch_1):page182_i79:\mated_in#\" )
			)
			( pin "J1C1.I3"
				( objectStatus "@baseboard_fab2_lib.baseboard_fab2(sch_1):page182_i79:\mb_on#\" )
			)
			( pin "J1C1.F5"
				( objectStatus "@baseboard_fab2_lib.baseboard_fab2(sch_1):page182_i79:mb_slot_id0" )
			)
			( pin "J1C1.G5"
				( objectStatus "@baseboard_fab2_lib.baseboard_fab2(sch_1):page182_i79:mb_slot_id1" )
			)
			( pin "J1C1.H5"
				( objectStatus "@baseboard_fab2_lib.baseboard_fab2(sch_1):page182_i79:mb_slot_id2" )
			)
			( pin "J1C1.E5"
				( objectStatus "@baseboard_fab2_lib.baseboard_fab2(sch_1):page182_i79:mng_rx_dn" )
			)
			( pin "J1C1.D5"
				( objectStatus "@baseboard_fab2_lib.baseboard_fab2(sch_1):page182_i79:mng_rx_dp" )
			)
			( pin "J1C1.B5"
				( objectStatus "@baseboard_fab2_lib.baseboard_fab2(sch_1):page182_i79:mng_tx_dn" )
			)
			( pin "J1C1.A5"
				( objectStatus "@baseboard_fab2_lib.baseboard_fab2(sch_1):page182_i79:mng_tx_dp" )
			)
			( pin "J1C1.I4"
				( objectStatus "@baseboard_fab2_lib.baseboard_fab2(sch_1):page182_i79:pcie_clk_100m_dn" )
			)
			( pin "J1C1.H4"
				( objectStatus "@baseboard_fab2_lib.baseboard_fab2(sch_1):page182_i79:pcie_clk_100m_dp" )
			)
			( pin "J1C1.I5"
				( objectStatus "@baseboard_fab2_lib.baseboard_fab2(sch_1):page182_i79:\pcie_perst#\" )
			)
			( pin "J1C1.B1"
				( objectStatus "@baseboard_fab2_lib.baseboard_fab2(sch_1):page182_i79:pcie_rx_dn0" )
			)
			( pin "J1C1.E1"
				( objectStatus "@baseboard_fab2_lib.baseboard_fab2(sch_1):page182_i79:pcie_rx_dn1" )
			)
			( pin "J1C1.H1"
				( objectStatus "@baseboard_fab2_lib.baseboard_fab2(sch_1):page182_i79:pcie_rx_dn2" )
			)
			( pin "J1C1.C2"
				( objectStatus "@baseboard_fab2_lib.baseboard_fab2(sch_1):page182_i79:pcie_rx_dn3" )
			)
			( pin "J1C1.F2"
				( objectStatus "@baseboard_fab2_lib.baseboard_fab2(sch_1):page182_i79:pcie_rx_dn4" )
			)
			( pin "J1C1.I2"
				( objectStatus "@baseboard_fab2_lib.baseboard_fab2(sch_1):page182_i79:pcie_rx_dn5" )
			)
			( pin "J1C1.B3"
				( objectStatus "@baseboard_fab2_lib.baseboard_fab2(sch_1):page182_i79:pcie_rx_dn6" )
			)
			( pin "J1C1.E3"
				( objectStatus "@baseboard_fab2_lib.baseboard_fab2(sch_1):page182_i79:pcie_rx_dn7" )
			)
			( pin "J1C1.A1"
				( objectStatus "@baseboard_fab2_lib.baseboard_fab2(sch_1):page182_i79:pcie_rx_dp0" )
			)
			( pin "J1C1.D1"
				( objectStatus "@baseboard_fab2_lib.baseboard_fab2(sch_1):page182_i79:pcie_rx_dp1" )
			)
			( pin "J1C1.G1"
				( objectStatus "@baseboard_fab2_lib.baseboard_fab2(sch_1):page182_i79:pcie_rx_dp2" )
			)
			( pin "J1C1.B2"
				( objectStatus "@baseboard_fab2_lib.baseboard_fab2(sch_1):page182_i79:pcie_rx_dp3" )
			)
			( pin "J1C1.E2"
				( objectStatus "@baseboard_fab2_lib.baseboard_fab2(sch_1):page182_i79:pcie_rx_dp4" )
			)
			( pin "J1C1.H2"
				( objectStatus "@baseboard_fab2_lib.baseboard_fab2(sch_1):page182_i79:pcie_rx_dp5" )
			)
			( pin "J1C1.A3"
				( objectStatus "@baseboard_fab2_lib.baseboard_fab2(sch_1):page182_i79:pcie_rx_dp6" )
			)
			( pin "J1C1.D3"
				( objectStatus "@baseboard_fab2_lib.baseboard_fab2(sch_1):page182_i79:pcie_rx_dp7" )
			)
			( pin "J1C1.C8"
				( objectStatus "@baseboard_fab2_lib.baseboard_fab2(sch_1):page182_i79:pcie_tx_dn0" )
			)
			( pin "J1C1.F8"
				( objectStatus "@baseboard_fab2_lib.baseboard_fab2(sch_1):page182_i79:pcie_tx_dn1" )
			)
			( pin "J1C1.I8"
				( objectStatus "@baseboard_fab2_lib.baseboard_fab2(sch_1):page182_i79:pcie_tx_dn2" )
			)
			( pin "J1C1.B7"
				( objectStatus "@baseboard_fab2_lib.baseboard_fab2(sch_1):page182_i79:pcie_tx_dn3" )
			)
			( pin "J1C1.E7"
				( objectStatus "@baseboard_fab2_lib.baseboard_fab2(sch_1):page182_i79:pcie_tx_dn4" )
			)
			( pin "J1C1.H7"
				( objectStatus "@baseboard_fab2_lib.baseboard_fab2(sch_1):page182_i79:pcie_tx_dn5" )
			)
			( pin "J1C1.F6"
				( objectStatus "@baseboard_fab2_lib.baseboard_fab2(sch_1):page182_i79:pcie_tx_dn6" )
			)
			( pin "J1C1.I6"
				( objectStatus "@baseboard_fab2_lib.baseboard_fab2(sch_1):page182_i79:pcie_tx_dn7" )
			)
			( pin "J1C1.B8"
				( objectStatus "@baseboard_fab2_lib.baseboard_fab2(sch_1):page182_i79:pcie_tx_dp0" )
			)
			( pin "J1C1.E8"
				( objectStatus "@baseboard_fab2_lib.baseboard_fab2(sch_1):page182_i79:pcie_tx_dp1" )
			)
			( pin "J1C1.H8"
				( objectStatus "@baseboard_fab2_lib.baseboard_fab2(sch_1):page182_i79:pcie_tx_dp2" )
			)
			( pin "J1C1.A7"
				( objectStatus "@baseboard_fab2_lib.baseboard_fab2(sch_1):page182_i79:pcie_tx_dp3" )
			)
			( pin "J1C1.D7"
				( objectStatus "@baseboard_fab2_lib.baseboard_fab2(sch_1):page182_i79:pcie_tx_dp4" )
			)
			( pin "J1C1.G7"
				( objectStatus "@baseboard_fab2_lib.baseboard_fab2(sch_1):page182_i79:pcie_tx_dp5" )
			)
			( pin "J1C1.E6"
				( objectStatus "@baseboard_fab2_lib.baseboard_fab2(sch_1):page182_i79:pcie_tx_dp6" )
			)
			( pin "J1C1.H6"
				( objectStatus "@baseboard_fab2_lib.baseboard_fab2(sch_1):page182_i79:pcie_tx_dp7" )
			)
			( pin "J1C1.A6"
				( objectStatus "@baseboard_fab2_lib.baseboard_fab2(sch_1):page182_i79:\pmbus_alert#\" )
			)
			( pin "J1C1.C6"
				( objectStatus "@baseboard_fab2_lib.baseboard_fab2(sch_1):page182_i79:pmbus_clk" )
			)
			( pin "J1C1.B6"
				( objectStatus "@baseboard_fab2_lib.baseboard_fab2(sch_1):page182_i79:pmbus_data" )
			)
			( pin "C8E4.1"
				( objectStatus "@baseboard_fab2_lib.baseboard_fab2(sch_1):page241_i100:\1\" )
			)
			( pin "C8E4.2"
				( objectStatus "@baseboard_fab2_lib.baseboard_fab2(sch_1):page241_i100:\2\" )
			)
			( pin "J1F1.H3"
				( objectStatus "@baseboard_fab2_lib.baseboard_fab2(sch_1):page181_i134:com_rx" )
			)
			( pin "J1F1.G3"
				( objectStatus "@baseboard_fab2_lib.baseboard_fab2(sch_1):page181_i134:com_tx" )
			)
			( pin "J1F1.F4"
				( objectStatus "@baseboard_fab2_lib.baseboard_fab2(sch_1):page181_i134:fan_pwm0" )
			)
			( pin "J1F1.D4"
				( objectStatus "@baseboard_fab2_lib.baseboard_fab2(sch_1):page181_i134:fan_tach0" )
			)
			( pin "J1F1.C4"
				( objectStatus "@baseboard_fab2_lib.baseboard_fab2(sch_1):page181_i134:fan_tach1" )
			)
			( pin "J1F1.B4"
				( objectStatus "@baseboard_fab2_lib.baseboard_fab2(sch_1):page181_i134:fan_tach2" )
			)
			( pin "J1F1.A4"
				( objectStatus "@baseboard_fab2_lib.baseboard_fab2(sch_1):page181_i134:fan_tach3" )
			)
			( pin "J1F1.A2"
				( objectStatus "@baseboard_fab2_lib.baseboard_fab2(sch_1):page181_i134:gnd1" )
			)
			( pin "J1F1.A8"
				( objectStatus "@baseboard_fab2_lib.baseboard_fab2(sch_1):page181_i134:gnd2" )
			)
			( pin "J1F1.C1"
				( objectStatus "@baseboard_fab2_lib.baseboard_fab2(sch_1):page181_i134:gnd3" )
			)
			( pin "J1F1.C3"
				( objectStatus "@baseboard_fab2_lib.baseboard_fab2(sch_1):page181_i134:gnd4" )
			)
			( pin "J1F1.C5"
				( objectStatus "@baseboard_fab2_lib.baseboard_fab2(sch_1):page181_i134:gnd5" )
			)
			( pin "J1F1.C7"
				( objectStatus "@baseboard_fab2_lib.baseboard_fab2(sch_1):page181_i134:gnd6" )
			)
			( pin "J1F1.D2"
				( objectStatus "@baseboard_fab2_lib.baseboard_fab2(sch_1):page181_i134:gnd7" )
			)
			( pin "J1F1.D6"
				( objectStatus "@baseboard_fab2_lib.baseboard_fab2(sch_1):page181_i134:gnd8" )
			)
			( pin "J1F1.D8"
				( objectStatus "@baseboard_fab2_lib.baseboard_fab2(sch_1):page181_i134:gnd9" )
			)
			( pin "J1F1.F1"
				( objectStatus "@baseboard_fab2_lib.baseboard_fab2(sch_1):page181_i134:gnd10" )
			)
			( pin "J1F1.F3"
				( objectStatus "@baseboard_fab2_lib.baseboard_fab2(sch_1):page181_i134:gnd11" )
			)
			( pin "J1F1.F7"
				( objectStatus "@baseboard_fab2_lib.baseboard_fab2(sch_1):page181_i134:gnd12" )
			)
			( pin "J1F1.G2"
				( objectStatus "@baseboard_fab2_lib.baseboard_fab2(sch_1):page181_i134:gnd13" )
			)
			( pin "J1F1.G4"
				( objectStatus "@baseboard_fab2_lib.baseboard_fab2(sch_1):page181_i134:gnd14" )
			)
			( pin "J1F1.G6"
				( objectStatus "@baseboard_fab2_lib.baseboard_fab2(sch_1):page181_i134:gnd15" )
			)
			( pin "J1F1.G8"
				( objectStatus "@baseboard_fab2_lib.baseboard_fab2(sch_1):page181_i134:gnd16" )
			)
			( pin "J1F1.I1"
				( objectStatus "@baseboard_fab2_lib.baseboard_fab2(sch_1):page181_i134:gnd17" )
			)
			( pin "J1F1.I7"
				( objectStatus "@baseboard_fab2_lib.baseboard_fab2(sch_1):page181_i134:gnd18" )
			)
			( pin "J1F1.J2"
				( objectStatus "@baseboard_fab2_lib.baseboard_fab2(sch_1):page181_i134:j2" )
			)
			( pin "J1F1.J4"
				( objectStatus "@baseboard_fab2_lib.baseboard_fab2(sch_1):page181_i134:j4" )
			)
			( pin "J1F1.J6"
				( objectStatus "@baseboard_fab2_lib.baseboard_fab2(sch_1):page181_i134:j6" )
			)
			( pin "J1F1.J8"
				( objectStatus "@baseboard_fab2_lib.baseboard_fab2(sch_1):page181_i134:j8" )
			)
			( pin "J1F1.E4"
				( objectStatus "@baseboard_fab2_lib.baseboard_fab2(sch_1):page181_i134:\mated_in#\" )
			)
			( pin "J1F1.I3"
				( objectStatus "@baseboard_fab2_lib.baseboard_fab2(sch_1):page181_i134:\mb_on#\" )
			)
			( pin "J1F1.F5"
				( objectStatus "@baseboard_fab2_lib.baseboard_fab2(sch_1):page181_i134:mb_slot_id0" )
			)
			( pin "J1F1.G5"
				( objectStatus "@baseboard_fab2_lib.baseboard_fab2(sch_1):page181_i134:mb_slot_id1" )
			)
			( pin "J1F1.H5"
				( objectStatus "@baseboard_fab2_lib.baseboard_fab2(sch_1):page181_i134:mb_slot_id2" )
			)
			( pin "J1F1.E5"
				( objectStatus "@baseboard_fab2_lib.baseboard_fab2(sch_1):page181_i134:mng_rx_dn" )
			)
			( pin "J1F1.D5"
				( objectStatus "@baseboard_fab2_lib.baseboard_fab2(sch_1):page181_i134:mng_rx_dp" )
			)
			( pin "J1F1.B5"
				( objectStatus "@baseboard_fab2_lib.baseboard_fab2(sch_1):page181_i134:mng_tx_dn" )
			)
			( pin "J1F1.A5"
				( objectStatus "@baseboard_fab2_lib.baseboard_fab2(sch_1):page181_i134:mng_tx_dp" )
			)
			( pin "J1F1.I4"
				( objectStatus "@baseboard_fab2_lib.baseboard_fab2(sch_1):page181_i134:pcie_clk_100m_dn" )
			)
			( pin "J1F1.H4"
				( objectStatus "@baseboard_fab2_lib.baseboard_fab2(sch_1):page181_i134:pcie_clk_100m_dp" )
			)
			( pin "J1F1.I5"
				( objectStatus "@baseboard_fab2_lib.baseboard_fab2(sch_1):page181_i134:\pcie_perst#\" )
			)
			( pin "J1F1.B1"
				( objectStatus "@baseboard_fab2_lib.baseboard_fab2(sch_1):page181_i134:pcie_rx_dn0" )
			)
			( pin "J1F1.E1"
				( objectStatus "@baseboard_fab2_lib.baseboard_fab2(sch_1):page181_i134:pcie_rx_dn1" )
			)
			( pin "J1F1.H1"
				( objectStatus "@baseboard_fab2_lib.baseboard_fab2(sch_1):page181_i134:pcie_rx_dn2" )
			)
			( pin "J1F1.C2"
				( objectStatus "@baseboard_fab2_lib.baseboard_fab2(sch_1):page181_i134:pcie_rx_dn3" )
			)
			( pin "J1F1.F2"
				( objectStatus "@baseboard_fab2_lib.baseboard_fab2(sch_1):page181_i134:pcie_rx_dn4" )
			)
			( pin "J1F1.I2"
				( objectStatus "@baseboard_fab2_lib.baseboard_fab2(sch_1):page181_i134:pcie_rx_dn5" )
			)
			( pin "J1F1.B3"
				( objectStatus "@baseboard_fab2_lib.baseboard_fab2(sch_1):page181_i134:pcie_rx_dn6" )
			)
			( pin "J1F1.E3"
				( objectStatus "@baseboard_fab2_lib.baseboard_fab2(sch_1):page181_i134:pcie_rx_dn7" )
			)
			( pin "J1F1.A1"
				( objectStatus "@baseboard_fab2_lib.baseboard_fab2(sch_1):page181_i134:pcie_rx_dp0" )
			)
			( pin "J1F1.D1"
				( objectStatus "@baseboard_fab2_lib.baseboard_fab2(sch_1):page181_i134:pcie_rx_dp1" )
			)
			( pin "J1F1.G1"
				( objectStatus "@baseboard_fab2_lib.baseboard_fab2(sch_1):page181_i134:pcie_rx_dp2" )
			)
			( pin "J1F1.B2"
				( objectStatus "@baseboard_fab2_lib.baseboard_fab2(sch_1):page181_i134:pcie_rx_dp3" )
			)
			( pin "J1F1.E2"
				( objectStatus "@baseboard_fab2_lib.baseboard_fab2(sch_1):page181_i134:pcie_rx_dp4" )
			)
			( pin "J1F1.H2"
				( objectStatus "@baseboard_fab2_lib.baseboard_fab2(sch_1):page181_i134:pcie_rx_dp5" )
			)
			( pin "J1F1.A3"
				( objectStatus "@baseboard_fab2_lib.baseboard_fab2(sch_1):page181_i134:pcie_rx_dp6" )
			)
			( pin "J1F1.D3"
				( objectStatus "@baseboard_fab2_lib.baseboard_fab2(sch_1):page181_i134:pcie_rx_dp7" )
			)
			( pin "J1F1.C8"
				( objectStatus "@baseboard_fab2_lib.baseboard_fab2(sch_1):page181_i134:pcie_tx_dn0" )
			)
			( pin "J1F1.F8"
				( objectStatus "@baseboard_fab2_lib.baseboard_fab2(sch_1):page181_i134:pcie_tx_dn1" )
			)
			( pin "J1F1.I8"
				( objectStatus "@baseboard_fab2_lib.baseboard_fab2(sch_1):page181_i134:pcie_tx_dn2" )
			)
			( pin "J1F1.B7"
				( objectStatus "@baseboard_fab2_lib.baseboard_fab2(sch_1):page181_i134:pcie_tx_dn3" )
			)
			( pin "J1F1.E7"
				( objectStatus "@baseboard_fab2_lib.baseboard_fab2(sch_1):page181_i134:pcie_tx_dn4" )
			)
			( pin "J1F1.H7"
				( objectStatus "@baseboard_fab2_lib.baseboard_fab2(sch_1):page181_i134:pcie_tx_dn5" )
			)
			( pin "J1F1.F6"
				( objectStatus "@baseboard_fab2_lib.baseboard_fab2(sch_1):page181_i134:pcie_tx_dn6" )
			)
			( pin "J1F1.I6"
				( objectStatus "@baseboard_fab2_lib.baseboard_fab2(sch_1):page181_i134:pcie_tx_dn7" )
			)
			( pin "J1F1.B8"
				( objectStatus "@baseboard_fab2_lib.baseboard_fab2(sch_1):page181_i134:pcie_tx_dp0" )
			)
			( pin "J1F1.E8"
				( objectStatus "@baseboard_fab2_lib.baseboard_fab2(sch_1):page181_i134:pcie_tx_dp1" )
			)
			( pin "J1F1.H8"
				( objectStatus "@baseboard_fab2_lib.baseboard_fab2(sch_1):page181_i134:pcie_tx_dp2" )
			)
			( pin "J1F1.A7"
				( objectStatus "@baseboard_fab2_lib.baseboard_fab2(sch_1):page181_i134:pcie_tx_dp3" )
			)
			( pin "J1F1.D7"
				( objectStatus "@baseboard_fab2_lib.baseboard_fab2(sch_1):page181_i134:pcie_tx_dp4" )
			)
			( pin "J1F1.G7"
				( objectStatus "@baseboard_fab2_lib.baseboard_fab2(sch_1):page181_i134:pcie_tx_dp5" )
			)
			( pin "J1F1.E6"
				( objectStatus "@baseboard_fab2_lib.baseboard_fab2(sch_1):page181_i134:pcie_tx_dp6" )
			)
			( pin "J1F1.H6"
				( objectStatus "@baseboard_fab2_lib.baseboard_fab2(sch_1):page181_i134:pcie_tx_dp7" )
			)
			( pin "J1F1.A6"
				( objectStatus "@baseboard_fab2_lib.baseboard_fab2(sch_1):page181_i134:\pmbus_alert#\" )
			)
			( pin "J1F1.C6"
				( objectStatus "@baseboard_fab2_lib.baseboard_fab2(sch_1):page181_i134:pmbus_clk" )
			)
			( pin "J1F1.B6"
				( objectStatus "@baseboard_fab2_lib.baseboard_fab2(sch_1):page181_i134:pmbus_data" )
			)
			( pin "R2U35.1"
				( objectStatus "@baseboard_fab2_lib.baseboard_fab2(sch_1):page108_i350:a" )
			)
			( pin "R2U35.2"
				( objectStatus "@baseboard_fab2_lib.baseboard_fab2(sch_1):page108_i350:b" )
			)
			( pin "R2U36.1"
				( objectStatus "@baseboard_fab2_lib.baseboard_fab2(sch_1):page108_i351:a" )
			)
			( pin "R2U36.2"
				( objectStatus "@baseboard_fab2_lib.baseboard_fab2(sch_1):page108_i351:b" )
			)
			( pin "R24W1.1"
				( objectStatus "@baseboard_fab2_lib.baseboard_fab2(sch_1):page138_i198:a" )
			)
			( pin "R24W1.2"
				( objectStatus "@baseboard_fab2_lib.baseboard_fab2(sch_1):page138_i198:b" )
			)
			( pin "R24W2.1"
				( objectStatus "@baseboard_fab2_lib.baseboard_fab2(sch_1):page138_i199:a" )
			)
			( pin "R24W2.2"
				( objectStatus "@baseboard_fab2_lib.baseboard_fab2(sch_1):page138_i199:b" )
			)
			( pin "R1U21.1"
				( objectStatus "@baseboard_fab2_lib.baseboard_fab2(sch_1):page164_i41:a" )
			)
			( pin "R1U21.2"
				( objectStatus "@baseboard_fab2_lib.baseboard_fab2(sch_1):page164_i41:b" )
			)
			( pin "R1U22.1"
				( objectStatus "@baseboard_fab2_lib.baseboard_fab2(sch_1):page164_i43:a" )
			)
			( pin "R1U22.2"
				( objectStatus "@baseboard_fab2_lib.baseboard_fab2(sch_1):page164_i43:b" )
			)
			( pin "CN8F1.1"
				( objectStatus "@baseboard_fab2_lib.baseboard_fab2(sch_1):page246_i21:a" )
			)
			( pin "CN8F1.2"
				( objectStatus "@baseboard_fab2_lib.baseboard_fab2(sch_1):page246_i21:b" )
			)
			( pin "C25W11.1"
				( objectStatus "@baseboard_fab2_lib.baseboard_fab2(sch_1):page151_i214:a" )
			)
			( pin "C25W11.2"
				( objectStatus "@baseboard_fab2_lib.baseboard_fab2(sch_1):page151_i214:b" )
			)
			( pin "C25W38.1"
				( objectStatus "@baseboard_fab2_lib.baseboard_fab2(sch_1):page149_i121:a" )
			)
			( pin "C25W38.2"
				( objectStatus "@baseboard_fab2_lib.baseboard_fab2(sch_1):page149_i121:b" )
			)
			( pin "C25W45.1"
				( objectStatus "@baseboard_fab2_lib.baseboard_fab2(sch_1):page149_i122:a" )
			)
			( pin "C25W45.2"
				( objectStatus "@baseboard_fab2_lib.baseboard_fab2(sch_1):page149_i122:b" )
			)
			( pin "C5L3.1"
				( objectStatus "@baseboard_fab2_lib.baseboard_fab2(sch_1):page220_i310:a" )
			)
			( pin "C5L3.2"
				( objectStatus "@baseboard_fab2_lib.baseboard_fab2(sch_1):page220_i310:b" )
			)
			( pin "C5L1.1"
				( objectStatus "@baseboard_fab2_lib.baseboard_fab2(sch_1):page220_i309:a" )
			)
			( pin "C5L1.2"
				( objectStatus "@baseboard_fab2_lib.baseboard_fab2(sch_1):page220_i309:b" )
			)
			( pin "C5G20.1"
				( objectStatus "@baseboard_fab2_lib.baseboard_fab2(sch_1):page217_i329:a" )
			)
			( pin "C5G20.2"
				( objectStatus "@baseboard_fab2_lib.baseboard_fab2(sch_1):page217_i329:b" )
			)
			( pin "C8P2.1"
				( objectStatus "@baseboard_fab2_lib.baseboard_fab2(sch_1):page228_i303:a" )
			)
			( pin "C8P2.2"
				( objectStatus "@baseboard_fab2_lib.baseboard_fab2(sch_1):page228_i303:b" )
			)
			( pin "C5P1.1"
				( objectStatus "@baseboard_fab2_lib.baseboard_fab2(sch_1):page220_i320:a" )
			)
			( pin "C5P1.2"
				( objectStatus "@baseboard_fab2_lib.baseboard_fab2(sch_1):page220_i320:b" )
			)
			( pin "C5P2.1"
				( objectStatus "@baseboard_fab2_lib.baseboard_fab2(sch_1):page220_i319:a" )
			)
			( pin "C5P2.2"
				( objectStatus "@baseboard_fab2_lib.baseboard_fab2(sch_1):page220_i319:b" )
			)
			( pin "R25W155.1"
				( objectStatus "@baseboard_fab2_lib.baseboard_fab2(sch_1):page148_i29:a" )
			)
			( pin "R25W155.2"
				( objectStatus "@baseboard_fab2_lib.baseboard_fab2(sch_1):page148_i29:b" )
			)
			( pin "R8W7.1"
				( objectStatus "@baseboard_fab2_lib.baseboard_fab2(sch_1):page138_i202:a" )
			)
			( pin "R8W7.2"
				( objectStatus "@baseboard_fab2_lib.baseboard_fab2(sch_1):page138_i202:b" )
			)
			( pin "R8W6.1"
				( objectStatus "@baseboard_fab2_lib.baseboard_fab2(sch_1):page138_i205:a" )
			)
			( pin "R8W6.2"
				( objectStatus "@baseboard_fab2_lib.baseboard_fab2(sch_1):page138_i205:b" )
			)
			( pin "R8C15.1"
				( objectStatus "@baseboard_fab2_lib.baseboard_fab2(sch_1):page159_i235:a" )
			)
			( pin "R8C15.2"
				( objectStatus "@baseboard_fab2_lib.baseboard_fab2(sch_1):page159_i235:b" )
			)
			( pin "R8C16.1"
				( objectStatus "@baseboard_fab2_lib.baseboard_fab2(sch_1):page159_i237:a" )
			)
			( pin "R8C16.2"
				( objectStatus "@baseboard_fab2_lib.baseboard_fab2(sch_1):page159_i237:b" )
			)
			( pin "C2D45.1"
				( objectStatus "@baseboard_fab2_lib.baseboard_fab2(sch_1):page225_i261:a" )
			)
			( pin "C2D45.2"
				( objectStatus "@baseboard_fab2_lib.baseboard_fab2(sch_1):page225_i261:b" )
			)
			( pin "C2D3.1"
				( objectStatus "@baseboard_fab2_lib.baseboard_fab2(sch_1):page228_i256:a" )
			)
			( pin "C2D3.2"
				( objectStatus "@baseboard_fab2_lib.baseboard_fab2(sch_1):page228_i256:b" )
			)
			( pin "C3D1.1"
				( objectStatus "@baseboard_fab2_lib.baseboard_fab2(sch_1):page228_i255:a" )
			)
			( pin "C3D1.2"
				( objectStatus "@baseboard_fab2_lib.baseboard_fab2(sch_1):page228_i255:b" )
			)
			( pin "RM1G1.1"
				( objectStatus "@baseboard_fab2_lib.baseboard_fab2(sch_1):page195_i117:\1\" )
			)
			( pin "R4E10.1"
				( objectStatus "@baseboard_fab2_lib.baseboard_fab2(sch_1):page201_i190:a" )
			)
			( pin "R4E10.2"
				( objectStatus "@baseboard_fab2_lib.baseboard_fab2(sch_1):page201_i190:b" )
			)
			( pin "R8W8.1"
				( objectStatus "@baseboard_fab2_lib.baseboard_fab2(sch_1):page235_i249:a" )
			)
			( pin "R8W8.2"
				( objectStatus "@baseboard_fab2_lib.baseboard_fab2(sch_1):page235_i249:b" )
			)
			( pin "R4W2.1"
				( objectStatus "@baseboard_fab2_lib.baseboard_fab2(sch_1):page102_i103:a" )
			)
			( pin "R4W2.2"
				( objectStatus "@baseboard_fab2_lib.baseboard_fab2(sch_1):page102_i103:b" )
			)
			( pin "Q4W1.3"
				( objectStatus "@baseboard_fab2_lib.baseboard_fab2(sch_1):page102_i101:drain(0)" )
			)
			( pin "Q4W1.5"
				( objectStatus "@baseboard_fab2_lib.baseboard_fab2(sch_1):page102_i101:gate(0)" )
			)
			( pin "Q4W1.4"
				( objectStatus "@baseboard_fab2_lib.baseboard_fab2(sch_1):page102_i101:source(0)" )
			)
			( pin "R4W4.1"
				( objectStatus "@baseboard_fab2_lib.baseboard_fab2(sch_1):page102_i106:a" )
			)
			( pin "R4W4.2"
				( objectStatus "@baseboard_fab2_lib.baseboard_fab2(sch_1):page102_i106:b" )
			)
			( pin "Q4W2.3"
				( objectStatus "@baseboard_fab2_lib.baseboard_fab2(sch_1):page102_i112:drn" )
			)
			( pin "Q4W2.1"
				( objectStatus "@baseboard_fab2_lib.baseboard_fab2(sch_1):page102_i112:gate" )
			)
			( pin "Q4W2.2"
				( objectStatus "@baseboard_fab2_lib.baseboard_fab2(sch_1):page102_i112:src" )
			)
			( pin "R4W6.1"
				( objectStatus "@baseboard_fab2_lib.baseboard_fab2(sch_1):page102_i109:a" )
			)
			( pin "R4W6.2"
				( objectStatus "@baseboard_fab2_lib.baseboard_fab2(sch_1):page102_i109:b" )
			)
			( pin "R4W5.1"
				( objectStatus "@baseboard_fab2_lib.baseboard_fab2(sch_1):page102_i114:a" )
			)
			( pin "R4W5.2"
				( objectStatus "@baseboard_fab2_lib.baseboard_fab2(sch_1):page102_i114:b" )
			)
			( pin "R12W1.1"
				( objectStatus "@baseboard_fab2_lib.baseboard_fab2(sch_1):page197_i101:\1\" )
			)
			( pin "R12W1.2"
				( objectStatus "@baseboard_fab2_lib.baseboard_fab2(sch_1):page197_i101:\2\" )
			)
			( pin "R12W11.1"
				( objectStatus "@baseboard_fab2_lib.baseboard_fab2(sch_1):page197_i118:\1\" )
			)
			( pin "R12W11.2"
				( objectStatus "@baseboard_fab2_lib.baseboard_fab2(sch_1):page197_i118:\2\" )
			)
			( pin "C8U1.1"
				( objectStatus "@baseboard_fab2_lib.baseboard_fab2(sch_1):page225_i319:a" )
			)
			( pin "C8U1.2"
				( objectStatus "@baseboard_fab2_lib.baseboard_fab2(sch_1):page225_i319:b" )
			)
			( pin "C2A8.1"
				( objectStatus "@baseboard_fab2_lib.baseboard_fab2(sch_1):page228_i309:a" )
			)
			( pin "C2A8.2"
				( objectStatus "@baseboard_fab2_lib.baseboard_fab2(sch_1):page228_i309:b" )
			)
			( pin "C5P44.1"
				( objectStatus "@baseboard_fab2_lib.baseboard_fab2(sch_1):page217_i324:a" )
			)
			( pin "C5P44.2"
				( objectStatus "@baseboard_fab2_lib.baseboard_fab2(sch_1):page217_i324:b" )
			)
			( pin "C5D54.1"
				( objectStatus "@baseboard_fab2_lib.baseboard_fab2(sch_1):page217_i279:a" )
			)
			( pin "C5D54.2"
				( objectStatus "@baseboard_fab2_lib.baseboard_fab2(sch_1):page217_i279:b" )
			)
			( pin "C5D55.1"
				( objectStatus "@baseboard_fab2_lib.baseboard_fab2(sch_1):page217_i280:a" )
			)
			( pin "C5D55.2"
				( objectStatus "@baseboard_fab2_lib.baseboard_fab2(sch_1):page217_i280:b" )
			)
			( pin "C5D56.1"
				( objectStatus "@baseboard_fab2_lib.baseboard_fab2(sch_1):page217_i281:a" )
			)
			( pin "C5D56.2"
				( objectStatus "@baseboard_fab2_lib.baseboard_fab2(sch_1):page217_i281:b" )
			)
			( pin "C5D57.1"
				( objectStatus "@baseboard_fab2_lib.baseboard_fab2(sch_1):page217_i282:a" )
			)
			( pin "C5D57.2"
				( objectStatus "@baseboard_fab2_lib.baseboard_fab2(sch_1):page217_i282:b" )
			)
			( pin "C5U6.1"
				( objectStatus "@baseboard_fab2_lib.baseboard_fab2(sch_1):page217_i287:a" )
			)
			( pin "C5U6.2"
				( objectStatus "@baseboard_fab2_lib.baseboard_fab2(sch_1):page217_i287:b" )
			)
			( pin "C5U7.1"
				( objectStatus "@baseboard_fab2_lib.baseboard_fab2(sch_1):page217_i288:a" )
			)
			( pin "C5U7.2"
				( objectStatus "@baseboard_fab2_lib.baseboard_fab2(sch_1):page217_i288:b" )
			)
			( pin "C5U8.1"
				( objectStatus "@baseboard_fab2_lib.baseboard_fab2(sch_1):page217_i289:a" )
			)
			( pin "C5U8.2"
				( objectStatus "@baseboard_fab2_lib.baseboard_fab2(sch_1):page217_i289:b" )
			)
			( pin "C5U9.1"
				( objectStatus "@baseboard_fab2_lib.baseboard_fab2(sch_1):page217_i290:a" )
			)
			( pin "C5U9.2"
				( objectStatus "@baseboard_fab2_lib.baseboard_fab2(sch_1):page217_i290:b" )
			)
			( pin "C5T12.1"
				( objectStatus "@baseboard_fab2_lib.baseboard_fab2(sch_1):page217_i291:a" )
			)
			( pin "C5T12.2"
				( objectStatus "@baseboard_fab2_lib.baseboard_fab2(sch_1):page217_i291:b" )
			)
			( pin "C5T11.1"
				( objectStatus "@baseboard_fab2_lib.baseboard_fab2(sch_1):page217_i292:a" )
			)
			( pin "C5T11.2"
				( objectStatus "@baseboard_fab2_lib.baseboard_fab2(sch_1):page217_i292:b" )
			)
			( pin "C5T10.1"
				( objectStatus "@baseboard_fab2_lib.baseboard_fab2(sch_1):page217_i293:a" )
			)
			( pin "C5T10.2"
				( objectStatus "@baseboard_fab2_lib.baseboard_fab2(sch_1):page217_i293:b" )
			)
			( pin "C5T9.1"
				( objectStatus "@baseboard_fab2_lib.baseboard_fab2(sch_1):page217_i294:a" )
			)
			( pin "C5T9.2"
				( objectStatus "@baseboard_fab2_lib.baseboard_fab2(sch_1):page217_i294:b" )
			)
			( pin "C5T8.1"
				( objectStatus "@baseboard_fab2_lib.baseboard_fab2(sch_1):page217_i295:a" )
			)
			( pin "C5T8.2"
				( objectStatus "@baseboard_fab2_lib.baseboard_fab2(sch_1):page217_i295:b" )
			)
			( pin "C5T7.1"
				( objectStatus "@baseboard_fab2_lib.baseboard_fab2(sch_1):page217_i296:a" )
			)
			( pin "C5T7.2"
				( objectStatus "@baseboard_fab2_lib.baseboard_fab2(sch_1):page217_i296:b" )
			)
			( pin "C5T6.1"
				( objectStatus "@baseboard_fab2_lib.baseboard_fab2(sch_1):page217_i297:a" )
			)
			( pin "C5T6.2"
				( objectStatus "@baseboard_fab2_lib.baseboard_fab2(sch_1):page217_i297:b" )
			)
			( pin "C5T5.1"
				( objectStatus "@baseboard_fab2_lib.baseboard_fab2(sch_1):page217_i298:a" )
			)
			( pin "C5T5.2"
				( objectStatus "@baseboard_fab2_lib.baseboard_fab2(sch_1):page217_i298:b" )
			)
			( pin "C3G5.1"
				( objectStatus "@baseboard_fab2_lib.baseboard_fab2(sch_1):page225_i288:a" )
			)
			( pin "C3G5.2"
				( objectStatus "@baseboard_fab2_lib.baseboard_fab2(sch_1):page225_i288:b" )
			)
			( pin "C3G6.1"
				( objectStatus "@baseboard_fab2_lib.baseboard_fab2(sch_1):page225_i289:a" )
			)
			( pin "C3G6.2"
				( objectStatus "@baseboard_fab2_lib.baseboard_fab2(sch_1):page225_i289:b" )
			)
			( pin "C8U7.1"
				( objectStatus "@baseboard_fab2_lib.baseboard_fab2(sch_1):page225_i290:a" )
			)
			( pin "C8U7.2"
				( objectStatus "@baseboard_fab2_lib.baseboard_fab2(sch_1):page225_i290:b" )
			)
			( pin "C8U2.1"
				( objectStatus "@baseboard_fab2_lib.baseboard_fab2(sch_1):page225_i291:a" )
			)
			( pin "C8U2.2"
				( objectStatus "@baseboard_fab2_lib.baseboard_fab2(sch_1):page225_i291:b" )
			)
			( pin "C7U2.1"
				( objectStatus "@baseboard_fab2_lib.baseboard_fab2(sch_1):page225_i292:a" )
			)
			( pin "C7U2.2"
				( objectStatus "@baseboard_fab2_lib.baseboard_fab2(sch_1):page225_i292:b" )
			)
			( pin "C7U1.1"
				( objectStatus "@baseboard_fab2_lib.baseboard_fab2(sch_1):page225_i293:a" )
			)
			( pin "C7U1.2"
				( objectStatus "@baseboard_fab2_lib.baseboard_fab2(sch_1):page225_i293:b" )
			)
			( pin "C8U3.1"
				( objectStatus "@baseboard_fab2_lib.baseboard_fab2(sch_1):page225_i294:a" )
			)
			( pin "C8U3.2"
				( objectStatus "@baseboard_fab2_lib.baseboard_fab2(sch_1):page225_i294:b" )
			)
			( pin "C7T4.1"
				( objectStatus "@baseboard_fab2_lib.baseboard_fab2(sch_1):page225_i295:a" )
			)
			( pin "C7T4.2"
				( objectStatus "@baseboard_fab2_lib.baseboard_fab2(sch_1):page225_i295:b" )
			)
			( pin "C7T5.1"
				( objectStatus "@baseboard_fab2_lib.baseboard_fab2(sch_1):page225_i296:a" )
			)
			( pin "C7T5.2"
				( objectStatus "@baseboard_fab2_lib.baseboard_fab2(sch_1):page225_i296:b" )
			)
			( pin "C8T5.1"
				( objectStatus "@baseboard_fab2_lib.baseboard_fab2(sch_1):page225_i297:a" )
			)
			( pin "C8T5.2"
				( objectStatus "@baseboard_fab2_lib.baseboard_fab2(sch_1):page225_i297:b" )
			)
			( pin "C8U6.1"
				( objectStatus "@baseboard_fab2_lib.baseboard_fab2(sch_1):page225_i298:a" )
			)
			( pin "C8U6.2"
				( objectStatus "@baseboard_fab2_lib.baseboard_fab2(sch_1):page225_i298:b" )
			)
			( pin "C8T6.1"
				( objectStatus "@baseboard_fab2_lib.baseboard_fab2(sch_1):page225_i299:a" )
			)
			( pin "C8T6.2"
				( objectStatus "@baseboard_fab2_lib.baseboard_fab2(sch_1):page225_i299:b" )
			)
			( pin "C8T7.1"
				( objectStatus "@baseboard_fab2_lib.baseboard_fab2(sch_1):page225_i300:a" )
			)
			( pin "C8T7.2"
				( objectStatus "@baseboard_fab2_lib.baseboard_fab2(sch_1):page225_i300:b" )
			)
			( pin "C8T8.1"
				( objectStatus "@baseboard_fab2_lib.baseboard_fab2(sch_1):page225_i301:a" )
			)
			( pin "C8T8.2"
				( objectStatus "@baseboard_fab2_lib.baseboard_fab2(sch_1):page225_i301:b" )
			)
			( pin "C8U5.1"
				( objectStatus "@baseboard_fab2_lib.baseboard_fab2(sch_1):page225_i302:a" )
			)
			( pin "C8U5.2"
				( objectStatus "@baseboard_fab2_lib.baseboard_fab2(sch_1):page225_i302:b" )
			)
			( pin "C8T9.1"
				( objectStatus "@baseboard_fab2_lib.baseboard_fab2(sch_1):page225_i303:a" )
			)
			( pin "C8T9.2"
				( objectStatus "@baseboard_fab2_lib.baseboard_fab2(sch_1):page225_i303:b" )
			)
			( pin "C8T10.1"
				( objectStatus "@baseboard_fab2_lib.baseboard_fab2(sch_1):page225_i304:a" )
			)
			( pin "C8T10.2"
				( objectStatus "@baseboard_fab2_lib.baseboard_fab2(sch_1):page225_i304:b" )
			)
			( pin "C8U4.1"
				( objectStatus "@baseboard_fab2_lib.baseboard_fab2(sch_1):page225_i305:a" )
			)
			( pin "C8U4.2"
				( objectStatus "@baseboard_fab2_lib.baseboard_fab2(sch_1):page225_i305:b" )
			)
			( pin "C5P6.1"
				( objectStatus "@baseboard_fab2_lib.baseboard_fab2(sch_1):page220_i316:a" )
			)
			( pin "C5P6.2"
				( objectStatus "@baseboard_fab2_lib.baseboard_fab2(sch_1):page220_i316:b" )
			)
			( pin "C7W5.1"
				( objectStatus "@baseboard_fab2_lib.baseboard_fab2(sch_1):page220_i298:\1\" )
			)
			( pin "C7W5.2"
				( objectStatus "@baseboard_fab2_lib.baseboard_fab2(sch_1):page220_i298:\2\" )
			)
			( pin "C7W9.1"
				( objectStatus "@baseboard_fab2_lib.baseboard_fab2(sch_1):page220_i299:\1\" )
			)
			( pin "C7W9.2"
				( objectStatus "@baseboard_fab2_lib.baseboard_fab2(sch_1):page220_i299:\2\" )
			)
			( pin "C7W8.1"
				( objectStatus "@baseboard_fab2_lib.baseboard_fab2(sch_1):page220_i300:\1\" )
			)
			( pin "C7W8.2"
				( objectStatus "@baseboard_fab2_lib.baseboard_fab2(sch_1):page220_i300:\2\" )
			)
			( pin "C7W7.1"
				( objectStatus "@baseboard_fab2_lib.baseboard_fab2(sch_1):page220_i301:\1\" )
			)
			( pin "C7W7.2"
				( objectStatus "@baseboard_fab2_lib.baseboard_fab2(sch_1):page220_i301:\2\" )
			)
			( pin "C7W6.1"
				( objectStatus "@baseboard_fab2_lib.baseboard_fab2(sch_1):page220_i302:\1\" )
			)
			( pin "C7W6.2"
				( objectStatus "@baseboard_fab2_lib.baseboard_fab2(sch_1):page220_i302:\2\" )
			)
			( pin "C7W13.1"
				( objectStatus "@baseboard_fab2_lib.baseboard_fab2(sch_1):page220_i303:\1\" )
			)
			( pin "C7W13.2"
				( objectStatus "@baseboard_fab2_lib.baseboard_fab2(sch_1):page220_i303:\2\" )
			)
			( pin "C7W12.1"
				( objectStatus "@baseboard_fab2_lib.baseboard_fab2(sch_1):page220_i304:\1\" )
			)
			( pin "C7W12.2"
				( objectStatus "@baseboard_fab2_lib.baseboard_fab2(sch_1):page220_i304:\2\" )
			)
			( pin "C7W11.1"
				( objectStatus "@baseboard_fab2_lib.baseboard_fab2(sch_1):page220_i305:\1\" )
			)
			( pin "C7W11.2"
				( objectStatus "@baseboard_fab2_lib.baseboard_fab2(sch_1):page220_i305:\2\" )
			)
			( pin "C7W10.1"
				( objectStatus "@baseboard_fab2_lib.baseboard_fab2(sch_1):page220_i306:\1\" )
			)
			( pin "C7W10.2"
				( objectStatus "@baseboard_fab2_lib.baseboard_fab2(sch_1):page220_i306:\2\" )
			)
			( pin "J8D4.1"
				( objectStatus "@baseboard_fab2_lib.baseboard_fab2(sch_1):page201_i191:\1\" )
			)
			( pin "J8D4.2"
				( objectStatus "@baseboard_fab2_lib.baseboard_fab2(sch_1):page201_i191:\2\" )
			)
			( pin "J8D4.3"
				( objectStatus "@baseboard_fab2_lib.baseboard_fab2(sch_1):page201_i191:\3\" )
			)
			( pin "C25W9.1"
				( objectStatus "@baseboard_fab2_lib.baseboard_fab2(sch_1):page147_i160:a" )
			)
			( pin "C25W9.2"
				( objectStatus "@baseboard_fab2_lib.baseboard_fab2(sch_1):page147_i160:b" )
			)
			( pin "C8E7.1"
				( objectStatus "@baseboard_fab2_lib.baseboard_fab2(sch_1):page241_i103:\1\" )
			)
			( pin "C8E7.2"
				( objectStatus "@baseboard_fab2_lib.baseboard_fab2(sch_1):page241_i103:\2\" )
			)
			( pin "C8E9.1"
				( objectStatus "@baseboard_fab2_lib.baseboard_fab2(sch_1):page241_i104:\1\" )
			)
			( pin "C8E9.2"
				( objectStatus "@baseboard_fab2_lib.baseboard_fab2(sch_1):page241_i104:\2\" )
			)
			( pin "R6W29.1"
				( objectStatus "@baseboard_fab2_lib.baseboard_fab2(sch_1):page89_i40:a" )
			)
			( pin "R6W29.2"
				( objectStatus "@baseboard_fab2_lib.baseboard_fab2(sch_1):page89_i40:b" )
			)
			( pin "WR8D30.1"
				( objectStatus "@baseboard_fab2_lib.baseboard_fab2(sch_1):page89_i45:a" )
			)
			( pin "WR8D30.2"
				( objectStatus "@baseboard_fab2_lib.baseboard_fab2(sch_1):page89_i45:b" )
			)
			( pin "Q8D1.2"
				( objectStatus "@baseboard_fab2_lib.baseboard_fab2(sch_1):page89_i46:b(0)" )
			)
			( pin "Q8D1.6"
				( objectStatus "@baseboard_fab2_lib.baseboard_fab2(sch_1):page89_i46:c(0)" )
			)
			( pin "Q8D1.1"
				( objectStatus "@baseboard_fab2_lib.baseboard_fab2(sch_1):page89_i46:e(0)" )
			)
			( pin "R8W9.1"
				( objectStatus "@baseboard_fab2_lib.baseboard_fab2(sch_1):page89_i49:a" )
			)
			( pin "R8W9.2"
				( objectStatus "@baseboard_fab2_lib.baseboard_fab2(sch_1):page89_i49:b" )
			)
			( pin "Q8W1.2"
				( objectStatus "@baseboard_fab2_lib.baseboard_fab2(sch_1):page89_i51:b(0)" )
			)
			( pin "Q8W1.6"
				( objectStatus "@baseboard_fab2_lib.baseboard_fab2(sch_1):page89_i51:c(0)" )
			)
			( pin "Q8W1.1"
				( objectStatus "@baseboard_fab2_lib.baseboard_fab2(sch_1):page89_i51:e(0)" )
			)
			( pin "Q8W1.5"
				( objectStatus "@baseboard_fab2_lib.baseboard_fab2(sch_1):page89_i52:b(0)" )
			)
			( pin "Q8W1.3"
				( objectStatus "@baseboard_fab2_lib.baseboard_fab2(sch_1):page89_i52:c(0)" )
			)
			( pin "Q8W1.4"
				( objectStatus "@baseboard_fab2_lib.baseboard_fab2(sch_1):page89_i52:e(0)" )
			)
			( pin "Q1F1.1"
				( objectStatus "@baseboard_fab2_lib.baseboard_fab2(sch_1):page89_i53:b" )
			)
			( pin "Q1F1.3"
				( objectStatus "@baseboard_fab2_lib.baseboard_fab2(sch_1):page89_i53:c" )
			)
			( pin "Q1F1.2"
				( objectStatus "@baseboard_fab2_lib.baseboard_fab2(sch_1):page89_i53:e" )
			)
			( pin "R1W32.1"
				( objectStatus "@baseboard_fab2_lib.baseboard_fab2(sch_1):page89_i54:a" )
			)
			( pin "R1W32.2"
				( objectStatus "@baseboard_fab2_lib.baseboard_fab2(sch_1):page89_i54:b" )
			)
			( pin "Q1W6.1"
				( objectStatus "@baseboard_fab2_lib.baseboard_fab2(sch_1):page89_i55:b" )
			)
			( pin "Q1W6.3"
				( objectStatus "@baseboard_fab2_lib.baseboard_fab2(sch_1):page89_i55:c" )
			)
			( pin "Q1W6.2"
				( objectStatus "@baseboard_fab2_lib.baseboard_fab2(sch_1):page89_i55:e" )
			)
			( pin "R1W31.1"
				( objectStatus "@baseboard_fab2_lib.baseboard_fab2(sch_1):page89_i56:a" )
			)
			( pin "R1W31.2"
				( objectStatus "@baseboard_fab2_lib.baseboard_fab2(sch_1):page89_i56:b" )
			)
			( pin "C30W3.1"
				( objectStatus "@baseboard_fab2_lib.baseboard_fab2(sch_1):page253_i35:\1\" )
			)
			( pin "C30W3.2"
				( objectStatus "@baseboard_fab2_lib.baseboard_fab2(sch_1):page253_i35:\2\" )
			)
			( pin "C30W4.1"
				( objectStatus "@baseboard_fab2_lib.baseboard_fab2(sch_1):page253_i36:\1\" )
			)
			( pin "C30W4.2"
				( objectStatus "@baseboard_fab2_lib.baseboard_fab2(sch_1):page253_i36:\2\" )
			)
			( pin "C30W6.1"
				( objectStatus "@baseboard_fab2_lib.baseboard_fab2(sch_1):page253_i37:\1\" )
			)
			( pin "C30W6.2"
				( objectStatus "@baseboard_fab2_lib.baseboard_fab2(sch_1):page253_i37:\2\" )
			)
			( pin "C30W5.1"
				( objectStatus "@baseboard_fab2_lib.baseboard_fab2(sch_1):page253_i38:\1\" )
			)
			( pin "C30W5.2"
				( objectStatus "@baseboard_fab2_lib.baseboard_fab2(sch_1):page253_i38:\2\" )
			)
			( pin "C30W9.1"
				( objectStatus "@baseboard_fab2_lib.baseboard_fab2(sch_1):page253_i40:\1\" )
			)
			( pin "C30W9.2"
				( objectStatus "@baseboard_fab2_lib.baseboard_fab2(sch_1):page253_i40:\2\" )
			)
			( pin "C30W8.1"
				( objectStatus "@baseboard_fab2_lib.baseboard_fab2(sch_1):page253_i41:\1\" )
			)
			( pin "C30W8.2"
				( objectStatus "@baseboard_fab2_lib.baseboard_fab2(sch_1):page253_i41:\2\" )
			)
			( pin "C30W7.1"
				( objectStatus "@baseboard_fab2_lib.baseboard_fab2(sch_1):page253_i42:\1\" )
			)
			( pin "C30W7.2"
				( objectStatus "@baseboard_fab2_lib.baseboard_fab2(sch_1):page253_i42:\2\" )
			)
			( pin "R4E2.1"
				( objectStatus "@baseboard_fab2_lib.baseboard_fab2(sch_1):page213_i103:a" )
			)
			( pin "R4E2.2"
				( objectStatus "@baseboard_fab2_lib.baseboard_fab2(sch_1):page213_i103:b" )
			)
			( pin "R4P1.1"
				( objectStatus "@baseboard_fab2_lib.baseboard_fab2(sch_1):page90_i98:a" )
			)
			( pin "R4P1.2"
				( objectStatus "@baseboard_fab2_lib.baseboard_fab2(sch_1):page90_i98:b" )
			)
			( pin "R3D13.1"
				( objectStatus "@baseboard_fab2_lib.baseboard_fab2(sch_1):page90_i99:a" )
			)
			( pin "R3D13.2"
				( objectStatus "@baseboard_fab2_lib.baseboard_fab2(sch_1):page90_i99:b" )
			)
			( pin "R1U15.1"
				( objectStatus "@baseboard_fab2_lib.baseboard_fab2(sch_1):page164_i48:a" )
			)
			( pin "R1U15.2"
				( objectStatus "@baseboard_fab2_lib.baseboard_fab2(sch_1):page164_i48:b" )
			)
			( pin "R6D6.1"
				( objectStatus "@baseboard_fab2_lib.baseboard_fab2(sch_1):page90_i101:a" )
			)
			( pin "R6D6.2"
				( objectStatus "@baseboard_fab2_lib.baseboard_fab2(sch_1):page90_i101:b" )
			)
			( pin "R3D12.1"
				( objectStatus "@baseboard_fab2_lib.baseboard_fab2(sch_1):page90_i102:a" )
			)
			( pin "R3D12.2"
				( objectStatus "@baseboard_fab2_lib.baseboard_fab2(sch_1):page90_i102:b" )
			)
			( pin "R2T1.1"
				( objectStatus "@baseboard_fab2_lib.baseboard_fab2(sch_1):page125_i89:a" )
			)
			( pin "R2T1.2"
				( objectStatus "@baseboard_fab2_lib.baseboard_fab2(sch_1):page125_i89:b" )
			)
			( pin "R9F32.1"
				( objectStatus "@baseboard_fab2_lib.baseboard_fab2(sch_1):page239_i100:a" )
			)
			( pin "R9F32.2"
				( objectStatus "@baseboard_fab2_lib.baseboard_fab2(sch_1):page239_i100:b" )
			)
			( pin "R9W32.1"
				( objectStatus "@baseboard_fab2_lib.baseboard_fab2(sch_1):page239_i101:a" )
			)
			( pin "R9W32.2"
				( objectStatus "@baseboard_fab2_lib.baseboard_fab2(sch_1):page239_i101:b" )
			)
			( pin "R7G8.1"
				( objectStatus "@baseboard_fab2_lib.baseboard_fab2(sch_1):page215_i72:a" )
			)
			( pin "R7G8.2"
				( objectStatus "@baseboard_fab2_lib.baseboard_fab2(sch_1):page215_i72:b" )
			)
			( pin "R2L26.1"
				( objectStatus "@baseboard_fab2_lib.baseboard_fab2(sch_1):page235_i253:a" )
			)
			( pin "R2L26.2"
				( objectStatus "@baseboard_fab2_lib.baseboard_fab2(sch_1):page235_i253:b" )
			)
			( pin "R7F11.1"
				( objectStatus "@baseboard_fab2_lib.baseboard_fab2(sch_1):page231_i230:a" )
			)
			( pin "R7F11.2"
				( objectStatus "@baseboard_fab2_lib.baseboard_fab2(sch_1):page231_i230:b" )
			)
			( pin "U6W5.2"
				( objectStatus "@baseboard_fab2_lib.baseboard_fab2(sch_1):page176_i148:a" )
			)
			( pin "U6W5.1"
				( objectStatus "@baseboard_fab2_lib.baseboard_fab2(sch_1):page176_i148:oe" )
			)
			( pin "U6W5.4"
				( objectStatus "@baseboard_fab2_lib.baseboard_fab2(sch_1):page176_i148:y" )
			)
			( pin "R25W156.1"
				( objectStatus "@baseboard_fab2_lib.baseboard_fab2(sch_1):page150_i240:a" )
			)
			( pin "R25W156.2"
				( objectStatus "@baseboard_fab2_lib.baseboard_fab2(sch_1):page150_i240:b" )
			)
			( pin "R6W1.1"
				( objectStatus "@baseboard_fab2_lib.baseboard_fab2(sch_1):page137_i149:a" )
			)
			( pin "R6W1.2"
				( objectStatus "@baseboard_fab2_lib.baseboard_fab2(sch_1):page137_i149:b" )
			)
			( pin "R1W33.1"
				( objectStatus "@baseboard_fab2_lib.baseboard_fab2(sch_1):page176_i142:a" )
			)
			( pin "R1W33.2"
				( objectStatus "@baseboard_fab2_lib.baseboard_fab2(sch_1):page176_i142:b" )
			)
			( pin "R1W34.1"
				( objectStatus "@baseboard_fab2_lib.baseboard_fab2(sch_1):page176_i143:a" )
			)
			( pin "R1W34.2"
				( objectStatus "@baseboard_fab2_lib.baseboard_fab2(sch_1):page176_i143:b" )
			)
			( pin "U6W4.2"
				( objectStatus "@baseboard_fab2_lib.baseboard_fab2(sch_1):page176_i146:a" )
			)
			( pin "U6W4.1"
				( objectStatus "@baseboard_fab2_lib.baseboard_fab2(sch_1):page176_i146:oe" )
			)
			( pin "U6W4.4"
				( objectStatus "@baseboard_fab2_lib.baseboard_fab2(sch_1):page176_i146:y" )
			)
			( pin "R6W30.1"
				( objectStatus "@baseboard_fab2_lib.baseboard_fab2(sch_1):page176_i147:a" )
			)
			( pin "R6W30.2"
				( objectStatus "@baseboard_fab2_lib.baseboard_fab2(sch_1):page176_i147:b" )
			)
			( pin "U6W6.2"
				( objectStatus "@baseboard_fab2_lib.baseboard_fab2(sch_1):page176_i157:a" )
			)
			( pin "U6W6.1"
				( objectStatus "@baseboard_fab2_lib.baseboard_fab2(sch_1):page176_i157:oe" )
			)
			( pin "U6W6.4"
				( objectStatus "@baseboard_fab2_lib.baseboard_fab2(sch_1):page176_i157:y" )
			)
			( pin "C5M13.1"
				( objectStatus "@baseboard_fab2_lib.baseboard_fab2(sch_1):page222_i41:a" )
			)
			( pin "C5M13.2"
				( objectStatus "@baseboard_fab2_lib.baseboard_fab2(sch_1):page222_i41:b" )
			)
			( pin "C8L4.1"
				( objectStatus "@baseboard_fab2_lib.baseboard_fab2(sch_1):page230_i42:a" )
			)
			( pin "C8L4.2"
				( objectStatus "@baseboard_fab2_lib.baseboard_fab2(sch_1):page230_i42:b" )
			)
			( pin "R9A5.1"
				( objectStatus "@baseboard_fab2_lib.baseboard_fab2(sch_1):page155_i198:a" )
			)
			( pin "R9A5.2"
				( objectStatus "@baseboard_fab2_lib.baseboard_fab2(sch_1):page155_i198:b" )
			)
			( pin "CR6W1.2"
				( objectStatus "@baseboard_fab2_lib.baseboard_fab2(sch_1):page247_i157:a" )
			)
			( pin "CR6W1.1"
				( objectStatus "@baseboard_fab2_lib.baseboard_fab2(sch_1):page247_i157:c" )
			)
			( pin "CR6W2.2"
				( objectStatus "@baseboard_fab2_lib.baseboard_fab2(sch_1):page247_i158:a" )
			)
			( pin "CR6W2.1"
				( objectStatus "@baseboard_fab2_lib.baseboard_fab2(sch_1):page247_i158:c" )
			)
			( pin "R6W38.1"
				( objectStatus "@baseboard_fab2_lib.baseboard_fab2(sch_1):page176_i156:a" )
			)
			( pin "R6W38.2"
				( objectStatus "@baseboard_fab2_lib.baseboard_fab2(sch_1):page176_i156:b" )
			)
			( pin "R6W39.1"
				( objectStatus "@baseboard_fab2_lib.baseboard_fab2(sch_1):page176_i158:a" )
			)
			( pin "R6W39.2"
				( objectStatus "@baseboard_fab2_lib.baseboard_fab2(sch_1):page176_i158:b" )
			)
			( pin "R7W4.1"
				( objectStatus "@baseboard_fab2_lib.baseboard_fab2(sch_1):page92_i106:a" )
			)
			( pin "R7W4.2"
				( objectStatus "@baseboard_fab2_lib.baseboard_fab2(sch_1):page92_i106:b" )
			)
			( pin "R3W10.1"
				( objectStatus "@baseboard_fab2_lib.baseboard_fab2(sch_1):page92_i108:a" )
			)
			( pin "R3W10.2"
				( objectStatus "@baseboard_fab2_lib.baseboard_fab2(sch_1):page92_i108:b" )
			)
			( pin "R2W2.1"
				( objectStatus "@baseboard_fab2_lib.baseboard_fab2(sch_1):page93_i147:a" )
			)
			( pin "R2W2.2"
				( objectStatus "@baseboard_fab2_lib.baseboard_fab2(sch_1):page93_i147:b" )
			)
			( pin "R1W35.1"
				( objectStatus "@baseboard_fab2_lib.baseboard_fab2(sch_1):page152_i105:a" )
			)
			( pin "R1W35.2"
				( objectStatus "@baseboard_fab2_lib.baseboard_fab2(sch_1):page152_i105:b" )
			)
			( pin "R6W37.1"
				( objectStatus "@baseboard_fab2_lib.baseboard_fab2(sch_1):page176_i160:a" )
			)
			( pin "R6W37.2"
				( objectStatus "@baseboard_fab2_lib.baseboard_fab2(sch_1):page176_i160:b" )
			)
			( pin "R6W36.1"
				( objectStatus "@baseboard_fab2_lib.baseboard_fab2(sch_1):page176_i161:a" )
			)
			( pin "R6W36.2"
				( objectStatus "@baseboard_fab2_lib.baseboard_fab2(sch_1):page176_i161:b" )
			)
			( pin "C5L5.1"
				( objectStatus "@baseboard_fab2_lib.baseboard_fab2(sch_1):page222_i44:a" )
			)
			( pin "C5L5.2"
				( objectStatus "@baseboard_fab2_lib.baseboard_fab2(sch_1):page222_i44:b" )
			)
			( pin "C1W18.1"
				( objectStatus "@baseboard_fab2_lib.baseboard_fab2(sch_1):page176_i163:a" )
			)
			( pin "C1W18.2"
				( objectStatus "@baseboard_fab2_lib.baseboard_fab2(sch_1):page176_i163:b" )
			)
			( pin "C1W19.1"
				( objectStatus "@baseboard_fab2_lib.baseboard_fab2(sch_1):page176_i166:a" )
			)
			( pin "C1W19.2"
				( objectStatus "@baseboard_fab2_lib.baseboard_fab2(sch_1):page176_i166:b" )
			)
			( pin "R1W36.1"
				( objectStatus "@baseboard_fab2_lib.baseboard_fab2(sch_1):page176_i172:a" )
			)
			( pin "R1W36.2"
				( objectStatus "@baseboard_fab2_lib.baseboard_fab2(sch_1):page176_i172:b" )
			)
			( pin "R1W37.1"
				( objectStatus "@baseboard_fab2_lib.baseboard_fab2(sch_1):page176_i173:a" )
			)
			( pin "R1W37.2"
				( objectStatus "@baseboard_fab2_lib.baseboard_fab2(sch_1):page176_i173:b" )
			)
			( pin "R8E36.1"
				( objectStatus "@baseboard_fab2_lib.baseboard_fab2(sch_1):page142_i34:\1\" )
			)
			( pin "R8E36.2"
				( objectStatus "@baseboard_fab2_lib.baseboard_fab2(sch_1):page142_i34:\2\" )
			)
			( pin "R8E30.1"
				( objectStatus "@baseboard_fab2_lib.baseboard_fab2(sch_1):page142_i35:\1\" )
			)
			( pin "R8E30.2"
				( objectStatus "@baseboard_fab2_lib.baseboard_fab2(sch_1):page142_i35:\2\" )
			)
			( pin "R1W38.1"
				( objectStatus "@baseboard_fab2_lib.baseboard_fab2(sch_1):page176_i176:a" )
			)
			( pin "R1W38.2"
				( objectStatus "@baseboard_fab2_lib.baseboard_fab2(sch_1):page176_i176:b" )
			)
			( pin "R6W3.1"
				( objectStatus "@baseboard_fab2_lib.baseboard_fab2(sch_1):page200_i250:\1\" )
			)
			( pin "R6W3.2"
				( objectStatus "@baseboard_fab2_lib.baseboard_fab2(sch_1):page200_i250:\2\" )
			)
			( pin "C1W20.1"
				( objectStatus "@baseboard_fab2_lib.baseboard_fab2(sch_1):page151_i220:a" )
			)
			( pin "C1W20.2"
				( objectStatus "@baseboard_fab2_lib.baseboard_fab2(sch_1):page151_i220:b" )
			)
			( pin "FB9E1.1"
				( objectStatus "@baseboard_fab2_lib.baseboard_fab2(sch_1):page240_i193:\1\" )
			)
			( pin "FB9E1.2"
				( objectStatus "@baseboard_fab2_lib.baseboard_fab2(sch_1):page240_i193:\2\" )
			)
			( pin "R6W40.1"
				( objectStatus "@baseboard_fab2_lib.baseboard_fab2(sch_1):page155_i201:a" )
			)
			( pin "R6W40.2"
				( objectStatus "@baseboard_fab2_lib.baseboard_fab2(sch_1):page155_i201:b" )
			)
			( pin "R25W30.1"
				( objectStatus "@baseboard_fab2_lib.baseboard_fab2(sch_1):page151_i222:a" )
			)
			( pin "R25W30.2"
				( objectStatus "@baseboard_fab2_lib.baseboard_fab2(sch_1):page151_i222:b" )
			)
			( pin "R1D29.1"
				( objectStatus "@baseboard_fab2_lib.baseboard_fab2(sch_1):page199_i137:a" )
			)
			( pin "R1D29.2"
				( objectStatus "@baseboard_fab2_lib.baseboard_fab2(sch_1):page199_i137:b" )
			)
			( pin "R1T10.1"
				( objectStatus "@baseboard_fab2_lib.baseboard_fab2(sch_1):page164_i101:a" )
			)
			( pin "R1T10.2"
				( objectStatus "@baseboard_fab2_lib.baseboard_fab2(sch_1):page164_i101:b" )
			)
			( pin "R1T6.1"
				( objectStatus "@baseboard_fab2_lib.baseboard_fab2(sch_1):page164_i51:a" )
			)
			( pin "R1T6.2"
				( objectStatus "@baseboard_fab2_lib.baseboard_fab2(sch_1):page164_i51:b" )
			)
			( pin "R1T12.1"
				( objectStatus "@baseboard_fab2_lib.baseboard_fab2(sch_1):page164_i53:a" )
			)
			( pin "R1T12.2"
				( objectStatus "@baseboard_fab2_lib.baseboard_fab2(sch_1):page164_i53:b" )
			)
			( pin "R3N22.1"
				( objectStatus "@baseboard_fab2_lib.baseboard_fab2(sch_1):page211_i102:a" )
			)
			( pin "R3N22.2"
				( objectStatus "@baseboard_fab2_lib.baseboard_fab2(sch_1):page211_i102:b" )
			)
			( pin "R4D64.1"
				( objectStatus "@baseboard_fab2_lib.baseboard_fab2(sch_1):page213_i104:a" )
			)
			( pin "R4D64.2"
				( objectStatus "@baseboard_fab2_lib.baseboard_fab2(sch_1):page213_i104:b" )
			)
			( pin "R9W31.1"
				( objectStatus "@baseboard_fab2_lib.baseboard_fab2(sch_1):page239_i102:\1\" )
			)
			( pin "R9W31.2"
				( objectStatus "@baseboard_fab2_lib.baseboard_fab2(sch_1):page239_i102:\2\" )
			)
			( pin "R25W28.1"
				( objectStatus "@baseboard_fab2_lib.baseboard_fab2(sch_1):page151_i224:\1\" )
			)
			( pin "R25W28.2"
				( objectStatus "@baseboard_fab2_lib.baseboard_fab2(sch_1):page151_i224:\2\" )
			)
			( pin "R25W29.1"
				( objectStatus "@baseboard_fab2_lib.baseboard_fab2(sch_1):page151_i225:\1\" )
			)
			( pin "R25W29.2"
				( objectStatus "@baseboard_fab2_lib.baseboard_fab2(sch_1):page151_i225:\2\" )
			)
			( pin "R25W34.1"
				( objectStatus "@baseboard_fab2_lib.baseboard_fab2(sch_1):page151_i229:\1\" )
			)
			( pin "R25W34.2"
				( objectStatus "@baseboard_fab2_lib.baseboard_fab2(sch_1):page151_i229:\2\" )
			)
			( pin "R25W35.1"
				( objectStatus "@baseboard_fab2_lib.baseboard_fab2(sch_1):page151_i230:\1\" )
			)
			( pin "R25W35.2"
				( objectStatus "@baseboard_fab2_lib.baseboard_fab2(sch_1):page151_i230:\2\" )
			)
			( pin "R25W36.1"
				( objectStatus "@baseboard_fab2_lib.baseboard_fab2(sch_1):page151_i231:\1\" )
			)
			( pin "R25W36.2"
				( objectStatus "@baseboard_fab2_lib.baseboard_fab2(sch_1):page151_i231:\2\" )
			)
			( pin "R25W37.1"
				( objectStatus "@baseboard_fab2_lib.baseboard_fab2(sch_1):page151_i232:\1\" )
			)
			( pin "R25W37.2"
				( objectStatus "@baseboard_fab2_lib.baseboard_fab2(sch_1):page151_i232:\2\" )
			)
			( pin "R25W38.1"
				( objectStatus "@baseboard_fab2_lib.baseboard_fab2(sch_1):page151_i233:\1\" )
			)
			( pin "R25W38.2"
				( objectStatus "@baseboard_fab2_lib.baseboard_fab2(sch_1):page151_i233:\2\" )
			)
			( pin "R25W39.1"
				( objectStatus "@baseboard_fab2_lib.baseboard_fab2(sch_1):page151_i234:\1\" )
			)
			( pin "R25W39.2"
				( objectStatus "@baseboard_fab2_lib.baseboard_fab2(sch_1):page151_i234:\2\" )
			)
			( pin "R25W41.1"
				( objectStatus "@baseboard_fab2_lib.baseboard_fab2(sch_1):page151_i235:\1\" )
			)
			( pin "R25W41.2"
				( objectStatus "@baseboard_fab2_lib.baseboard_fab2(sch_1):page151_i235:\2\" )
			)
			( pin "R25W42.1"
				( objectStatus "@baseboard_fab2_lib.baseboard_fab2(sch_1):page151_i236:\1\" )
			)
			( pin "R25W42.2"
				( objectStatus "@baseboard_fab2_lib.baseboard_fab2(sch_1):page151_i236:\2\" )
			)
			( pin "R25W44.1"
				( objectStatus "@baseboard_fab2_lib.baseboard_fab2(sch_1):page151_i237:\1\" )
			)
			( pin "R25W44.2"
				( objectStatus "@baseboard_fab2_lib.baseboard_fab2(sch_1):page151_i237:\2\" )
			)
			( pin "R25W43.1"
				( objectStatus "@baseboard_fab2_lib.baseboard_fab2(sch_1):page151_i238:\1\" )
			)
			( pin "R25W43.2"
				( objectStatus "@baseboard_fab2_lib.baseboard_fab2(sch_1):page151_i238:\2\" )
			)
			( pin "R25W47.1"
				( objectStatus "@baseboard_fab2_lib.baseboard_fab2(sch_1):page151_i239:\1\" )
			)
			( pin "R25W47.2"
				( objectStatus "@baseboard_fab2_lib.baseboard_fab2(sch_1):page151_i239:\2\" )
			)
			( pin "R25W48.1"
				( objectStatus "@baseboard_fab2_lib.baseboard_fab2(sch_1):page151_i240:\1\" )
			)
			( pin "R25W48.2"
				( objectStatus "@baseboard_fab2_lib.baseboard_fab2(sch_1):page151_i240:\2\" )
			)
			( pin "R25W46.1"
				( objectStatus "@baseboard_fab2_lib.baseboard_fab2(sch_1):page151_i241:\1\" )
			)
			( pin "R25W46.2"
				( objectStatus "@baseboard_fab2_lib.baseboard_fab2(sch_1):page151_i241:\2\" )
			)
			( pin "R25W45.1"
				( objectStatus "@baseboard_fab2_lib.baseboard_fab2(sch_1):page151_i242:\1\" )
			)
			( pin "R25W45.2"
				( objectStatus "@baseboard_fab2_lib.baseboard_fab2(sch_1):page151_i242:\2\" )
			)
			( pin "R25W49.1"
				( objectStatus "@baseboard_fab2_lib.baseboard_fab2(sch_1):page151_i243:\1\" )
			)
			( pin "R25W49.2"
				( objectStatus "@baseboard_fab2_lib.baseboard_fab2(sch_1):page151_i243:\2\" )
			)
			( pin "R25W50.1"
				( objectStatus "@baseboard_fab2_lib.baseboard_fab2(sch_1):page151_i244:\1\" )
			)
			( pin "R25W50.2"
				( objectStatus "@baseboard_fab2_lib.baseboard_fab2(sch_1):page151_i244:\2\" )
			)
			( pin "R25W51.1"
				( objectStatus "@baseboard_fab2_lib.baseboard_fab2(sch_1):page151_i245:\1\" )
			)
			( pin "R25W51.2"
				( objectStatus "@baseboard_fab2_lib.baseboard_fab2(sch_1):page151_i245:\2\" )
			)
			( pin "R25W52.1"
				( objectStatus "@baseboard_fab2_lib.baseboard_fab2(sch_1):page151_i246:\1\" )
			)
			( pin "R25W52.2"
				( objectStatus "@baseboard_fab2_lib.baseboard_fab2(sch_1):page151_i246:\2\" )
			)
			( pin "R25W40.1"
				( objectStatus "@baseboard_fab2_lib.baseboard_fab2(sch_1):page151_i247:\1\" )
			)
			( pin "R25W40.2"
				( objectStatus "@baseboard_fab2_lib.baseboard_fab2(sch_1):page151_i247:\2\" )
			)
			( pin "R25W22.1"
				( objectStatus "@baseboard_fab2_lib.baseboard_fab2(sch_1):page151_i270:\1\" )
			)
			( pin "R25W22.2"
				( objectStatus "@baseboard_fab2_lib.baseboard_fab2(sch_1):page151_i270:\2\" )
			)
			( pin "R25W21.1"
				( objectStatus "@baseboard_fab2_lib.baseboard_fab2(sch_1):page151_i271:\1\" )
			)
			( pin "R25W21.2"
				( objectStatus "@baseboard_fab2_lib.baseboard_fab2(sch_1):page151_i271:\2\" )
			)
			( pin "R25W26.1"
				( objectStatus "@baseboard_fab2_lib.baseboard_fab2(sch_1):page151_i274:\1\" )
			)
			( pin "R25W26.2"
				( objectStatus "@baseboard_fab2_lib.baseboard_fab2(sch_1):page151_i274:\2\" )
			)
			( pin "R25W25.1"
				( objectStatus "@baseboard_fab2_lib.baseboard_fab2(sch_1):page151_i275:\1\" )
			)
			( pin "R25W25.2"
				( objectStatus "@baseboard_fab2_lib.baseboard_fab2(sch_1):page151_i275:\2\" )
			)
			( pin "R1B15.1"
				( objectStatus "@baseboard_fab2_lib.baseboard_fab2(sch_1):page226_i73:a" )
			)
			( pin "R1B15.2"
				( objectStatus "@baseboard_fab2_lib.baseboard_fab2(sch_1):page226_i73:b" )
			)
			( pin "R6W4.1"
				( objectStatus "@baseboard_fab2_lib.baseboard_fab2(sch_1):page247_i159:a" )
			)
			( pin "R6W4.2"
				( objectStatus "@baseboard_fab2_lib.baseboard_fab2(sch_1):page247_i159:b" )
			)
			( pin "R6W5.1"
				( objectStatus "@baseboard_fab2_lib.baseboard_fab2(sch_1):page247_i160:a" )
			)
			( pin "R6W5.2"
				( objectStatus "@baseboard_fab2_lib.baseboard_fab2(sch_1):page247_i160:b" )
			)
			( pin "R6W6.1"
				( objectStatus "@baseboard_fab2_lib.baseboard_fab2(sch_1):page247_i161:a" )
			)
			( pin "R6W6.2"
				( objectStatus "@baseboard_fab2_lib.baseboard_fab2(sch_1):page247_i161:b" )
			)
			( pin "R6W9.1"
				( objectStatus "@baseboard_fab2_lib.baseboard_fab2(sch_1):page247_i162:a" )
			)
			( pin "R6W9.2"
				( objectStatus "@baseboard_fab2_lib.baseboard_fab2(sch_1):page247_i162:b" )
			)
			( pin "R6W8.1"
				( objectStatus "@baseboard_fab2_lib.baseboard_fab2(sch_1):page247_i163:a" )
			)
			( pin "R6W8.2"
				( objectStatus "@baseboard_fab2_lib.baseboard_fab2(sch_1):page247_i163:b" )
			)
			( pin "R6W7.1"
				( objectStatus "@baseboard_fab2_lib.baseboard_fab2(sch_1):page247_i164:a" )
			)
			( pin "R6W7.2"
				( objectStatus "@baseboard_fab2_lib.baseboard_fab2(sch_1):page247_i164:b" )
			)
			( pin "R1T40.1"
				( objectStatus "@baseboard_fab2_lib.baseboard_fab2(sch_1):page151_i278:a" )
			)
			( pin "R1T40.2"
				( objectStatus "@baseboard_fab2_lib.baseboard_fab2(sch_1):page151_i278:b" )
			)
			( pin "R1T28.1"
				( objectStatus "@baseboard_fab2_lib.baseboard_fab2(sch_1):page151_i279:a" )
			)
			( pin "R1T28.2"
				( objectStatus "@baseboard_fab2_lib.baseboard_fab2(sch_1):page151_i279:b" )
			)
			( pin "R8F9.1"
				( objectStatus "@baseboard_fab2_lib.baseboard_fab2(sch_1):page240_i195:a" )
			)
			( pin "R8F9.2"
				( objectStatus "@baseboard_fab2_lib.baseboard_fab2(sch_1):page240_i195:b" )
			)
			( pin "L1G1.2"
				( objectStatus "@baseboard_fab2_lib.baseboard_fab2(sch_1):page224_i160:f" )
			)
			( pin "L1G1.1"
				( objectStatus "@baseboard_fab2_lib.baseboard_fab2(sch_1):page224_i160:s" )
			)
			( pin "C8W4.1"
				( objectStatus "@baseboard_fab2_lib.baseboard_fab2(sch_1):page76_i245:a" )
			)
			( pin "C8W4.2"
				( objectStatus "@baseboard_fab2_lib.baseboard_fab2(sch_1):page76_i245:b" )
			)
			( pin "C5U10.1"
				( objectStatus "@baseboard_fab2_lib.baseboard_fab2(sch_1):page217_i317:a" )
			)
			( pin "C5U10.2"
				( objectStatus "@baseboard_fab2_lib.baseboard_fab2(sch_1):page217_i317:b" )
			)
			( pin "C5U15.1"
				( objectStatus "@baseboard_fab2_lib.baseboard_fab2(sch_1):page217_i320:a" )
			)
			( pin "C5U15.2"
				( objectStatus "@baseboard_fab2_lib.baseboard_fab2(sch_1):page217_i320:b" )
			)
			( pin "C5P38.1"
				( objectStatus "@baseboard_fab2_lib.baseboard_fab2(sch_1):page217_i327:a" )
			)
			( pin "C5P38.2"
				( objectStatus "@baseboard_fab2_lib.baseboard_fab2(sch_1):page217_i327:b" )
			)
			( pin "C5P39.1"
				( objectStatus "@baseboard_fab2_lib.baseboard_fab2(sch_1):page217_i328:a" )
			)
			( pin "C5P39.2"
				( objectStatus "@baseboard_fab2_lib.baseboard_fab2(sch_1):page217_i328:b" )
			)
			( pin "R6W35.1"
				( objectStatus "@baseboard_fab2_lib.baseboard_fab2(sch_1):page247_i165:a" )
			)
			( pin "R6W35.2"
				( objectStatus "@baseboard_fab2_lib.baseboard_fab2(sch_1):page247_i165:b" )
			)
			( pin "C7C13.1"
				( objectStatus "@baseboard_fab2_lib.baseboard_fab2(sch_1):page114_i195:a" )
			)
			( pin "C7C13.2"
				( objectStatus "@baseboard_fab2_lib.baseboard_fab2(sch_1):page114_i195:b" )
			)
			( pin "C7C15.1"
				( objectStatus "@baseboard_fab2_lib.baseboard_fab2(sch_1):page114_i196:a" )
			)
			( pin "C7C15.2"
				( objectStatus "@baseboard_fab2_lib.baseboard_fab2(sch_1):page114_i196:b" )
			)
			( pin "C5P8.1"
				( objectStatus "@baseboard_fab2_lib.baseboard_fab2(sch_1):page42_i214:a" )
			)
			( pin "C5P8.2"
				( objectStatus "@baseboard_fab2_lib.baseboard_fab2(sch_1):page42_i214:b" )
			)
			( pin "C8P6.1"
				( objectStatus "@baseboard_fab2_lib.baseboard_fab2(sch_1):page76_i247:a" )
			)
			( pin "C8P6.2"
				( objectStatus "@baseboard_fab2_lib.baseboard_fab2(sch_1):page76_i247:b" )
			)
			( pin "C8P7.1"
				( objectStatus "@baseboard_fab2_lib.baseboard_fab2(sch_1):page76_i248:a" )
			)
			( pin "C8P7.2"
				( objectStatus "@baseboard_fab2_lib.baseboard_fab2(sch_1):page76_i248:b" )
			)
			( pin "C8P17.1"
				( objectStatus "@baseboard_fab2_lib.baseboard_fab2(sch_1):page76_i252:a" )
			)
			( pin "C8P17.2"
				( objectStatus "@baseboard_fab2_lib.baseboard_fab2(sch_1):page76_i252:b" )
			)
			( pin "R25W157.1"
				( objectStatus "@baseboard_fab2_lib.baseboard_fab2(sch_1):page147_i164:a" )
			)
			( pin "R25W157.2"
				( objectStatus "@baseboard_fab2_lib.baseboard_fab2(sch_1):page147_i164:b" )
			)
			( pin "R32W10.1"
				( objectStatus "@baseboard_fab2_lib.baseboard_fab2(sch_1):page185_i183:a" )
			)
			( pin "R32W10.2"
				( objectStatus "@baseboard_fab2_lib.baseboard_fab2(sch_1):page185_i183:b" )
			)
			( pin "R32W11.1"
				( objectStatus "@baseboard_fab2_lib.baseboard_fab2(sch_1):page185_i184:a" )
			)
			( pin "R32W11.2"
				( objectStatus "@baseboard_fab2_lib.baseboard_fab2(sch_1):page185_i184:b" )
			)
			( pin "R32W12.1"
				( objectStatus "@baseboard_fab2_lib.baseboard_fab2(sch_1):page185_i187:a" )
			)
			( pin "R32W12.2"
				( objectStatus "@baseboard_fab2_lib.baseboard_fab2(sch_1):page185_i187:b" )
			)
			( pin "C32W1.1"
				( objectStatus "@baseboard_fab2_lib.baseboard_fab2(sch_1):page185_i188:a" )
			)
			( pin "C32W1.2"
				( objectStatus "@baseboard_fab2_lib.baseboard_fab2(sch_1):page185_i188:b" )
			)
			( pin "C32W3.1"
				( objectStatus "@baseboard_fab2_lib.baseboard_fab2(sch_1):page185_i190:a" )
			)
			( pin "C32W3.2"
				( objectStatus "@baseboard_fab2_lib.baseboard_fab2(sch_1):page185_i190:b" )
			)
			( pin "U32W1.5"
				( objectStatus "@baseboard_fab2_lib.baseboard_fab2(sch_1):page185_i191:en" )
			)
			( pin "U32W1.4"
				( objectStatus "@baseboard_fab2_lib.baseboard_fab2(sch_1):page185_i191:gnd" )
			)
			( pin "U32W1.2"
				( objectStatus "@baseboard_fab2_lib.baseboard_fab2(sch_1):page185_i191:scla" )
			)
			( pin "U32W1.7"
				( objectStatus "@baseboard_fab2_lib.baseboard_fab2(sch_1):page185_i191:sclb" )
			)
			( pin "U32W1.3"
				( objectStatus "@baseboard_fab2_lib.baseboard_fab2(sch_1):page185_i191:sdaa" )
			)
			( pin "U32W1.6"
				( objectStatus "@baseboard_fab2_lib.baseboard_fab2(sch_1):page185_i191:sdab" )
			)
			( pin "U32W1.1"
				( objectStatus "@baseboard_fab2_lib.baseboard_fab2(sch_1):page185_i191:vcca" )
			)
			( pin "U32W1.8"
				( objectStatus "@baseboard_fab2_lib.baseboard_fab2(sch_1):page185_i191:vccb" )
			)
			( pin "C32W2.1"
				( objectStatus "@baseboard_fab2_lib.baseboard_fab2(sch_1):page185_i193:a" )
			)
			( pin "C32W2.2"
				( objectStatus "@baseboard_fab2_lib.baseboard_fab2(sch_1):page185_i193:b" )
			)
			( pin "C32W4.1"
				( objectStatus "@baseboard_fab2_lib.baseboard_fab2(sch_1):page185_i196:a" )
			)
			( pin "C32W4.2"
				( objectStatus "@baseboard_fab2_lib.baseboard_fab2(sch_1):page185_i196:b" )
			)
			( pin "R32W9.1"
				( objectStatus "@baseboard_fab2_lib.baseboard_fab2(sch_1):page185_i200:a" )
			)
			( pin "R32W9.2"
				( objectStatus "@baseboard_fab2_lib.baseboard_fab2(sch_1):page185_i200:b" )
			)
			( pin "U32W2.5"
				( objectStatus "@baseboard_fab2_lib.baseboard_fab2(sch_1):page185_i204:en" )
			)
			( pin "U32W2.4"
				( objectStatus "@baseboard_fab2_lib.baseboard_fab2(sch_1):page185_i204:gnd" )
			)
			( pin "U32W2.2"
				( objectStatus "@baseboard_fab2_lib.baseboard_fab2(sch_1):page185_i204:scla" )
			)
			( pin "U32W2.7"
				( objectStatus "@baseboard_fab2_lib.baseboard_fab2(sch_1):page185_i204:sclb" )
			)
			( pin "U32W2.3"
				( objectStatus "@baseboard_fab2_lib.baseboard_fab2(sch_1):page185_i204:sdaa" )
			)
			( pin "U32W2.6"
				( objectStatus "@baseboard_fab2_lib.baseboard_fab2(sch_1):page185_i204:sdab" )
			)
			( pin "U32W2.1"
				( objectStatus "@baseboard_fab2_lib.baseboard_fab2(sch_1):page185_i204:vcca" )
			)
			( pin "U32W2.8"
				( objectStatus "@baseboard_fab2_lib.baseboard_fab2(sch_1):page185_i204:vccb" )
			)
			( pin "R32W3.1"
				( objectStatus "@baseboard_fab2_lib.baseboard_fab2(sch_1):page185_i206:a" )
			)
			( pin "R32W3.2"
				( objectStatus "@baseboard_fab2_lib.baseboard_fab2(sch_1):page185_i206:b" )
			)
			( pin "R32W2.1"
				( objectStatus "@baseboard_fab2_lib.baseboard_fab2(sch_1):page185_i207:a" )
			)
			( pin "R32W2.2"
				( objectStatus "@baseboard_fab2_lib.baseboard_fab2(sch_1):page185_i207:b" )
			)
			( pin "R32W1.1"
				( objectStatus "@baseboard_fab2_lib.baseboard_fab2(sch_1):page185_i208:a" )
			)
			( pin "R32W1.2"
				( objectStatus "@baseboard_fab2_lib.baseboard_fab2(sch_1):page185_i208:b" )
			)
			( pin "R32W4.1"
				( objectStatus "@baseboard_fab2_lib.baseboard_fab2(sch_1):page185_i211:a" )
			)
			( pin "R32W4.2"
				( objectStatus "@baseboard_fab2_lib.baseboard_fab2(sch_1):page185_i211:b" )
			)
			( pin "VR32W1.3"
				( objectStatus "@baseboard_fab2_lib.baseboard_fab2(sch_1):page185_i213:anode" )
			)
			( pin "VR32W1.2"
				( objectStatus "@baseboard_fab2_lib.baseboard_fab2(sch_1):page185_i213:cathode" )
			)
			( pin "VR32W1.1"
				( objectStatus "@baseboard_fab2_lib.baseboard_fab2(sch_1):page185_i213:ref" )
			)
			( pin "R32W6.1"
				( objectStatus "@baseboard_fab2_lib.baseboard_fab2(sch_1):page185_i214:a" )
			)
			( pin "R32W6.2"
				( objectStatus "@baseboard_fab2_lib.baseboard_fab2(sch_1):page185_i214:b" )
			)
			( pin "R32W7.1"
				( objectStatus "@baseboard_fab2_lib.baseboard_fab2(sch_1):page185_i215:a" )
			)
			( pin "R32W7.2"
				( objectStatus "@baseboard_fab2_lib.baseboard_fab2(sch_1):page185_i215:b" )
			)
			( pin "R32W5.1"
				( objectStatus "@baseboard_fab2_lib.baseboard_fab2(sch_1):page185_i216:a" )
			)
			( pin "R32W5.2"
				( objectStatus "@baseboard_fab2_lib.baseboard_fab2(sch_1):page185_i216:b" )
			)
			( pin "C8W1.1"
				( objectStatus "@baseboard_fab2_lib.baseboard_fab2(sch_1):page249_i52:\1\" )
			)
			( pin "C8W1.2"
				( objectStatus "@baseboard_fab2_lib.baseboard_fab2(sch_1):page249_i52:\2\" )
			)
			( pin "R12W2.1"
				( objectStatus "@baseboard_fab2_lib.baseboard_fab2(sch_1):page197_i117:\1\" )
			)
			( pin "R12W2.2"
				( objectStatus "@baseboard_fab2_lib.baseboard_fab2(sch_1):page197_i117:\2\" )
			)
			( pin "R12W12.1"
				( objectStatus "@baseboard_fab2_lib.baseboard_fab2(sch_1):page197_i119:\1\" )
			)
			( pin "R12W12.2"
				( objectStatus "@baseboard_fab2_lib.baseboard_fab2(sch_1):page197_i119:\2\" )
			)
			( pin "R12W6.1"
				( objectStatus "@baseboard_fab2_lib.baseboard_fab2(sch_1):page197_i120:\1\" )
			)
			( pin "R12W6.2"
				( objectStatus "@baseboard_fab2_lib.baseboard_fab2(sch_1):page197_i120:\2\" )
			)
			( pin "R12W7.1"
				( objectStatus "@baseboard_fab2_lib.baseboard_fab2(sch_1):page197_i121:\1\" )
			)
			( pin "R12W7.2"
				( objectStatus "@baseboard_fab2_lib.baseboard_fab2(sch_1):page197_i121:\2\" )
			)
			( pin "R12W16.1"
				( objectStatus "@baseboard_fab2_lib.baseboard_fab2(sch_1):page197_i122:\1\" )
			)
			( pin "R12W16.2"
				( objectStatus "@baseboard_fab2_lib.baseboard_fab2(sch_1):page197_i122:\2\" )
			)
			( pin "R12W17.1"
				( objectStatus "@baseboard_fab2_lib.baseboard_fab2(sch_1):page197_i123:\1\" )
			)
			( pin "R12W17.2"
				( objectStatus "@baseboard_fab2_lib.baseboard_fab2(sch_1):page197_i123:\2\" )
			)
			( pin "Q9W3.1"
				( objectStatus "@baseboard_fab2_lib.baseboard_fab2(sch_1):page249_i49:b" )
			)
			( pin "Q9W3.3"
				( objectStatus "@baseboard_fab2_lib.baseboard_fab2(sch_1):page249_i49:c" )
			)
			( pin "Q9W3.2"
				( objectStatus "@baseboard_fab2_lib.baseboard_fab2(sch_1):page249_i49:e" )
			)
			( pin "C9E8.1"
				( objectStatus "@baseboard_fab2_lib.baseboard_fab2(sch_1):page139_i250:a" )
			)
			( pin "C9E8.2"
				( objectStatus "@baseboard_fab2_lib.baseboard_fab2(sch_1):page139_i250:b" )
			)
			( pin "R9W36.1"
				( objectStatus "@baseboard_fab2_lib.baseboard_fab2(sch_1):page139_i252:a" )
			)
			( pin "R9W36.2"
				( objectStatus "@baseboard_fab2_lib.baseboard_fab2(sch_1):page139_i252:b" )
			)
			( pin "Q9B1.B"
				( objectStatus "@baseboard_fab2_lib.baseboard_fab2(sch_1):page167_i93:b" )
			)
			( pin "Q9B1.C"
				( objectStatus "@baseboard_fab2_lib.baseboard_fab2(sch_1):page167_i93:c" )
			)
			( pin "Q9B1.E"
				( objectStatus "@baseboard_fab2_lib.baseboard_fab2(sch_1):page167_i93:e" )
			)
			( pin "Q1E1.B"
				( objectStatus "@baseboard_fab2_lib.baseboard_fab2(sch_1):page167_i94:b" )
			)
			( pin "Q1E1.C"
				( objectStatus "@baseboard_fab2_lib.baseboard_fab2(sch_1):page167_i94:c" )
			)
			( pin "Q1E1.E"
				( objectStatus "@baseboard_fab2_lib.baseboard_fab2(sch_1):page167_i94:e" )
			)
			( pin "R3W2.1"
				( objectStatus "@baseboard_fab2_lib.baseboard_fab2(sch_1):page249_i56:a" )
			)
			( pin "R3W2.2"
				( objectStatus "@baseboard_fab2_lib.baseboard_fab2(sch_1):page249_i56:b" )
			)
			( pin "C4D20.1"
				( objectStatus "@baseboard_fab2_lib.baseboard_fab2(sch_1):page201_i192:a" )
			)
			( pin "C4D20.2"
				( objectStatus "@baseboard_fab2_lib.baseboard_fab2(sch_1):page201_i192:b" )
			)
			( pin "CR3W1.2"
				( objectStatus "@baseboard_fab2_lib.baseboard_fab2(sch_1):page249_i55:a" )
			)
			( pin "CR3W1.1"
				( objectStatus "@baseboard_fab2_lib.baseboard_fab2(sch_1):page249_i55:c" )
			)
			( pin "R3W5.1"
				( objectStatus "@baseboard_fab2_lib.baseboard_fab2(sch_1):page249_i58:a" )
			)
			( pin "R3W5.2"
				( objectStatus "@baseboard_fab2_lib.baseboard_fab2(sch_1):page249_i58:b" )
			)
			( pin "C5W1.1"
				( objectStatus "@baseboard_fab2_lib.baseboard_fab2(sch_1):page42_i217:a" )
			)
			( pin "C5W1.2"
				( objectStatus "@baseboard_fab2_lib.baseboard_fab2(sch_1):page42_i217:b" )
			)
			( pin "C5W2.1"
				( objectStatus "@baseboard_fab2_lib.baseboard_fab2(sch_1):page42_i218:a" )
			)
			( pin "C5W2.2"
				( objectStatus "@baseboard_fab2_lib.baseboard_fab2(sch_1):page42_i218:b" )
			)
			( pin "C3W4.1"
				( objectStatus "@baseboard_fab2_lib.baseboard_fab2(sch_1):page76_i254:a" )
			)
			( pin "C3W4.2"
				( objectStatus "@baseboard_fab2_lib.baseboard_fab2(sch_1):page76_i254:b" )
			)
			( pin "C3W3.1"
				( objectStatus "@baseboard_fab2_lib.baseboard_fab2(sch_1):page76_i256:a" )
			)
			( pin "C3W3.2"
				( objectStatus "@baseboard_fab2_lib.baseboard_fab2(sch_1):page76_i256:b" )
			)
			( pin "R12W25.1"
				( objectStatus "@baseboard_fab2_lib.baseboard_fab2(sch_1):page215_i74:a" )
			)
			( pin "R12W25.2"
				( objectStatus "@baseboard_fab2_lib.baseboard_fab2(sch_1):page215_i74:b" )
			)
			( pin "R2W3.1"
				( objectStatus "@baseboard_fab2_lib.baseboard_fab2(sch_1):page119_i223:a" )
			)
			( pin "R2W3.2"
				( objectStatus "@baseboard_fab2_lib.baseboard_fab2(sch_1):page119_i223:b" )
			)
			( pin "R2W4.1"
				( objectStatus "@baseboard_fab2_lib.baseboard_fab2(sch_1):page119_i224:a" )
			)
			( pin "R2W4.2"
				( objectStatus "@baseboard_fab2_lib.baseboard_fab2(sch_1):page119_i224:b" )
			)
			( pin "R2W5.1"
				( objectStatus "@baseboard_fab2_lib.baseboard_fab2(sch_1):page145_i176:a" )
			)
			( pin "R2W5.2"
				( objectStatus "@baseboard_fab2_lib.baseboard_fab2(sch_1):page145_i176:b" )
			)
			( pin "U25W19.2"
				( objectStatus "@baseboard_fab2_lib.baseboard_fab2(sch_1):page269_i76:a" )
			)
			( pin "U25W19.1"
				( objectStatus "@baseboard_fab2_lib.baseboard_fab2(sch_1):page269_i76:oe" )
			)
			( pin "U25W19.4"
				( objectStatus "@baseboard_fab2_lib.baseboard_fab2(sch_1):page269_i76:y" )
			)
			( pin "R25W174.1"
				( objectStatus "@baseboard_fab2_lib.baseboard_fab2(sch_1):page269_i4:a" )
			)
			( pin "R25W174.2"
				( objectStatus "@baseboard_fab2_lib.baseboard_fab2(sch_1):page269_i4:b" )
			)
			( pin "R6W16.1"
				( objectStatus "@baseboard_fab2_lib.baseboard_fab2(sch_1):page168_i46:a" )
			)
			( pin "R6W16.2"
				( objectStatus "@baseboard_fab2_lib.baseboard_fab2(sch_1):page168_i46:b" )
			)
			( pin "R25W167.1"
				( objectStatus "@baseboard_fab2_lib.baseboard_fab2(sch_1):page269_i10:a" )
			)
			( pin "R25W167.2"
				( objectStatus "@baseboard_fab2_lib.baseboard_fab2(sch_1):page269_i10:b" )
			)
			( pin "R25W168.1"
				( objectStatus "@baseboard_fab2_lib.baseboard_fab2(sch_1):page269_i11:a" )
			)
			( pin "R25W168.2"
				( objectStatus "@baseboard_fab2_lib.baseboard_fab2(sch_1):page269_i11:b" )
			)
			( pin "R25W169.1"
				( objectStatus "@baseboard_fab2_lib.baseboard_fab2(sch_1):page269_i12:a" )
			)
			( pin "R25W169.2"
				( objectStatus "@baseboard_fab2_lib.baseboard_fab2(sch_1):page269_i12:b" )
			)
			( pin "R25W170.1"
				( objectStatus "@baseboard_fab2_lib.baseboard_fab2(sch_1):page269_i13:a" )
			)
			( pin "R25W170.2"
				( objectStatus "@baseboard_fab2_lib.baseboard_fab2(sch_1):page269_i13:b" )
			)
			( pin "R25W177.1"
				( objectStatus "@baseboard_fab2_lib.baseboard_fab2(sch_1):page269_i18:a" )
			)
			( pin "R25W177.2"
				( objectStatus "@baseboard_fab2_lib.baseboard_fab2(sch_1):page269_i18:b" )
			)
			( pin "R25W178.1"
				( objectStatus "@baseboard_fab2_lib.baseboard_fab2(sch_1):page269_i19:a" )
			)
			( pin "R25W178.2"
				( objectStatus "@baseboard_fab2_lib.baseboard_fab2(sch_1):page269_i19:b" )
			)
			( pin "R25W160.1"
				( objectStatus "@baseboard_fab2_lib.baseboard_fab2(sch_1):page269_i20:a" )
			)
			( pin "R25W160.2"
				( objectStatus "@baseboard_fab2_lib.baseboard_fab2(sch_1):page269_i20:b" )
			)
			( pin "R25W161.1"
				( objectStatus "@baseboard_fab2_lib.baseboard_fab2(sch_1):page269_i21:a" )
			)
			( pin "R25W161.2"
				( objectStatus "@baseboard_fab2_lib.baseboard_fab2(sch_1):page269_i21:b" )
			)
			( pin "R25W158.1"
				( objectStatus "@baseboard_fab2_lib.baseboard_fab2(sch_1):page269_i22:a" )
			)
			( pin "R25W158.2"
				( objectStatus "@baseboard_fab2_lib.baseboard_fab2(sch_1):page269_i22:b" )
			)
			( pin "R25W159.1"
				( objectStatus "@baseboard_fab2_lib.baseboard_fab2(sch_1):page269_i24:a" )
			)
			( pin "R25W159.2"
				( objectStatus "@baseboard_fab2_lib.baseboard_fab2(sch_1):page269_i24:b" )
			)
			( pin "C25W91.1"
				( objectStatus "@baseboard_fab2_lib.baseboard_fab2(sch_1):page269_i26:a" )
			)
			( pin "C25W91.2"
				( objectStatus "@baseboard_fab2_lib.baseboard_fab2(sch_1):page269_i26:b" )
			)
			( pin "C25W94.1"
				( objectStatus "@baseboard_fab2_lib.baseboard_fab2(sch_1):page269_i32:a" )
			)
			( pin "C25W94.2"
				( objectStatus "@baseboard_fab2_lib.baseboard_fab2(sch_1):page269_i32:b" )
			)
			( pin "U25W12.12"
				( objectStatus "@baseboard_fab2_lib.baseboard_fab2(sch_1):page269_i33:a(0)" )
			)
			( pin "U25W12.9"
				( objectStatus "@baseboard_fab2_lib.baseboard_fab2(sch_1):page269_i33:a(1)" )
			)
			( pin "U25W12.5"
				( objectStatus "@baseboard_fab2_lib.baseboard_fab2(sch_1):page269_i33:a(2)" )
			)
			( pin "U25W12.2"
				( objectStatus "@baseboard_fab2_lib.baseboard_fab2(sch_1):page269_i33:a(3)" )
			)
			( pin "U25W12.11"
				( objectStatus "@baseboard_fab2_lib.baseboard_fab2(sch_1):page269_i33:b(0)" )
			)
			( pin "U25W12.8"
				( objectStatus "@baseboard_fab2_lib.baseboard_fab2(sch_1):page269_i33:b(1)" )
			)
			( pin "U25W12.6"
				( objectStatus "@baseboard_fab2_lib.baseboard_fab2(sch_1):page269_i33:b(2)" )
			)
			( pin "U25W12.3"
				( objectStatus "@baseboard_fab2_lib.baseboard_fab2(sch_1):page269_i33:b(3)" )
			)
			( pin "U25W12.13"
				( objectStatus "@baseboard_fab2_lib.baseboard_fab2(sch_1):page269_i33:oe(0)" )
			)
			( pin "U25W12.10"
				( objectStatus "@baseboard_fab2_lib.baseboard_fab2(sch_1):page269_i33:oe(1)" )
			)
			( pin "U25W12.4"
				( objectStatus "@baseboard_fab2_lib.baseboard_fab2(sch_1):page269_i33:oe(2)" )
			)
			( pin "U25W12.1"
				( objectStatus "@baseboard_fab2_lib.baseboard_fab2(sch_1):page269_i33:oe(3)" )
			)
			( pin "U25W10.13"
				( objectStatus "@baseboard_fab2_lib.baseboard_fab2(sch_1):page269_i49:a0" )
			)
			( pin "U25W10.12"
				( objectStatus "@baseboard_fab2_lib.baseboard_fab2(sch_1):page269_i49:a1" )
			)
			( pin "U25W10.10"
				( objectStatus "@baseboard_fab2_lib.baseboard_fab2(sch_1):page269_i49:a2" )
			)
			( pin "U25W10.9"
				( objectStatus "@baseboard_fab2_lib.baseboard_fab2(sch_1):page269_i49:a3" )
			)
			( pin "U25W10.2"
				( objectStatus "@baseboard_fab2_lib.baseboard_fab2(sch_1):page269_i49:b0" )
			)
			( pin "U25W10.3"
				( objectStatus "@baseboard_fab2_lib.baseboard_fab2(sch_1):page269_i49:b1" )
			)
			( pin "U25W10.5"
				( objectStatus "@baseboard_fab2_lib.baseboard_fab2(sch_1):page269_i49:b2" )
			)
			( pin "U25W10.6"
				( objectStatus "@baseboard_fab2_lib.baseboard_fab2(sch_1):page269_i49:b3" )
			)
			( pin "U25W10.1"
				( objectStatus "@baseboard_fab2_lib.baseboard_fab2(sch_1):page269_i49:dir" )
			)
			( pin "U25W10.7"
				( objectStatus "@baseboard_fab2_lib.baseboard_fab2(sch_1):page269_i49:gnd(0)" )
			)
			( pin "U25W10.8"
				( objectStatus "@baseboard_fab2_lib.baseboard_fab2(sch_1):page269_i49:gnd(1)" )
			)
			( pin "U25W10.11"
				( objectStatus "@baseboard_fab2_lib.baseboard_fab2(sch_1):page269_i49:gnd(2)" )
			)
			( pin "U25W10.14"
				( objectStatus "@baseboard_fab2_lib.baseboard_fab2(sch_1):page269_i49:vcc" )
			)
			( pin "U25W10.4"
				( objectStatus "@baseboard_fab2_lib.baseboard_fab2(sch_1):page269_i49:vref" )
			)
			( pin "R25W180.1"
				( objectStatus "@baseboard_fab2_lib.baseboard_fab2(sch_1):page268_i2:a" )
			)
			( pin "R25W180.2"
				( objectStatus "@baseboard_fab2_lib.baseboard_fab2(sch_1):page268_i2:b" )
			)
			( pin "C25W97.1"
				( objectStatus "@baseboard_fab2_lib.baseboard_fab2(sch_1):page268_i4:a" )
			)
			( pin "C25W97.2"
				( objectStatus "@baseboard_fab2_lib.baseboard_fab2(sch_1):page268_i4:b" )
			)
			( pin "R25W179.1"
				( objectStatus "@baseboard_fab2_lib.baseboard_fab2(sch_1):page268_i7:a" )
			)
			( pin "R25W179.2"
				( objectStatus "@baseboard_fab2_lib.baseboard_fab2(sch_1):page268_i7:b" )
			)
			( pin "C25W96.1"
				( objectStatus "@baseboard_fab2_lib.baseboard_fab2(sch_1):page268_i9:a" )
			)
			( pin "C25W96.2"
				( objectStatus "@baseboard_fab2_lib.baseboard_fab2(sch_1):page268_i9:b" )
			)
			( pin "U25W15.2"
				( objectStatus "@baseboard_fab2_lib.baseboard_fab2(sch_1):page268_i12:a" )
			)
			( pin "U25W15.4"
				( objectStatus "@baseboard_fab2_lib.baseboard_fab2(sch_1):page268_i12:y" )
			)
			( pin "U25W14.2"
				( objectStatus "@baseboard_fab2_lib.baseboard_fab2(sch_1):page268_i13:a" )
			)
			( pin "U25W14.4"
				( objectStatus "@baseboard_fab2_lib.baseboard_fab2(sch_1):page268_i13:y" )
			)
			( pin "R25W176.1"
				( objectStatus "@baseboard_fab2_lib.baseboard_fab2(sch_1):page268_i14:a" )
			)
			( pin "R25W176.2"
				( objectStatus "@baseboard_fab2_lib.baseboard_fab2(sch_1):page268_i14:b" )
			)
			( pin "R25W175.1"
				( objectStatus "@baseboard_fab2_lib.baseboard_fab2(sch_1):page268_i17:a" )
			)
			( pin "R25W175.2"
				( objectStatus "@baseboard_fab2_lib.baseboard_fab2(sch_1):page268_i17:b" )
			)
			( pin "C25W92.1"
				( objectStatus "@baseboard_fab2_lib.baseboard_fab2(sch_1):page268_i23:a" )
			)
			( pin "C25W92.2"
				( objectStatus "@baseboard_fab2_lib.baseboard_fab2(sch_1):page268_i23:b" )
			)
			( pin "R25W166.1"
				( objectStatus "@baseboard_fab2_lib.baseboard_fab2(sch_1):page268_i26:a" )
			)
			( pin "R25W166.2"
				( objectStatus "@baseboard_fab2_lib.baseboard_fab2(sch_1):page268_i26:b" )
			)
			( pin "C25W93.1"
				( objectStatus "@baseboard_fab2_lib.baseboard_fab2(sch_1):page268_i27:a" )
			)
			( pin "C25W93.2"
				( objectStatus "@baseboard_fab2_lib.baseboard_fab2(sch_1):page268_i27:b" )
			)
			( pin "R25W165.1"
				( objectStatus "@baseboard_fab2_lib.baseboard_fab2(sch_1):page268_i28:a" )
			)
			( pin "R25W165.2"
				( objectStatus "@baseboard_fab2_lib.baseboard_fab2(sch_1):page268_i28:b" )
			)
			( pin "R25W164.1"
				( objectStatus "@baseboard_fab2_lib.baseboard_fab2(sch_1):page268_i29:a" )
			)
			( pin "R25W164.2"
				( objectStatus "@baseboard_fab2_lib.baseboard_fab2(sch_1):page268_i29:b" )
			)
			( pin "U25W11.13"
				( objectStatus "@baseboard_fab2_lib.baseboard_fab2(sch_1):page268_i33:a0" )
			)
			( pin "U25W11.12"
				( objectStatus "@baseboard_fab2_lib.baseboard_fab2(sch_1):page268_i33:a1" )
			)
			( pin "U25W11.10"
				( objectStatus "@baseboard_fab2_lib.baseboard_fab2(sch_1):page268_i33:a2" )
			)
			( pin "U25W11.9"
				( objectStatus "@baseboard_fab2_lib.baseboard_fab2(sch_1):page268_i33:a3" )
			)
			( pin "U25W11.2"
				( objectStatus "@baseboard_fab2_lib.baseboard_fab2(sch_1):page268_i33:b0" )
			)
			( pin "U25W11.3"
				( objectStatus "@baseboard_fab2_lib.baseboard_fab2(sch_1):page268_i33:b1" )
			)
			( pin "U25W11.5"
				( objectStatus "@baseboard_fab2_lib.baseboard_fab2(sch_1):page268_i33:b2" )
			)
			( pin "U25W11.6"
				( objectStatus "@baseboard_fab2_lib.baseboard_fab2(sch_1):page268_i33:b3" )
			)
			( pin "U25W11.1"
				( objectStatus "@baseboard_fab2_lib.baseboard_fab2(sch_1):page268_i33:dir" )
			)
			( pin "U25W11.7"
				( objectStatus "@baseboard_fab2_lib.baseboard_fab2(sch_1):page268_i33:gnd(0)" )
			)
			( pin "U25W11.8"
				( objectStatus "@baseboard_fab2_lib.baseboard_fab2(sch_1):page268_i33:gnd(1)" )
			)
			( pin "U25W11.11"
				( objectStatus "@baseboard_fab2_lib.baseboard_fab2(sch_1):page268_i33:gnd(2)" )
			)
			( pin "U25W11.14"
				( objectStatus "@baseboard_fab2_lib.baseboard_fab2(sch_1):page268_i33:vcc" )
			)
			( pin "U25W11.4"
				( objectStatus "@baseboard_fab2_lib.baseboard_fab2(sch_1):page268_i33:vref" )
			)
			( pin "U25W13.8"
				( objectStatus "@baseboard_fab2_lib.baseboard_fab2(sch_1):page269_i53:com" )
			)
			( pin "U25W13.7"
				( objectStatus "@baseboard_fab2_lib.baseboard_fab2(sch_1):page269_i53:\en#\" )
			)
			( pin "U25W13.5"
				( objectStatus "@baseboard_fab2_lib.baseboard_fab2(sch_1):page269_i53:gnd" )
			)
			( pin "U25W13.3"
				( objectStatus "@baseboard_fab2_lib.baseboard_fab2(sch_1):page269_i53:\in\" )
			)
			( pin "U25W13.1"
				( objectStatus "@baseboard_fab2_lib.baseboard_fab2(sch_1):page269_i53:nc" )
			)
			( pin "U25W13.4"
				( objectStatus "@baseboard_fab2_lib.baseboard_fab2(sch_1):page269_i53:no" )
			)
			( pin "U25W13.2"
				( objectStatus "@baseboard_fab2_lib.baseboard_fab2(sch_1):page269_i53:\v+\" )
			)
			( pin "U25W13.6"
				( objectStatus "@baseboard_fab2_lib.baseboard_fab2(sch_1):page269_i53:\v-\" )
			)
			( pin "C25W95.1"
				( objectStatus "@baseboard_fab2_lib.baseboard_fab2(sch_1):page269_i56:a" )
			)
			( pin "C25W95.2"
				( objectStatus "@baseboard_fab2_lib.baseboard_fab2(sch_1):page269_i56:b" )
			)
			( pin "R6W46.1"
				( objectStatus "@baseboard_fab2_lib.baseboard_fab2(sch_1):page164_i93:a" )
			)
			( pin "R6W46.2"
				( objectStatus "@baseboard_fab2_lib.baseboard_fab2(sch_1):page164_i93:b" )
			)
			( pin "R25W182.1"
				( objectStatus "@baseboard_fab2_lib.baseboard_fab2(sch_1):page144_i151:a" )
			)
			( pin "R25W182.2"
				( objectStatus "@baseboard_fab2_lib.baseboard_fab2(sch_1):page144_i151:b" )
			)
			( pin "R25W181.1"
				( objectStatus "@baseboard_fab2_lib.baseboard_fab2(sch_1):page147_i173:a" )
			)
			( pin "R25W181.2"
				( objectStatus "@baseboard_fab2_lib.baseboard_fab2(sch_1):page147_i173:b" )
			)
			( pin "R6W45.1"
				( objectStatus "@baseboard_fab2_lib.baseboard_fab2(sch_1):page164_i94:a" )
			)
			( pin "R6W45.2"
				( objectStatus "@baseboard_fab2_lib.baseboard_fab2(sch_1):page164_i94:b" )
			)
			( pin "R6W42.1"
				( objectStatus "@baseboard_fab2_lib.baseboard_fab2(sch_1):page164_i95:a" )
			)
			( pin "R6W42.2"
				( objectStatus "@baseboard_fab2_lib.baseboard_fab2(sch_1):page164_i95:b" )
			)
			( pin "R6W43.1"
				( objectStatus "@baseboard_fab2_lib.baseboard_fab2(sch_1):page164_i96:a" )
			)
			( pin "R6W43.2"
				( objectStatus "@baseboard_fab2_lib.baseboard_fab2(sch_1):page164_i96:b" )
			)
			( pin "U1L10.12"
				( objectStatus "@baseboard_fab2_lib.baseboard_fab2(sch_1):page189_i67:a(0)" )
			)
			( pin "U1L10.9"
				( objectStatus "@baseboard_fab2_lib.baseboard_fab2(sch_1):page189_i67:a(1)" )
			)
			( pin "U1L10.5"
				( objectStatus "@baseboard_fab2_lib.baseboard_fab2(sch_1):page189_i67:a(2)" )
			)
			( pin "U1L10.2"
				( objectStatus "@baseboard_fab2_lib.baseboard_fab2(sch_1):page189_i67:a(3)" )
			)
			( pin "U1L10.11"
				( objectStatus "@baseboard_fab2_lib.baseboard_fab2(sch_1):page189_i67:b(0)" )
			)
			( pin "U1L10.8"
				( objectStatus "@baseboard_fab2_lib.baseboard_fab2(sch_1):page189_i67:b(1)" )
			)
			( pin "U1L10.6"
				( objectStatus "@baseboard_fab2_lib.baseboard_fab2(sch_1):page189_i67:b(2)" )
			)
			( pin "U1L10.3"
				( objectStatus "@baseboard_fab2_lib.baseboard_fab2(sch_1):page189_i67:b(3)" )
			)
			( pin "U1L10.13"
				( objectStatus "@baseboard_fab2_lib.baseboard_fab2(sch_1):page189_i67:oe(0)" )
			)
			( pin "U1L10.10"
				( objectStatus "@baseboard_fab2_lib.baseboard_fab2(sch_1):page189_i67:oe(1)" )
			)
			( pin "U1L10.4"
				( objectStatus "@baseboard_fab2_lib.baseboard_fab2(sch_1):page189_i67:oe(2)" )
			)
			( pin "U1L10.1"
				( objectStatus "@baseboard_fab2_lib.baseboard_fab2(sch_1):page189_i67:oe(3)" )
			)
			( pin "C1L119.1"
				( objectStatus "@baseboard_fab2_lib.baseboard_fab2(sch_1):page189_i69:a" )
			)
			( pin "C1L119.2"
				( objectStatus "@baseboard_fab2_lib.baseboard_fab2(sch_1):page189_i69:b" )
			)
			( pin "R7G114.1"
				( objectStatus "@baseboard_fab2_lib.baseboard_fab2(sch_1):page189_i76:a" )
			)
			( pin "R7G114.2"
				( objectStatus "@baseboard_fab2_lib.baseboard_fab2(sch_1):page189_i76:b" )
			)
			( pin "C4E29.1"
				( objectStatus "@baseboard_fab2_lib.baseboard_fab2(sch_1):page193_i175:a" )
			)
			( pin "C4E29.2"
				( objectStatus "@baseboard_fab2_lib.baseboard_fab2(sch_1):page193_i175:b" )
			)
			( pin "R25W184.1"
				( objectStatus "@baseboard_fab2_lib.baseboard_fab2(sch_1):page146_i166:a" )
			)
			( pin "R25W184.2"
				( objectStatus "@baseboard_fab2_lib.baseboard_fab2(sch_1):page146_i166:b" )
			)
			( pin "R8E3.1"
				( objectStatus "@baseboard_fab2_lib.baseboard_fab2(sch_1):page133_i371:a" )
			)
			( pin "R8E3.2"
				( objectStatus "@baseboard_fab2_lib.baseboard_fab2(sch_1):page133_i371:b" )
			)
			( pin "C5P30.1"
				( objectStatus "@baseboard_fab2_lib.baseboard_fab2(sch_1):page42_i221:a" )
			)
			( pin "C5P30.2"
				( objectStatus "@baseboard_fab2_lib.baseboard_fab2(sch_1):page42_i221:b" )
			)
			( pin "C5P19.1"
				( objectStatus "@baseboard_fab2_lib.baseboard_fab2(sch_1):page42_i222:a" )
			)
			( pin "C5P19.2"
				( objectStatus "@baseboard_fab2_lib.baseboard_fab2(sch_1):page42_i222:b" )
			)
			( pin "C4P4.1"
				( objectStatus "@baseboard_fab2_lib.baseboard_fab2(sch_1):page42_i223:a" )
			)
			( pin "C4P4.2"
				( objectStatus "@baseboard_fab2_lib.baseboard_fab2(sch_1):page42_i223:b" )
			)
			( pin "C4P7.1"
				( objectStatus "@baseboard_fab2_lib.baseboard_fab2(sch_1):page42_i224:a" )
			)
			( pin "C4P7.2"
				( objectStatus "@baseboard_fab2_lib.baseboard_fab2(sch_1):page42_i224:b" )
			)
			( pin "C4P3.1"
				( objectStatus "@baseboard_fab2_lib.baseboard_fab2(sch_1):page42_i225:a" )
			)
			( pin "C4P3.2"
				( objectStatus "@baseboard_fab2_lib.baseboard_fab2(sch_1):page42_i225:b" )
			)
			( pin "C5P10.1"
				( objectStatus "@baseboard_fab2_lib.baseboard_fab2(sch_1):page42_i226:a" )
			)
			( pin "C5P10.2"
				( objectStatus "@baseboard_fab2_lib.baseboard_fab2(sch_1):page42_i226:b" )
			)
			( pin "C5P11.1"
				( objectStatus "@baseboard_fab2_lib.baseboard_fab2(sch_1):page42_i227:a" )
			)
			( pin "C5P11.2"
				( objectStatus "@baseboard_fab2_lib.baseboard_fab2(sch_1):page42_i227:b" )
			)
			( pin "C5P18.1"
				( objectStatus "@baseboard_fab2_lib.baseboard_fab2(sch_1):page42_i228:a" )
			)
			( pin "C5P18.2"
				( objectStatus "@baseboard_fab2_lib.baseboard_fab2(sch_1):page42_i228:b" )
			)
			( pin "C5P28.1"
				( objectStatus "@baseboard_fab2_lib.baseboard_fab2(sch_1):page42_i229:a" )
			)
			( pin "C5P28.2"
				( objectStatus "@baseboard_fab2_lib.baseboard_fab2(sch_1):page42_i229:b" )
			)
			( pin "C4P2.1"
				( objectStatus "@baseboard_fab2_lib.baseboard_fab2(sch_1):page42_i230:a" )
			)
			( pin "C4P2.2"
				( objectStatus "@baseboard_fab2_lib.baseboard_fab2(sch_1):page42_i230:b" )
			)
			( pin "C5P31.1"
				( objectStatus "@baseboard_fab2_lib.baseboard_fab2(sch_1):page42_i231:a" )
			)
			( pin "C5P31.2"
				( objectStatus "@baseboard_fab2_lib.baseboard_fab2(sch_1):page42_i231:b" )
			)
			( pin "C5P13.1"
				( objectStatus "@baseboard_fab2_lib.baseboard_fab2(sch_1):page42_i232:a" )
			)
			( pin "C5P13.2"
				( objectStatus "@baseboard_fab2_lib.baseboard_fab2(sch_1):page42_i232:b" )
			)
			( pin "C4P5.1"
				( objectStatus "@baseboard_fab2_lib.baseboard_fab2(sch_1):page42_i233:a" )
			)
			( pin "C4P5.2"
				( objectStatus "@baseboard_fab2_lib.baseboard_fab2(sch_1):page42_i233:b" )
			)
			( pin "C5P20.1"
				( objectStatus "@baseboard_fab2_lib.baseboard_fab2(sch_1):page42_i234:a" )
			)
			( pin "C5P20.2"
				( objectStatus "@baseboard_fab2_lib.baseboard_fab2(sch_1):page42_i234:b" )
			)
			( pin "C5P21.1"
				( objectStatus "@baseboard_fab2_lib.baseboard_fab2(sch_1):page42_i235:a" )
			)
			( pin "C5P21.2"
				( objectStatus "@baseboard_fab2_lib.baseboard_fab2(sch_1):page42_i235:b" )
			)
			( pin "C5P12.1"
				( objectStatus "@baseboard_fab2_lib.baseboard_fab2(sch_1):page42_i236:a" )
			)
			( pin "C5P12.2"
				( objectStatus "@baseboard_fab2_lib.baseboard_fab2(sch_1):page42_i236:b" )
			)
			( pin "C7P9.1"
				( objectStatus "@baseboard_fab2_lib.baseboard_fab2(sch_1):page76_i258:a" )
			)
			( pin "C7P9.2"
				( objectStatus "@baseboard_fab2_lib.baseboard_fab2(sch_1):page76_i258:b" )
			)
			( pin "C7P5.1"
				( objectStatus "@baseboard_fab2_lib.baseboard_fab2(sch_1):page76_i259:a" )
			)
			( pin "C7P5.2"
				( objectStatus "@baseboard_fab2_lib.baseboard_fab2(sch_1):page76_i259:b" )
			)
			( pin "C7P10.1"
				( objectStatus "@baseboard_fab2_lib.baseboard_fab2(sch_1):page76_i266:a" )
			)
			( pin "C7P10.2"
				( objectStatus "@baseboard_fab2_lib.baseboard_fab2(sch_1):page76_i266:b" )
			)
			( pin "C7P7.1"
				( objectStatus "@baseboard_fab2_lib.baseboard_fab2(sch_1):page76_i267:a" )
			)
			( pin "C7P7.2"
				( objectStatus "@baseboard_fab2_lib.baseboard_fab2(sch_1):page76_i267:b" )
			)
			( pin "C8P14.1"
				( objectStatus "@baseboard_fab2_lib.baseboard_fab2(sch_1):page76_i272:a" )
			)
			( pin "C8P14.2"
				( objectStatus "@baseboard_fab2_lib.baseboard_fab2(sch_1):page76_i272:b" )
			)
			( pin "C8P9.1"
				( objectStatus "@baseboard_fab2_lib.baseboard_fab2(sch_1):page76_i273:a" )
			)
			( pin "C8P9.2"
				( objectStatus "@baseboard_fab2_lib.baseboard_fab2(sch_1):page76_i273:b" )
			)
			( pin "C8P8.1"
				( objectStatus "@baseboard_fab2_lib.baseboard_fab2(sch_1):page76_i274:a" )
			)
			( pin "C8P8.2"
				( objectStatus "@baseboard_fab2_lib.baseboard_fab2(sch_1):page76_i274:b" )
			)
			( pin "R7F36.1"
				( objectStatus "@baseboard_fab2_lib.baseboard_fab2(sch_1):page215_i75:a" )
			)
			( pin "R7F36.2"
				( objectStatus "@baseboard_fab2_lib.baseboard_fab2(sch_1):page215_i75:b" )
			)
			( pin "C25W98.1"
				( objectStatus "@baseboard_fab2_lib.baseboard_fab2(sch_1):page268_i40:a" )
			)
			( pin "C25W98.2"
				( objectStatus "@baseboard_fab2_lib.baseboard_fab2(sch_1):page268_i40:b" )
			)
			( pin "Q25W5.3"
				( objectStatus "@baseboard_fab2_lib.baseboard_fab2(sch_1):page268_i51:drn" )
			)
			( pin "Q25W5.1"
				( objectStatus "@baseboard_fab2_lib.baseboard_fab2(sch_1):page268_i51:gate" )
			)
			( pin "Q25W5.2"
				( objectStatus "@baseboard_fab2_lib.baseboard_fab2(sch_1):page268_i51:src" )
			)
			( pin "R25W185.1"
				( objectStatus "@baseboard_fab2_lib.baseboard_fab2(sch_1):page268_i54:a" )
			)
			( pin "R25W185.2"
				( objectStatus "@baseboard_fab2_lib.baseboard_fab2(sch_1):page268_i54:b" )
			)
			( pin "R25W186.1"
				( objectStatus "@baseboard_fab2_lib.baseboard_fab2(sch_1):page189_i77:a" )
			)
			( pin "R25W186.2"
				( objectStatus "@baseboard_fab2_lib.baseboard_fab2(sch_1):page189_i77:b" )
			)
			( pin "R7W5.1"
				( objectStatus "@baseboard_fab2_lib.baseboard_fab2(sch_1):page153_i187:a" )
			)
			( pin "R7W5.2"
				( objectStatus "@baseboard_fab2_lib.baseboard_fab2(sch_1):page153_i187:b" )
			)
			( pin "EU1D4.33"
				( objectStatus "@baseboard_fab2_lib.baseboard_fab2(sch_1):page207_i113:boost" )
			)
			( pin "EU1D4.35"
				( objectStatus "@baseboard_fab2_lib.baseboard_fab2(sch_1):page207_i113:en" )
			)
			( pin "EU1D4.6"
				( objectStatus "@baseboard_fab2_lib.baseboard_fab2(sch_1):page207_i113:gl(0)" )
			)
			( pin "EU1D4.41"
				( objectStatus "@baseboard_fab2_lib.baseboard_fab2(sch_1):page207_i113:gl(1)" )
			)
			( pin "EU1D4.38"
				( objectStatus "@baseboard_fab2_lib.baseboard_fab2(sch_1):page207_i113:iout" )
			)
			( pin "EU1D4.2"
				( objectStatus "@baseboard_fab2_lib.baseboard_fab2(sch_1):page207_i113:lgnd" )
			)
			( pin "EU1D4.31"
				( objectStatus "@baseboard_fab2_lib.baseboard_fab2(sch_1):page207_i113:nc" )
			)
			( pin "EU1D4.37"
				( objectStatus "@baseboard_fab2_lib.baseboard_fab2(sch_1):page207_i113:ocset" )
			)
			( pin "EU1D4.5"
				( objectStatus "@baseboard_fab2_lib.baseboard_fab2(sch_1):page207_i113:pgnd(0)" )
			)
			( pin "EU1D4.7"
				( objectStatus "@baseboard_fab2_lib.baseboard_fab2(sch_1):page207_i113:pgnd(1)" )
			)
			( pin "EU1D4.40"
				( objectStatus "@baseboard_fab2_lib.baseboard_fab2(sch_1):page207_i113:pgnd(2)" )
			)
			( pin "EU1D4.32"
				( objectStatus "@baseboard_fab2_lib.baseboard_fab2(sch_1):page207_i113:phase" )
			)
			( pin "EU1D4.34"
				( objectStatus "@baseboard_fab2_lib.baseboard_fab2(sch_1):page207_i113:pwm" )
			)
			( pin "EU1D4.39"
				( objectStatus "@baseboard_fab2_lib.baseboard_fab2(sch_1):page207_i113:refin" )
			)
			( pin "EU1D4.10"
				( objectStatus "@baseboard_fab2_lib.baseboard_fab2(sch_1):page207_i113:sw" )
			)
			( pin "EU1D4.36"
				( objectStatus "@baseboard_fab2_lib.baseboard_fab2(sch_1):page207_i113:tout_flt" )
			)
			( pin "EU1D4.3"
				( objectStatus "@baseboard_fab2_lib.baseboard_fab2(sch_1):page207_i113:vcc" )
			)
			( pin "EU1D4.4"
				( objectStatus "@baseboard_fab2_lib.baseboard_fab2(sch_1):page207_i113:vdrv" )
			)
			( pin "EU1D4.25"
				( objectStatus "@baseboard_fab2_lib.baseboard_fab2(sch_1):page207_i113:vin(0)" )
			)
			( pin "EU1D4.30"
				( objectStatus "@baseboard_fab2_lib.baseboard_fab2(sch_1):page207_i113:vin(1)" )
			)
			( pin "EU1D4.1"
				( objectStatus "@baseboard_fab2_lib.baseboard_fab2(sch_1):page207_i113:vos" )
			)
			( pin "U25W17.1"
				( objectStatus "@baseboard_fab2_lib.baseboard_fab2(sch_1):page269_i61:a(0)" )
			)
			( pin "U25W17.2"
				( objectStatus "@baseboard_fab2_lib.baseboard_fab2(sch_1):page269_i61:b(0)" )
			)
			( pin "U25W17.4"
				( objectStatus "@baseboard_fab2_lib.baseboard_fab2(sch_1):page269_i61:y(0)" )
			)
			( pin "C25W99.1"
				( objectStatus "@baseboard_fab2_lib.baseboard_fab2(sch_1):page269_i62:a" )
			)
			( pin "C25W99.2"
				( objectStatus "@baseboard_fab2_lib.baseboard_fab2(sch_1):page269_i62:b" )
			)
			( pin "U25W18.1"
				( objectStatus "@baseboard_fab2_lib.baseboard_fab2(sch_1):page268_i57:a(0)" )
			)
			( pin "U25W18.2"
				( objectStatus "@baseboard_fab2_lib.baseboard_fab2(sch_1):page268_i57:b(0)" )
			)
			( pin "U25W18.4"
				( objectStatus "@baseboard_fab2_lib.baseboard_fab2(sch_1):page268_i57:y(0)" )
			)
			( pin "C25W100.1"
				( objectStatus "@baseboard_fab2_lib.baseboard_fab2(sch_1):page268_i60:a" )
			)
			( pin "C25W100.2"
				( objectStatus "@baseboard_fab2_lib.baseboard_fab2(sch_1):page268_i60:b" )
			)
			( pin "R9W33.1"
				( objectStatus "@baseboard_fab2_lib.baseboard_fab2(sch_1):page158_i153:a" )
			)
			( pin "R9W33.2"
				( objectStatus "@baseboard_fab2_lib.baseboard_fab2(sch_1):page158_i153:b" )
			)
			( pin "R9W34.1"
				( objectStatus "@baseboard_fab2_lib.baseboard_fab2(sch_1):page158_i154:a" )
			)
			( pin "R9W34.2"
				( objectStatus "@baseboard_fab2_lib.baseboard_fab2(sch_1):page158_i154:b" )
			)
			( pin "R9W35.1"
				( objectStatus "@baseboard_fab2_lib.baseboard_fab2(sch_1):page158_i155:a" )
			)
			( pin "R9W35.2"
				( objectStatus "@baseboard_fab2_lib.baseboard_fab2(sch_1):page158_i155:b" )
			)
			( pin "CR9W1.2"
				( objectStatus "@baseboard_fab2_lib.baseboard_fab2(sch_1):page155_i202:a" )
			)
			( pin "CR9W1.1"
				( objectStatus "@baseboard_fab2_lib.baseboard_fab2(sch_1):page155_i202:c" )
			)
			( pin "C9W14.1"
				( objectStatus "@baseboard_fab2_lib.baseboard_fab2(sch_1):page238_i46:a" )
			)
			( pin "C9W14.2"
				( objectStatus "@baseboard_fab2_lib.baseboard_fab2(sch_1):page238_i46:b" )
			)
			( pin "C9W17.1"
				( objectStatus "@baseboard_fab2_lib.baseboard_fab2(sch_1):page239_i104:a" )
			)
			( pin "C9W17.2"
				( objectStatus "@baseboard_fab2_lib.baseboard_fab2(sch_1):page239_i104:b" )
			)
			( pin "C9W16.1"
				( objectStatus "@baseboard_fab2_lib.baseboard_fab2(sch_1):page238_i50:a" )
			)
			( pin "C9W16.2"
				( objectStatus "@baseboard_fab2_lib.baseboard_fab2(sch_1):page238_i50:b" )
			)
			( pin "C9W19.1"
				( objectStatus "@baseboard_fab2_lib.baseboard_fab2(sch_1):page239_i111:a" )
			)
			( pin "C9W19.2"
				( objectStatus "@baseboard_fab2_lib.baseboard_fab2(sch_1):page239_i111:b" )
			)
			( pin "R7D39.1"
				( objectStatus "@baseboard_fab2_lib.baseboard_fab2(sch_1):page104_i103:a" )
			)
			( pin "R7D39.2"
				( objectStatus "@baseboard_fab2_lib.baseboard_fab2(sch_1):page104_i103:b" )
			)
			( pin "R7D37.1"
				( objectStatus "@baseboard_fab2_lib.baseboard_fab2(sch_1):page104_i104:a" )
			)
			( pin "R7D37.2"
				( objectStatus "@baseboard_fab2_lib.baseboard_fab2(sch_1):page104_i104:b" )
			)
			( pin "S9W1.1"
				( objectStatus "@baseboard_fab2_lib.baseboard_fab2(sch_1):page268_i63:\1\" )
			)
			( pin "S9W1.2"
				( objectStatus "@baseboard_fab2_lib.baseboard_fab2(sch_1):page268_i63:\2\" )
			)
			( pin "S9W1.3"
				( objectStatus "@baseboard_fab2_lib.baseboard_fab2(sch_1):page268_i63:\3\" )
			)
			( pin "S9W1.4"
				( objectStatus "@baseboard_fab2_lib.baseboard_fab2(sch_1):page268_i63:\4\" )
			)
			( pin "S9W1.5"
				( objectStatus "@baseboard_fab2_lib.baseboard_fab2(sch_1):page268_i63:\5\" )
			)
			( pin "S9W1.6"
				( objectStatus "@baseboard_fab2_lib.baseboard_fab2(sch_1):page268_i63:\6\" )
			)
			( pin "S9W1.7"
				( objectStatus "@baseboard_fab2_lib.baseboard_fab2(sch_1):page268_i63:\7\" )
			)
			( pin "S9W1.NP1"
				( objectStatus "@baseboard_fab2_lib.baseboard_fab2(sch_1):page268_i63:np1" )
			)
			( pin "S9W1.NP2"
				( objectStatus "@baseboard_fab2_lib.baseboard_fab2(sch_1):page268_i63:np2" )
			)
			( pin "FB25W1.1"
				( objectStatus "@baseboard_fab2_lib.baseboard_fab2(sch_1):page269_i71:\1\" )
			)
			( pin "FB25W1.2"
				( objectStatus "@baseboard_fab2_lib.baseboard_fab2(sch_1):page269_i71:\2\" )
			)
			( pin "FB25W2.1"
				( objectStatus "@baseboard_fab2_lib.baseboard_fab2(sch_1):page269_i72:\1\" )
			)
			( pin "FB25W2.2"
				( objectStatus "@baseboard_fab2_lib.baseboard_fab2(sch_1):page269_i72:\2\" )
			)
			( pin "FB25W3.1"
				( objectStatus "@baseboard_fab2_lib.baseboard_fab2(sch_1):page269_i73:\1\" )
			)
			( pin "FB25W3.2"
				( objectStatus "@baseboard_fab2_lib.baseboard_fab2(sch_1):page269_i73:\2\" )
			)
			( pin "FB25W5.1"
				( objectStatus "@baseboard_fab2_lib.baseboard_fab2(sch_1):page269_i74:\1\" )
			)
			( pin "FB25W5.2"
				( objectStatus "@baseboard_fab2_lib.baseboard_fab2(sch_1):page269_i74:\2\" )
			)
			( pin "FB25W4.1"
				( objectStatus "@baseboard_fab2_lib.baseboard_fab2(sch_1):page269_i75:\1\" )
			)
			( pin "FB25W4.2"
				( objectStatus "@baseboard_fab2_lib.baseboard_fab2(sch_1):page269_i75:\2\" )
			)
			( pin "C1G15.1"
				( objectStatus "@baseboard_fab2_lib.baseboard_fab2(sch_1):page225_i327:\1\" )
			)
			( pin "C1G15.2"
				( objectStatus "@baseboard_fab2_lib.baseboard_fab2(sch_1):page225_i327:\2\" )
			)
			( pin "C1G12.1"
				( objectStatus "@baseboard_fab2_lib.baseboard_fab2(sch_1):page225_i328:\1\" )
			)
			( pin "C1G12.2"
				( objectStatus "@baseboard_fab2_lib.baseboard_fab2(sch_1):page225_i328:\2\" )
			)
			( pin "C1G7.1"
				( objectStatus "@baseboard_fab2_lib.baseboard_fab2(sch_1):page225_i329:\1\" )
			)
			( pin "C1G7.2"
				( objectStatus "@baseboard_fab2_lib.baseboard_fab2(sch_1):page225_i329:\2\" )
			)
			( pin "C7W2.1"
				( objectStatus "@baseboard_fab2_lib.baseboard_fab2(sch_1):page220_i324:\1\" )
			)
			( pin "C7W2.2"
				( objectStatus "@baseboard_fab2_lib.baseboard_fab2(sch_1):page220_i324:\2\" )
			)
			( pin "T1P14.1"
				( objectStatus "@baseboard_fab2_lib.baseboard_fab2(sch_1):page271_i30:\1\" )
			)
			( pin "T1P14.2"
				( objectStatus "@baseboard_fab2_lib.baseboard_fab2(sch_1):page271_i30:\2\" )
			)
			( pin "T1P14.GND1"
				( objectStatus "@baseboard_fab2_lib.baseboard_fab2(sch_1):page271_i30:gnd1" )
			)
			( pin "T1P14.GND2"
				( objectStatus "@baseboard_fab2_lib.baseboard_fab2(sch_1):page271_i30:gnd2" )
			)
			( pin "T1P1.1"
				( objectStatus "@baseboard_fab2_lib.baseboard_fab2(sch_1):page271_i3:\1\" )
			)
			( pin "T1P1.2"
				( objectStatus "@baseboard_fab2_lib.baseboard_fab2(sch_1):page271_i3:\2\" )
			)
			( pin "T1P1.GND1"
				( objectStatus "@baseboard_fab2_lib.baseboard_fab2(sch_1):page271_i3:gnd1" )
			)
			( pin "T1P1.GND2"
				( objectStatus "@baseboard_fab2_lib.baseboard_fab2(sch_1):page271_i3:gnd2" )
			)
			( pin "T1D10.2"
				( objectStatus "@baseboard_fab2_lib.baseboard_fab2(sch_1):page270_i17:dn" )
			)
			( pin "T1D10.1"
				( objectStatus "@baseboard_fab2_lib.baseboard_fab2(sch_1):page270_i17:dp" )
			)
			( pin "T1D10.3"
				( objectStatus "@baseboard_fab2_lib.baseboard_fab2(sch_1):page270_i17:gnd(0)" )
			)
			( pin "T1D10.4"
				( objectStatus "@baseboard_fab2_lib.baseboard_fab2(sch_1):page270_i17:gnd(1)" )
			)
			( pin "T1D10.5"
				( objectStatus "@baseboard_fab2_lib.baseboard_fab2(sch_1):page270_i17:gnd(2)" )
			)
			( pin "T1D10.6"
				( objectStatus "@baseboard_fab2_lib.baseboard_fab2(sch_1):page270_i17:gnd(3)" )
			)
			( pin "T1D10.7"
				( objectStatus "@baseboard_fab2_lib.baseboard_fab2(sch_1):page270_i17:gnd(4)" )
			)
			( pin "T1D10.8"
				( objectStatus "@baseboard_fab2_lib.baseboard_fab2(sch_1):page270_i17:gnd(5)" )
			)
			( pin "T1D10.9"
				( objectStatus "@baseboard_fab2_lib.baseboard_fab2(sch_1):page270_i17:gnd(6)" )
			)
			( pin "T1D10.10"
				( objectStatus "@baseboard_fab2_lib.baseboard_fab2(sch_1):page270_i17:gnd(7)" )
			)
			( pin "T1D10.11"
				( objectStatus "@baseboard_fab2_lib.baseboard_fab2(sch_1):page270_i17:gnd(8)" )
			)
			( pin "T1D10.12"
				( objectStatus "@baseboard_fab2_lib.baseboard_fab2(sch_1):page270_i17:gnd(9)" )
			)
			( pin "T1D1.2"
				( objectStatus "@baseboard_fab2_lib.baseboard_fab2(sch_1):page270_i1:dn" )
			)
			( pin "T1D1.1"
				( objectStatus "@baseboard_fab2_lib.baseboard_fab2(sch_1):page270_i1:dp" )
			)
			( pin "T1D1.3"
				( objectStatus "@baseboard_fab2_lib.baseboard_fab2(sch_1):page270_i1:gnd(0)" )
			)
			( pin "T1D1.4"
				( objectStatus "@baseboard_fab2_lib.baseboard_fab2(sch_1):page270_i1:gnd(1)" )
			)
			( pin "T1D1.5"
				( objectStatus "@baseboard_fab2_lib.baseboard_fab2(sch_1):page270_i1:gnd(2)" )
			)
			( pin "T1D1.6"
				( objectStatus "@baseboard_fab2_lib.baseboard_fab2(sch_1):page270_i1:gnd(3)" )
			)
			( pin "T1D1.7"
				( objectStatus "@baseboard_fab2_lib.baseboard_fab2(sch_1):page270_i1:gnd(4)" )
			)
			( pin "T1D1.8"
				( objectStatus "@baseboard_fab2_lib.baseboard_fab2(sch_1):page270_i1:gnd(5)" )
			)
			( pin "T1D1.9"
				( objectStatus "@baseboard_fab2_lib.baseboard_fab2(sch_1):page270_i1:gnd(6)" )
			)
			( pin "T1D1.10"
				( objectStatus "@baseboard_fab2_lib.baseboard_fab2(sch_1):page270_i1:gnd(7)" )
			)
			( pin "T1D1.11"
				( objectStatus "@baseboard_fab2_lib.baseboard_fab2(sch_1):page270_i1:gnd(8)" )
			)
			( pin "T1D1.12"
				( objectStatus "@baseboard_fab2_lib.baseboard_fab2(sch_1):page270_i1:gnd(9)" )
			)
			( pin "T1D2.2"
				( objectStatus "@baseboard_fab2_lib.baseboard_fab2(sch_1):page270_i3:dn" )
			)
			( pin "T1D2.1"
				( objectStatus "@baseboard_fab2_lib.baseboard_fab2(sch_1):page270_i3:dp" )
			)
			( pin "T1D2.3"
				( objectStatus "@baseboard_fab2_lib.baseboard_fab2(sch_1):page270_i3:gnd(0)" )
			)
			( pin "T1D2.4"
				( objectStatus "@baseboard_fab2_lib.baseboard_fab2(sch_1):page270_i3:gnd(1)" )
			)
			( pin "T1D2.5"
				( objectStatus "@baseboard_fab2_lib.baseboard_fab2(sch_1):page270_i3:gnd(2)" )
			)
			( pin "T1D2.6"
				( objectStatus "@baseboard_fab2_lib.baseboard_fab2(sch_1):page270_i3:gnd(3)" )
			)
			( pin "T1D2.7"
				( objectStatus "@baseboard_fab2_lib.baseboard_fab2(sch_1):page270_i3:gnd(4)" )
			)
			( pin "T1D2.8"
				( objectStatus "@baseboard_fab2_lib.baseboard_fab2(sch_1):page270_i3:gnd(5)" )
			)
			( pin "T1D2.9"
				( objectStatus "@baseboard_fab2_lib.baseboard_fab2(sch_1):page270_i3:gnd(6)" )
			)
			( pin "T1D2.10"
				( objectStatus "@baseboard_fab2_lib.baseboard_fab2(sch_1):page270_i3:gnd(7)" )
			)
			( pin "T1D2.11"
				( objectStatus "@baseboard_fab2_lib.baseboard_fab2(sch_1):page270_i3:gnd(8)" )
			)
			( pin "T1D2.12"
				( objectStatus "@baseboard_fab2_lib.baseboard_fab2(sch_1):page270_i3:gnd(9)" )
			)
			( pin "T1D3.2"
				( objectStatus "@baseboard_fab2_lib.baseboard_fab2(sch_1):page270_i5:dn" )
			)
			( pin "T1D3.1"
				( objectStatus "@baseboard_fab2_lib.baseboard_fab2(sch_1):page270_i5:dp" )
			)
			( pin "T1D3.3"
				( objectStatus "@baseboard_fab2_lib.baseboard_fab2(sch_1):page270_i5:gnd(0)" )
			)
			( pin "T1D3.4"
				( objectStatus "@baseboard_fab2_lib.baseboard_fab2(sch_1):page270_i5:gnd(1)" )
			)
			( pin "T1D3.5"
				( objectStatus "@baseboard_fab2_lib.baseboard_fab2(sch_1):page270_i5:gnd(2)" )
			)
			( pin "T1D3.6"
				( objectStatus "@baseboard_fab2_lib.baseboard_fab2(sch_1):page270_i5:gnd(3)" )
			)
			( pin "T1D3.7"
				( objectStatus "@baseboard_fab2_lib.baseboard_fab2(sch_1):page270_i5:gnd(4)" )
			)
			( pin "T1D3.8"
				( objectStatus "@baseboard_fab2_lib.baseboard_fab2(sch_1):page270_i5:gnd(5)" )
			)
			( pin "T1D3.9"
				( objectStatus "@baseboard_fab2_lib.baseboard_fab2(sch_1):page270_i5:gnd(6)" )
			)
			( pin "T1D3.10"
				( objectStatus "@baseboard_fab2_lib.baseboard_fab2(sch_1):page270_i5:gnd(7)" )
			)
			( pin "T1D3.11"
				( objectStatus "@baseboard_fab2_lib.baseboard_fab2(sch_1):page270_i5:gnd(8)" )
			)
			( pin "T1D3.12"
				( objectStatus "@baseboard_fab2_lib.baseboard_fab2(sch_1):page270_i5:gnd(9)" )
			)
			( pin "T1D4.2"
				( objectStatus "@baseboard_fab2_lib.baseboard_fab2(sch_1):page270_i6:dn" )
			)
			( pin "T1D4.1"
				( objectStatus "@baseboard_fab2_lib.baseboard_fab2(sch_1):page270_i6:dp" )
			)
			( pin "T1D4.3"
				( objectStatus "@baseboard_fab2_lib.baseboard_fab2(sch_1):page270_i6:gnd(0)" )
			)
			( pin "T1D4.4"
				( objectStatus "@baseboard_fab2_lib.baseboard_fab2(sch_1):page270_i6:gnd(1)" )
			)
			( pin "T1D4.5"
				( objectStatus "@baseboard_fab2_lib.baseboard_fab2(sch_1):page270_i6:gnd(2)" )
			)
			( pin "T1D4.6"
				( objectStatus "@baseboard_fab2_lib.baseboard_fab2(sch_1):page270_i6:gnd(3)" )
			)
			( pin "T1D4.7"
				( objectStatus "@baseboard_fab2_lib.baseboard_fab2(sch_1):page270_i6:gnd(4)" )
			)
			( pin "T1D4.8"
				( objectStatus "@baseboard_fab2_lib.baseboard_fab2(sch_1):page270_i6:gnd(5)" )
			)
			( pin "T1D4.9"
				( objectStatus "@baseboard_fab2_lib.baseboard_fab2(sch_1):page270_i6:gnd(6)" )
			)
			( pin "T1D4.10"
				( objectStatus "@baseboard_fab2_lib.baseboard_fab2(sch_1):page270_i6:gnd(7)" )
			)
			( pin "T1D4.11"
				( objectStatus "@baseboard_fab2_lib.baseboard_fab2(sch_1):page270_i6:gnd(8)" )
			)
			( pin "T1D4.12"
				( objectStatus "@baseboard_fab2_lib.baseboard_fab2(sch_1):page270_i6:gnd(9)" )
			)
			( pin "T1D6.2"
				( objectStatus "@baseboard_fab2_lib.baseboard_fab2(sch_1):page270_i9:dn" )
			)
			( pin "T1D6.1"
				( objectStatus "@baseboard_fab2_lib.baseboard_fab2(sch_1):page270_i9:dp" )
			)
			( pin "T1D6.3"
				( objectStatus "@baseboard_fab2_lib.baseboard_fab2(sch_1):page270_i9:gnd(0)" )
			)
			( pin "T1D6.4"
				( objectStatus "@baseboard_fab2_lib.baseboard_fab2(sch_1):page270_i9:gnd(1)" )
			)
			( pin "T1D6.5"
				( objectStatus "@baseboard_fab2_lib.baseboard_fab2(sch_1):page270_i9:gnd(2)" )
			)
			( pin "T1D6.6"
				( objectStatus "@baseboard_fab2_lib.baseboard_fab2(sch_1):page270_i9:gnd(3)" )
			)
			( pin "T1D6.7"
				( objectStatus "@baseboard_fab2_lib.baseboard_fab2(sch_1):page270_i9:gnd(4)" )
			)
			( pin "T1D6.8"
				( objectStatus "@baseboard_fab2_lib.baseboard_fab2(sch_1):page270_i9:gnd(5)" )
			)
			( pin "T1D6.9"
				( objectStatus "@baseboard_fab2_lib.baseboard_fab2(sch_1):page270_i9:gnd(6)" )
			)
			( pin "T1D6.10"
				( objectStatus "@baseboard_fab2_lib.baseboard_fab2(sch_1):page270_i9:gnd(7)" )
			)
			( pin "T1D6.11"
				( objectStatus "@baseboard_fab2_lib.baseboard_fab2(sch_1):page270_i9:gnd(8)" )
			)
			( pin "T1D6.12"
				( objectStatus "@baseboard_fab2_lib.baseboard_fab2(sch_1):page270_i9:gnd(9)" )
			)
			( pin "T1D5.2"
				( objectStatus "@baseboard_fab2_lib.baseboard_fab2(sch_1):page270_i12:dn" )
			)
			( pin "T1D5.1"
				( objectStatus "@baseboard_fab2_lib.baseboard_fab2(sch_1):page270_i12:dp" )
			)
			( pin "T1D5.3"
				( objectStatus "@baseboard_fab2_lib.baseboard_fab2(sch_1):page270_i12:gnd(0)" )
			)
			( pin "T1D5.4"
				( objectStatus "@baseboard_fab2_lib.baseboard_fab2(sch_1):page270_i12:gnd(1)" )
			)
			( pin "T1D5.5"
				( objectStatus "@baseboard_fab2_lib.baseboard_fab2(sch_1):page270_i12:gnd(2)" )
			)
			( pin "T1D5.6"
				( objectStatus "@baseboard_fab2_lib.baseboard_fab2(sch_1):page270_i12:gnd(3)" )
			)
			( pin "T1D5.7"
				( objectStatus "@baseboard_fab2_lib.baseboard_fab2(sch_1):page270_i12:gnd(4)" )
			)
			( pin "T1D5.8"
				( objectStatus "@baseboard_fab2_lib.baseboard_fab2(sch_1):page270_i12:gnd(5)" )
			)
			( pin "T1D5.9"
				( objectStatus "@baseboard_fab2_lib.baseboard_fab2(sch_1):page270_i12:gnd(6)" )
			)
			( pin "T1D5.10"
				( objectStatus "@baseboard_fab2_lib.baseboard_fab2(sch_1):page270_i12:gnd(7)" )
			)
			( pin "T1D5.11"
				( objectStatus "@baseboard_fab2_lib.baseboard_fab2(sch_1):page270_i12:gnd(8)" )
			)
			( pin "T1D5.12"
				( objectStatus "@baseboard_fab2_lib.baseboard_fab2(sch_1):page270_i12:gnd(9)" )
			)
			( pin "T1D8.2"
				( objectStatus "@baseboard_fab2_lib.baseboard_fab2(sch_1):page270_i13:dn" )
			)
			( pin "T1D8.1"
				( objectStatus "@baseboard_fab2_lib.baseboard_fab2(sch_1):page270_i13:dp" )
			)
			( pin "T1D8.3"
				( objectStatus "@baseboard_fab2_lib.baseboard_fab2(sch_1):page270_i13:gnd(0)" )
			)
			( pin "T1D8.4"
				( objectStatus "@baseboard_fab2_lib.baseboard_fab2(sch_1):page270_i13:gnd(1)" )
			)
			( pin "T1D8.5"
				( objectStatus "@baseboard_fab2_lib.baseboard_fab2(sch_1):page270_i13:gnd(2)" )
			)
			( pin "T1D8.6"
				( objectStatus "@baseboard_fab2_lib.baseboard_fab2(sch_1):page270_i13:gnd(3)" )
			)
			( pin "T1D8.7"
				( objectStatus "@baseboard_fab2_lib.baseboard_fab2(sch_1):page270_i13:gnd(4)" )
			)
			( pin "T1D8.8"
				( objectStatus "@baseboard_fab2_lib.baseboard_fab2(sch_1):page270_i13:gnd(5)" )
			)
			( pin "T1D8.9"
				( objectStatus "@baseboard_fab2_lib.baseboard_fab2(sch_1):page270_i13:gnd(6)" )
			)
			( pin "T1D8.10"
				( objectStatus "@baseboard_fab2_lib.baseboard_fab2(sch_1):page270_i13:gnd(7)" )
			)
			( pin "T1D8.11"
				( objectStatus "@baseboard_fab2_lib.baseboard_fab2(sch_1):page270_i13:gnd(8)" )
			)
			( pin "T1D8.12"
				( objectStatus "@baseboard_fab2_lib.baseboard_fab2(sch_1):page270_i13:gnd(9)" )
			)
			( pin "T1D7.2"
				( objectStatus "@baseboard_fab2_lib.baseboard_fab2(sch_1):page270_i16:dn" )
			)
			( pin "T1D7.1"
				( objectStatus "@baseboard_fab2_lib.baseboard_fab2(sch_1):page270_i16:dp" )
			)
			( pin "T1D7.3"
				( objectStatus "@baseboard_fab2_lib.baseboard_fab2(sch_1):page270_i16:gnd(0)" )
			)
			( pin "T1D7.4"
				( objectStatus "@baseboard_fab2_lib.baseboard_fab2(sch_1):page270_i16:gnd(1)" )
			)
			( pin "T1D7.5"
				( objectStatus "@baseboard_fab2_lib.baseboard_fab2(sch_1):page270_i16:gnd(2)" )
			)
			( pin "T1D7.6"
				( objectStatus "@baseboard_fab2_lib.baseboard_fab2(sch_1):page270_i16:gnd(3)" )
			)
			( pin "T1D7.7"
				( objectStatus "@baseboard_fab2_lib.baseboard_fab2(sch_1):page270_i16:gnd(4)" )
			)
			( pin "T1D7.8"
				( objectStatus "@baseboard_fab2_lib.baseboard_fab2(sch_1):page270_i16:gnd(5)" )
			)
			( pin "T1D7.9"
				( objectStatus "@baseboard_fab2_lib.baseboard_fab2(sch_1):page270_i16:gnd(6)" )
			)
			( pin "T1D7.10"
				( objectStatus "@baseboard_fab2_lib.baseboard_fab2(sch_1):page270_i16:gnd(7)" )
			)
			( pin "T1D7.11"
				( objectStatus "@baseboard_fab2_lib.baseboard_fab2(sch_1):page270_i16:gnd(8)" )
			)
			( pin "T1D7.12"
				( objectStatus "@baseboard_fab2_lib.baseboard_fab2(sch_1):page270_i16:gnd(9)" )
			)
			( pin "T1D9.2"
				( objectStatus "@baseboard_fab2_lib.baseboard_fab2(sch_1):page270_i18:dn" )
			)
			( pin "T1D9.1"
				( objectStatus "@baseboard_fab2_lib.baseboard_fab2(sch_1):page270_i18:dp" )
			)
			( pin "T1D9.3"
				( objectStatus "@baseboard_fab2_lib.baseboard_fab2(sch_1):page270_i18:gnd(0)" )
			)
			( pin "T1D9.4"
				( objectStatus "@baseboard_fab2_lib.baseboard_fab2(sch_1):page270_i18:gnd(1)" )
			)
			( pin "T1D9.5"
				( objectStatus "@baseboard_fab2_lib.baseboard_fab2(sch_1):page270_i18:gnd(2)" )
			)
			( pin "T1D9.6"
				( objectStatus "@baseboard_fab2_lib.baseboard_fab2(sch_1):page270_i18:gnd(3)" )
			)
			( pin "T1D9.7"
				( objectStatus "@baseboard_fab2_lib.baseboard_fab2(sch_1):page270_i18:gnd(4)" )
			)
			( pin "T1D9.8"
				( objectStatus "@baseboard_fab2_lib.baseboard_fab2(sch_1):page270_i18:gnd(5)" )
			)
			( pin "T1D9.9"
				( objectStatus "@baseboard_fab2_lib.baseboard_fab2(sch_1):page270_i18:gnd(6)" )
			)
			( pin "T1D9.10"
				( objectStatus "@baseboard_fab2_lib.baseboard_fab2(sch_1):page270_i18:gnd(7)" )
			)
			( pin "T1D9.11"
				( objectStatus "@baseboard_fab2_lib.baseboard_fab2(sch_1):page270_i18:gnd(8)" )
			)
			( pin "T1D9.12"
				( objectStatus "@baseboard_fab2_lib.baseboard_fab2(sch_1):page270_i18:gnd(9)" )
			)
			( pin "T1D12.2"
				( objectStatus "@baseboard_fab2_lib.baseboard_fab2(sch_1):page270_i21:dn" )
			)
			( pin "T1D12.1"
				( objectStatus "@baseboard_fab2_lib.baseboard_fab2(sch_1):page270_i21:dp" )
			)
			( pin "T1D12.3"
				( objectStatus "@baseboard_fab2_lib.baseboard_fab2(sch_1):page270_i21:gnd(0)" )
			)
			( pin "T1D12.4"
				( objectStatus "@baseboard_fab2_lib.baseboard_fab2(sch_1):page270_i21:gnd(1)" )
			)
			( pin "T1D12.5"
				( objectStatus "@baseboard_fab2_lib.baseboard_fab2(sch_1):page270_i21:gnd(2)" )
			)
			( pin "T1D12.6"
				( objectStatus "@baseboard_fab2_lib.baseboard_fab2(sch_1):page270_i21:gnd(3)" )
			)
			( pin "T1D12.7"
				( objectStatus "@baseboard_fab2_lib.baseboard_fab2(sch_1):page270_i21:gnd(4)" )
			)
			( pin "T1D12.8"
				( objectStatus "@baseboard_fab2_lib.baseboard_fab2(sch_1):page270_i21:gnd(5)" )
			)
			( pin "T1D12.9"
				( objectStatus "@baseboard_fab2_lib.baseboard_fab2(sch_1):page270_i21:gnd(6)" )
			)
			( pin "T1D12.10"
				( objectStatus "@baseboard_fab2_lib.baseboard_fab2(sch_1):page270_i21:gnd(7)" )
			)
			( pin "T1D12.11"
				( objectStatus "@baseboard_fab2_lib.baseboard_fab2(sch_1):page270_i21:gnd(8)" )
			)
			( pin "T1D12.12"
				( objectStatus "@baseboard_fab2_lib.baseboard_fab2(sch_1):page270_i21:gnd(9)" )
			)
			( pin "T1D11.2"
				( objectStatus "@baseboard_fab2_lib.baseboard_fab2(sch_1):page270_i24:dn" )
			)
			( pin "T1D11.1"
				( objectStatus "@baseboard_fab2_lib.baseboard_fab2(sch_1):page270_i24:dp" )
			)
			( pin "T1D11.3"
				( objectStatus "@baseboard_fab2_lib.baseboard_fab2(sch_1):page270_i24:gnd(0)" )
			)
			( pin "T1D11.4"
				( objectStatus "@baseboard_fab2_lib.baseboard_fab2(sch_1):page270_i24:gnd(1)" )
			)
			( pin "T1D11.5"
				( objectStatus "@baseboard_fab2_lib.baseboard_fab2(sch_1):page270_i24:gnd(2)" )
			)
			( pin "T1D11.6"
				( objectStatus "@baseboard_fab2_lib.baseboard_fab2(sch_1):page270_i24:gnd(3)" )
			)
			( pin "T1D11.7"
				( objectStatus "@baseboard_fab2_lib.baseboard_fab2(sch_1):page270_i24:gnd(4)" )
			)
			( pin "T1D11.8"
				( objectStatus "@baseboard_fab2_lib.baseboard_fab2(sch_1):page270_i24:gnd(5)" )
			)
			( pin "T1D11.9"
				( objectStatus "@baseboard_fab2_lib.baseboard_fab2(sch_1):page270_i24:gnd(6)" )
			)
			( pin "T1D11.10"
				( objectStatus "@baseboard_fab2_lib.baseboard_fab2(sch_1):page270_i24:gnd(7)" )
			)
			( pin "T1D11.11"
				( objectStatus "@baseboard_fab2_lib.baseboard_fab2(sch_1):page270_i24:gnd(8)" )
			)
			( pin "T1D11.12"
				( objectStatus "@baseboard_fab2_lib.baseboard_fab2(sch_1):page270_i24:gnd(9)" )
			)
			( pin "T1D17.2"
				( objectStatus "@baseboard_fab2_lib.baseboard_fab2(sch_1):page272_i1:dn" )
			)
			( pin "T1D17.1"
				( objectStatus "@baseboard_fab2_lib.baseboard_fab2(sch_1):page272_i1:dp" )
			)
			( pin "T1D17.3"
				( objectStatus "@baseboard_fab2_lib.baseboard_fab2(sch_1):page272_i1:gnd(0)" )
			)
			( pin "T1D17.4"
				( objectStatus "@baseboard_fab2_lib.baseboard_fab2(sch_1):page272_i1:gnd(1)" )
			)
			( pin "T1D17.5"
				( objectStatus "@baseboard_fab2_lib.baseboard_fab2(sch_1):page272_i1:gnd(2)" )
			)
			( pin "T1D17.6"
				( objectStatus "@baseboard_fab2_lib.baseboard_fab2(sch_1):page272_i1:gnd(3)" )
			)
			( pin "T1D17.7"
				( objectStatus "@baseboard_fab2_lib.baseboard_fab2(sch_1):page272_i1:gnd(4)" )
			)
			( pin "T1D17.8"
				( objectStatus "@baseboard_fab2_lib.baseboard_fab2(sch_1):page272_i1:gnd(5)" )
			)
			( pin "T1D17.9"
				( objectStatus "@baseboard_fab2_lib.baseboard_fab2(sch_1):page272_i1:gnd(6)" )
			)
			( pin "T1D17.10"
				( objectStatus "@baseboard_fab2_lib.baseboard_fab2(sch_1):page272_i1:gnd(7)" )
			)
			( pin "T1D17.11"
				( objectStatus "@baseboard_fab2_lib.baseboard_fab2(sch_1):page272_i1:gnd(8)" )
			)
			( pin "T1D17.12"
				( objectStatus "@baseboard_fab2_lib.baseboard_fab2(sch_1):page272_i1:gnd(9)" )
			)
			( pin "T1D15.2"
				( objectStatus "@baseboard_fab2_lib.baseboard_fab2(sch_1):page272_i3:dn" )
			)
			( pin "T1D15.1"
				( objectStatus "@baseboard_fab2_lib.baseboard_fab2(sch_1):page272_i3:dp" )
			)
			( pin "T1D15.3"
				( objectStatus "@baseboard_fab2_lib.baseboard_fab2(sch_1):page272_i3:gnd(0)" )
			)
			( pin "T1D15.4"
				( objectStatus "@baseboard_fab2_lib.baseboard_fab2(sch_1):page272_i3:gnd(1)" )
			)
			( pin "T1D15.5"
				( objectStatus "@baseboard_fab2_lib.baseboard_fab2(sch_1):page272_i3:gnd(2)" )
			)
			( pin "T1D15.6"
				( objectStatus "@baseboard_fab2_lib.baseboard_fab2(sch_1):page272_i3:gnd(3)" )
			)
			( pin "T1D15.7"
				( objectStatus "@baseboard_fab2_lib.baseboard_fab2(sch_1):page272_i3:gnd(4)" )
			)
			( pin "T1D15.8"
				( objectStatus "@baseboard_fab2_lib.baseboard_fab2(sch_1):page272_i3:gnd(5)" )
			)
			( pin "T1D15.9"
				( objectStatus "@baseboard_fab2_lib.baseboard_fab2(sch_1):page272_i3:gnd(6)" )
			)
			( pin "T1D15.10"
				( objectStatus "@baseboard_fab2_lib.baseboard_fab2(sch_1):page272_i3:gnd(7)" )
			)
			( pin "T1D15.11"
				( objectStatus "@baseboard_fab2_lib.baseboard_fab2(sch_1):page272_i3:gnd(8)" )
			)
			( pin "T1D15.12"
				( objectStatus "@baseboard_fab2_lib.baseboard_fab2(sch_1):page272_i3:gnd(9)" )
			)
			( pin "T1D13.2"
				( objectStatus "@baseboard_fab2_lib.baseboard_fab2(sch_1):page272_i5:dn" )
			)
			( pin "T1D13.1"
				( objectStatus "@baseboard_fab2_lib.baseboard_fab2(sch_1):page272_i5:dp" )
			)
			( pin "T1D13.3"
				( objectStatus "@baseboard_fab2_lib.baseboard_fab2(sch_1):page272_i5:gnd(0)" )
			)
			( pin "T1D13.4"
				( objectStatus "@baseboard_fab2_lib.baseboard_fab2(sch_1):page272_i5:gnd(1)" )
			)
			( pin "T1D13.5"
				( objectStatus "@baseboard_fab2_lib.baseboard_fab2(sch_1):page272_i5:gnd(2)" )
			)
			( pin "T1D13.6"
				( objectStatus "@baseboard_fab2_lib.baseboard_fab2(sch_1):page272_i5:gnd(3)" )
			)
			( pin "T1D13.7"
				( objectStatus "@baseboard_fab2_lib.baseboard_fab2(sch_1):page272_i5:gnd(4)" )
			)
			( pin "T1D13.8"
				( objectStatus "@baseboard_fab2_lib.baseboard_fab2(sch_1):page272_i5:gnd(5)" )
			)
			( pin "T1D13.9"
				( objectStatus "@baseboard_fab2_lib.baseboard_fab2(sch_1):page272_i5:gnd(6)" )
			)
			( pin "T1D13.10"
				( objectStatus "@baseboard_fab2_lib.baseboard_fab2(sch_1):page272_i5:gnd(7)" )
			)
			( pin "T1D13.11"
				( objectStatus "@baseboard_fab2_lib.baseboard_fab2(sch_1):page272_i5:gnd(8)" )
			)
			( pin "T1D13.12"
				( objectStatus "@baseboard_fab2_lib.baseboard_fab2(sch_1):page272_i5:gnd(9)" )
			)
			( pin "T1D18.2"
				( objectStatus "@baseboard_fab2_lib.baseboard_fab2(sch_1):page272_i8:dn" )
			)
			( pin "T1D18.1"
				( objectStatus "@baseboard_fab2_lib.baseboard_fab2(sch_1):page272_i8:dp" )
			)
			( pin "T1D18.3"
				( objectStatus "@baseboard_fab2_lib.baseboard_fab2(sch_1):page272_i8:gnd(0)" )
			)
			( pin "T1D18.4"
				( objectStatus "@baseboard_fab2_lib.baseboard_fab2(sch_1):page272_i8:gnd(1)" )
			)
			( pin "T1D18.5"
				( objectStatus "@baseboard_fab2_lib.baseboard_fab2(sch_1):page272_i8:gnd(2)" )
			)
			( pin "T1D18.6"
				( objectStatus "@baseboard_fab2_lib.baseboard_fab2(sch_1):page272_i8:gnd(3)" )
			)
			( pin "T1D18.7"
				( objectStatus "@baseboard_fab2_lib.baseboard_fab2(sch_1):page272_i8:gnd(4)" )
			)
			( pin "T1D18.8"
				( objectStatus "@baseboard_fab2_lib.baseboard_fab2(sch_1):page272_i8:gnd(5)" )
			)
			( pin "T1D18.9"
				( objectStatus "@baseboard_fab2_lib.baseboard_fab2(sch_1):page272_i8:gnd(6)" )
			)
			( pin "T1D18.10"
				( objectStatus "@baseboard_fab2_lib.baseboard_fab2(sch_1):page272_i8:gnd(7)" )
			)
			( pin "T1D18.11"
				( objectStatus "@baseboard_fab2_lib.baseboard_fab2(sch_1):page272_i8:gnd(8)" )
			)
			( pin "T1D18.12"
				( objectStatus "@baseboard_fab2_lib.baseboard_fab2(sch_1):page272_i8:gnd(9)" )
			)
			( pin "T1D23.2"
				( objectStatus "@baseboard_fab2_lib.baseboard_fab2(sch_1):page272_i9:dn" )
			)
			( pin "T1D23.1"
				( objectStatus "@baseboard_fab2_lib.baseboard_fab2(sch_1):page272_i9:dp" )
			)
			( pin "T1D23.3"
				( objectStatus "@baseboard_fab2_lib.baseboard_fab2(sch_1):page272_i9:gnd(0)" )
			)
			( pin "T1D23.4"
				( objectStatus "@baseboard_fab2_lib.baseboard_fab2(sch_1):page272_i9:gnd(1)" )
			)
			( pin "T1D23.5"
				( objectStatus "@baseboard_fab2_lib.baseboard_fab2(sch_1):page272_i9:gnd(2)" )
			)
			( pin "T1D23.6"
				( objectStatus "@baseboard_fab2_lib.baseboard_fab2(sch_1):page272_i9:gnd(3)" )
			)
			( pin "T1D23.7"
				( objectStatus "@baseboard_fab2_lib.baseboard_fab2(sch_1):page272_i9:gnd(4)" )
			)
			( pin "T1D23.8"
				( objectStatus "@baseboard_fab2_lib.baseboard_fab2(sch_1):page272_i9:gnd(5)" )
			)
			( pin "T1D23.9"
				( objectStatus "@baseboard_fab2_lib.baseboard_fab2(sch_1):page272_i9:gnd(6)" )
			)
			( pin "T1D23.10"
				( objectStatus "@baseboard_fab2_lib.baseboard_fab2(sch_1):page272_i9:gnd(7)" )
			)
			( pin "T1D23.11"
				( objectStatus "@baseboard_fab2_lib.baseboard_fab2(sch_1):page272_i9:gnd(8)" )
			)
			( pin "T1D23.12"
				( objectStatus "@baseboard_fab2_lib.baseboard_fab2(sch_1):page272_i9:gnd(9)" )
			)
			( pin "T1D24.2"
				( objectStatus "@baseboard_fab2_lib.baseboard_fab2(sch_1):page272_i12:dn" )
			)
			( pin "T1D24.1"
				( objectStatus "@baseboard_fab2_lib.baseboard_fab2(sch_1):page272_i12:dp" )
			)
			( pin "T1D24.3"
				( objectStatus "@baseboard_fab2_lib.baseboard_fab2(sch_1):page272_i12:gnd(0)" )
			)
			( pin "T1D24.4"
				( objectStatus "@baseboard_fab2_lib.baseboard_fab2(sch_1):page272_i12:gnd(1)" )
			)
			( pin "T1D24.5"
				( objectStatus "@baseboard_fab2_lib.baseboard_fab2(sch_1):page272_i12:gnd(2)" )
			)
			( pin "T1D24.6"
				( objectStatus "@baseboard_fab2_lib.baseboard_fab2(sch_1):page272_i12:gnd(3)" )
			)
			( pin "T1D24.7"
				( objectStatus "@baseboard_fab2_lib.baseboard_fab2(sch_1):page272_i12:gnd(4)" )
			)
			( pin "T1D24.8"
				( objectStatus "@baseboard_fab2_lib.baseboard_fab2(sch_1):page272_i12:gnd(5)" )
			)
			( pin "T1D24.9"
				( objectStatus "@baseboard_fab2_lib.baseboard_fab2(sch_1):page272_i12:gnd(6)" )
			)
			( pin "T1D24.10"
				( objectStatus "@baseboard_fab2_lib.baseboard_fab2(sch_1):page272_i12:gnd(7)" )
			)
			( pin "T1D24.11"
				( objectStatus "@baseboard_fab2_lib.baseboard_fab2(sch_1):page272_i12:gnd(8)" )
			)
			( pin "T1D24.12"
				( objectStatus "@baseboard_fab2_lib.baseboard_fab2(sch_1):page272_i12:gnd(9)" )
			)
			( pin "T1D16.2"
				( objectStatus "@baseboard_fab2_lib.baseboard_fab2(sch_1):page272_i14:dn" )
			)
			( pin "T1D16.1"
				( objectStatus "@baseboard_fab2_lib.baseboard_fab2(sch_1):page272_i14:dp" )
			)
			( pin "T1D16.3"
				( objectStatus "@baseboard_fab2_lib.baseboard_fab2(sch_1):page272_i14:gnd(0)" )
			)
			( pin "T1D16.4"
				( objectStatus "@baseboard_fab2_lib.baseboard_fab2(sch_1):page272_i14:gnd(1)" )
			)
			( pin "T1D16.5"
				( objectStatus "@baseboard_fab2_lib.baseboard_fab2(sch_1):page272_i14:gnd(2)" )
			)
			( pin "T1D16.6"
				( objectStatus "@baseboard_fab2_lib.baseboard_fab2(sch_1):page272_i14:gnd(3)" )
			)
			( pin "T1D16.7"
				( objectStatus "@baseboard_fab2_lib.baseboard_fab2(sch_1):page272_i14:gnd(4)" )
			)
			( pin "T1D16.8"
				( objectStatus "@baseboard_fab2_lib.baseboard_fab2(sch_1):page272_i14:gnd(5)" )
			)
			( pin "T1D16.9"
				( objectStatus "@baseboard_fab2_lib.baseboard_fab2(sch_1):page272_i14:gnd(6)" )
			)
			( pin "T1D16.10"
				( objectStatus "@baseboard_fab2_lib.baseboard_fab2(sch_1):page272_i14:gnd(7)" )
			)
			( pin "T1D16.11"
				( objectStatus "@baseboard_fab2_lib.baseboard_fab2(sch_1):page272_i14:gnd(8)" )
			)
			( pin "T1D16.12"
				( objectStatus "@baseboard_fab2_lib.baseboard_fab2(sch_1):page272_i14:gnd(9)" )
			)
			( pin "T1D21.2"
				( objectStatus "@baseboard_fab2_lib.baseboard_fab2(sch_1):page272_i16:dn" )
			)
			( pin "T1D21.1"
				( objectStatus "@baseboard_fab2_lib.baseboard_fab2(sch_1):page272_i16:dp" )
			)
			( pin "T1D21.3"
				( objectStatus "@baseboard_fab2_lib.baseboard_fab2(sch_1):page272_i16:gnd(0)" )
			)
			( pin "T1D21.4"
				( objectStatus "@baseboard_fab2_lib.baseboard_fab2(sch_1):page272_i16:gnd(1)" )
			)
			( pin "T1D21.5"
				( objectStatus "@baseboard_fab2_lib.baseboard_fab2(sch_1):page272_i16:gnd(2)" )
			)
			( pin "T1D21.6"
				( objectStatus "@baseboard_fab2_lib.baseboard_fab2(sch_1):page272_i16:gnd(3)" )
			)
			( pin "T1D21.7"
				( objectStatus "@baseboard_fab2_lib.baseboard_fab2(sch_1):page272_i16:gnd(4)" )
			)
			( pin "T1D21.8"
				( objectStatus "@baseboard_fab2_lib.baseboard_fab2(sch_1):page272_i16:gnd(5)" )
			)
			( pin "T1D21.9"
				( objectStatus "@baseboard_fab2_lib.baseboard_fab2(sch_1):page272_i16:gnd(6)" )
			)
			( pin "T1D21.10"
				( objectStatus "@baseboard_fab2_lib.baseboard_fab2(sch_1):page272_i16:gnd(7)" )
			)
			( pin "T1D21.11"
				( objectStatus "@baseboard_fab2_lib.baseboard_fab2(sch_1):page272_i16:gnd(8)" )
			)
			( pin "T1D21.12"
				( objectStatus "@baseboard_fab2_lib.baseboard_fab2(sch_1):page272_i16:gnd(9)" )
			)
			( pin "T1D22.2"
				( objectStatus "@baseboard_fab2_lib.baseboard_fab2(sch_1):page272_i21:dn" )
			)
			( pin "T1D22.1"
				( objectStatus "@baseboard_fab2_lib.baseboard_fab2(sch_1):page272_i21:dp" )
			)
			( pin "T1D22.3"
				( objectStatus "@baseboard_fab2_lib.baseboard_fab2(sch_1):page272_i21:gnd(0)" )
			)
			( pin "T1D22.4"
				( objectStatus "@baseboard_fab2_lib.baseboard_fab2(sch_1):page272_i21:gnd(1)" )
			)
			( pin "T1D22.5"
				( objectStatus "@baseboard_fab2_lib.baseboard_fab2(sch_1):page272_i21:gnd(2)" )
			)
			( pin "T1D22.6"
				( objectStatus "@baseboard_fab2_lib.baseboard_fab2(sch_1):page272_i21:gnd(3)" )
			)
			( pin "T1D22.7"
				( objectStatus "@baseboard_fab2_lib.baseboard_fab2(sch_1):page272_i21:gnd(4)" )
			)
			( pin "T1D22.8"
				( objectStatus "@baseboard_fab2_lib.baseboard_fab2(sch_1):page272_i21:gnd(5)" )
			)
			( pin "T1D22.9"
				( objectStatus "@baseboard_fab2_lib.baseboard_fab2(sch_1):page272_i21:gnd(6)" )
			)
			( pin "T1D22.10"
				( objectStatus "@baseboard_fab2_lib.baseboard_fab2(sch_1):page272_i21:gnd(7)" )
			)
			( pin "T1D22.11"
				( objectStatus "@baseboard_fab2_lib.baseboard_fab2(sch_1):page272_i21:gnd(8)" )
			)
			( pin "T1D22.12"
				( objectStatus "@baseboard_fab2_lib.baseboard_fab2(sch_1):page272_i21:gnd(9)" )
			)
			( pin "T1D14.2"
				( objectStatus "@baseboard_fab2_lib.baseboard_fab2(sch_1):page272_i22:dn" )
			)
			( pin "T1D14.1"
				( objectStatus "@baseboard_fab2_lib.baseboard_fab2(sch_1):page272_i22:dp" )
			)
			( pin "T1D14.3"
				( objectStatus "@baseboard_fab2_lib.baseboard_fab2(sch_1):page272_i22:gnd(0)" )
			)
			( pin "T1D14.4"
				( objectStatus "@baseboard_fab2_lib.baseboard_fab2(sch_1):page272_i22:gnd(1)" )
			)
			( pin "T1D14.5"
				( objectStatus "@baseboard_fab2_lib.baseboard_fab2(sch_1):page272_i22:gnd(2)" )
			)
			( pin "T1D14.6"
				( objectStatus "@baseboard_fab2_lib.baseboard_fab2(sch_1):page272_i22:gnd(3)" )
			)
			( pin "T1D14.7"
				( objectStatus "@baseboard_fab2_lib.baseboard_fab2(sch_1):page272_i22:gnd(4)" )
			)
			( pin "T1D14.8"
				( objectStatus "@baseboard_fab2_lib.baseboard_fab2(sch_1):page272_i22:gnd(5)" )
			)
			( pin "T1D14.9"
				( objectStatus "@baseboard_fab2_lib.baseboard_fab2(sch_1):page272_i22:gnd(6)" )
			)
			( pin "T1D14.10"
				( objectStatus "@baseboard_fab2_lib.baseboard_fab2(sch_1):page272_i22:gnd(7)" )
			)
			( pin "T1D14.11"
				( objectStatus "@baseboard_fab2_lib.baseboard_fab2(sch_1):page272_i22:gnd(8)" )
			)
			( pin "T1D14.12"
				( objectStatus "@baseboard_fab2_lib.baseboard_fab2(sch_1):page272_i22:gnd(9)" )
			)
			( pin "T1D19.2"
				( objectStatus "@baseboard_fab2_lib.baseboard_fab2(sch_1):page272_i23:dn" )
			)
			( pin "T1D19.1"
				( objectStatus "@baseboard_fab2_lib.baseboard_fab2(sch_1):page272_i23:dp" )
			)
			( pin "T1D19.3"
				( objectStatus "@baseboard_fab2_lib.baseboard_fab2(sch_1):page272_i23:gnd(0)" )
			)
			( pin "T1D19.4"
				( objectStatus "@baseboard_fab2_lib.baseboard_fab2(sch_1):page272_i23:gnd(1)" )
			)
			( pin "T1D19.5"
				( objectStatus "@baseboard_fab2_lib.baseboard_fab2(sch_1):page272_i23:gnd(2)" )
			)
			( pin "T1D19.6"
				( objectStatus "@baseboard_fab2_lib.baseboard_fab2(sch_1):page272_i23:gnd(3)" )
			)
			( pin "T1D19.7"
				( objectStatus "@baseboard_fab2_lib.baseboard_fab2(sch_1):page272_i23:gnd(4)" )
			)
			( pin "T1D19.8"
				( objectStatus "@baseboard_fab2_lib.baseboard_fab2(sch_1):page272_i23:gnd(5)" )
			)
			( pin "T1D19.9"
				( objectStatus "@baseboard_fab2_lib.baseboard_fab2(sch_1):page272_i23:gnd(6)" )
			)
			( pin "T1D19.10"
				( objectStatus "@baseboard_fab2_lib.baseboard_fab2(sch_1):page272_i23:gnd(7)" )
			)
			( pin "T1D19.11"
				( objectStatus "@baseboard_fab2_lib.baseboard_fab2(sch_1):page272_i23:gnd(8)" )
			)
			( pin "T1D19.12"
				( objectStatus "@baseboard_fab2_lib.baseboard_fab2(sch_1):page272_i23:gnd(9)" )
			)
			( pin "T1D20.2"
				( objectStatus "@baseboard_fab2_lib.baseboard_fab2(sch_1):page272_i24:dn" )
			)
			( pin "T1D20.1"
				( objectStatus "@baseboard_fab2_lib.baseboard_fab2(sch_1):page272_i24:dp" )
			)
			( pin "T1D20.3"
				( objectStatus "@baseboard_fab2_lib.baseboard_fab2(sch_1):page272_i24:gnd(0)" )
			)
			( pin "T1D20.4"
				( objectStatus "@baseboard_fab2_lib.baseboard_fab2(sch_1):page272_i24:gnd(1)" )
			)
			( pin "T1D20.5"
				( objectStatus "@baseboard_fab2_lib.baseboard_fab2(sch_1):page272_i24:gnd(2)" )
			)
			( pin "T1D20.6"
				( objectStatus "@baseboard_fab2_lib.baseboard_fab2(sch_1):page272_i24:gnd(3)" )
			)
			( pin "T1D20.7"
				( objectStatus "@baseboard_fab2_lib.baseboard_fab2(sch_1):page272_i24:gnd(4)" )
			)
			( pin "T1D20.8"
				( objectStatus "@baseboard_fab2_lib.baseboard_fab2(sch_1):page272_i24:gnd(5)" )
			)
			( pin "T1D20.9"
				( objectStatus "@baseboard_fab2_lib.baseboard_fab2(sch_1):page272_i24:gnd(6)" )
			)
			( pin "T1D20.10"
				( objectStatus "@baseboard_fab2_lib.baseboard_fab2(sch_1):page272_i24:gnd(7)" )
			)
			( pin "T1D20.11"
				( objectStatus "@baseboard_fab2_lib.baseboard_fab2(sch_1):page272_i24:gnd(8)" )
			)
			( pin "T1D20.12"
				( objectStatus "@baseboard_fab2_lib.baseboard_fab2(sch_1):page272_i24:gnd(9)" )
			)
			( pin "T1P2.1"
				( objectStatus "@baseboard_fab2_lib.baseboard_fab2(sch_1):page271_i5:\1\" )
			)
			( pin "T1P2.2"
				( objectStatus "@baseboard_fab2_lib.baseboard_fab2(sch_1):page271_i5:\2\" )
			)
			( pin "T1P2.GND1"
				( objectStatus "@baseboard_fab2_lib.baseboard_fab2(sch_1):page271_i5:gnd1" )
			)
			( pin "T1P2.GND2"
				( objectStatus "@baseboard_fab2_lib.baseboard_fab2(sch_1):page271_i5:gnd2" )
			)
			( pin "T1P4.1"
				( objectStatus "@baseboard_fab2_lib.baseboard_fab2(sch_1):page271_i7:\1\" )
			)
			( pin "T1P4.2"
				( objectStatus "@baseboard_fab2_lib.baseboard_fab2(sch_1):page271_i7:\2\" )
			)
			( pin "T1P4.GND1"
				( objectStatus "@baseboard_fab2_lib.baseboard_fab2(sch_1):page271_i7:gnd1" )
			)
			( pin "T1P4.GND2"
				( objectStatus "@baseboard_fab2_lib.baseboard_fab2(sch_1):page271_i7:gnd2" )
			)
			( pin "T1P3.1"
				( objectStatus "@baseboard_fab2_lib.baseboard_fab2(sch_1):page271_i8:\1\" )
			)
			( pin "T1P3.2"
				( objectStatus "@baseboard_fab2_lib.baseboard_fab2(sch_1):page271_i8:\2\" )
			)
			( pin "T1P3.GND1"
				( objectStatus "@baseboard_fab2_lib.baseboard_fab2(sch_1):page271_i8:gnd1" )
			)
			( pin "T1P3.GND2"
				( objectStatus "@baseboard_fab2_lib.baseboard_fab2(sch_1):page271_i8:gnd2" )
			)
			( pin "T1P5.1"
				( objectStatus "@baseboard_fab2_lib.baseboard_fab2(sch_1):page271_i11:\1\" )
			)
			( pin "T1P5.2"
				( objectStatus "@baseboard_fab2_lib.baseboard_fab2(sch_1):page271_i11:\2\" )
			)
			( pin "T1P5.GND1"
				( objectStatus "@baseboard_fab2_lib.baseboard_fab2(sch_1):page271_i11:gnd1" )
			)
			( pin "T1P5.GND2"
				( objectStatus "@baseboard_fab2_lib.baseboard_fab2(sch_1):page271_i11:gnd2" )
			)
			( pin "T1P6.1"
				( objectStatus "@baseboard_fab2_lib.baseboard_fab2(sch_1):page271_i13:\1\" )
			)
			( pin "T1P6.2"
				( objectStatus "@baseboard_fab2_lib.baseboard_fab2(sch_1):page271_i13:\2\" )
			)
			( pin "T1P6.GND1"
				( objectStatus "@baseboard_fab2_lib.baseboard_fab2(sch_1):page271_i13:gnd1" )
			)
			( pin "T1P6.GND2"
				( objectStatus "@baseboard_fab2_lib.baseboard_fab2(sch_1):page271_i13:gnd2" )
			)
			( pin "T1P10.1"
				( objectStatus "@baseboard_fab2_lib.baseboard_fab2(sch_1):page271_i15:\1\" )
			)
			( pin "T1P10.2"
				( objectStatus "@baseboard_fab2_lib.baseboard_fab2(sch_1):page271_i15:\2\" )
			)
			( pin "T1P10.GND1"
				( objectStatus "@baseboard_fab2_lib.baseboard_fab2(sch_1):page271_i15:gnd1" )
			)
			( pin "T1P10.GND2"
				( objectStatus "@baseboard_fab2_lib.baseboard_fab2(sch_1):page271_i15:gnd2" )
			)
			( pin "T1P8.1"
				( objectStatus "@baseboard_fab2_lib.baseboard_fab2(sch_1):page271_i16:\1\" )
			)
			( pin "T1P8.2"
				( objectStatus "@baseboard_fab2_lib.baseboard_fab2(sch_1):page271_i16:\2\" )
			)
			( pin "T1P8.GND1"
				( objectStatus "@baseboard_fab2_lib.baseboard_fab2(sch_1):page271_i16:gnd1" )
			)
			( pin "T1P8.GND2"
				( objectStatus "@baseboard_fab2_lib.baseboard_fab2(sch_1):page271_i16:gnd2" )
			)
			( pin "T1P7.1"
				( objectStatus "@baseboard_fab2_lib.baseboard_fab2(sch_1):page271_i17:\1\" )
			)
			( pin "T1P7.2"
				( objectStatus "@baseboard_fab2_lib.baseboard_fab2(sch_1):page271_i17:\2\" )
			)
			( pin "T1P7.GND1"
				( objectStatus "@baseboard_fab2_lib.baseboard_fab2(sch_1):page271_i17:gnd1" )
			)
			( pin "T1P7.GND2"
				( objectStatus "@baseboard_fab2_lib.baseboard_fab2(sch_1):page271_i17:gnd2" )
			)
			( pin "T1P9.1"
				( objectStatus "@baseboard_fab2_lib.baseboard_fab2(sch_1):page271_i19:\1\" )
			)
			( pin "T1P9.2"
				( objectStatus "@baseboard_fab2_lib.baseboard_fab2(sch_1):page271_i19:\2\" )
			)
			( pin "T1P9.GND1"
				( objectStatus "@baseboard_fab2_lib.baseboard_fab2(sch_1):page271_i19:gnd1" )
			)
			( pin "T1P9.GND2"
				( objectStatus "@baseboard_fab2_lib.baseboard_fab2(sch_1):page271_i19:gnd2" )
			)
			( pin "T1P11.1"
				( objectStatus "@baseboard_fab2_lib.baseboard_fab2(sch_1):page271_i23:\1\" )
			)
			( pin "T1P11.2"
				( objectStatus "@baseboard_fab2_lib.baseboard_fab2(sch_1):page271_i23:\2\" )
			)
			( pin "T1P11.GND1"
				( objectStatus "@baseboard_fab2_lib.baseboard_fab2(sch_1):page271_i23:gnd1" )
			)
			( pin "T1P11.GND2"
				( objectStatus "@baseboard_fab2_lib.baseboard_fab2(sch_1):page271_i23:gnd2" )
			)
			( pin "T1P12.1"
				( objectStatus "@baseboard_fab2_lib.baseboard_fab2(sch_1):page271_i24:\1\" )
			)
			( pin "T1P12.2"
				( objectStatus "@baseboard_fab2_lib.baseboard_fab2(sch_1):page271_i24:\2\" )
			)
			( pin "T1P12.GND1"
				( objectStatus "@baseboard_fab2_lib.baseboard_fab2(sch_1):page271_i24:gnd1" )
			)
			( pin "T1P12.GND2"
				( objectStatus "@baseboard_fab2_lib.baseboard_fab2(sch_1):page271_i24:gnd2" )
			)
			( pin "T1P17.1"
				( objectStatus "@baseboard_fab2_lib.baseboard_fab2(sch_1):page271_i36:\1\" )
			)
			( pin "T1P17.2"
				( objectStatus "@baseboard_fab2_lib.baseboard_fab2(sch_1):page271_i36:\2\" )
			)
			( pin "T1P17.GND1"
				( objectStatus "@baseboard_fab2_lib.baseboard_fab2(sch_1):page271_i36:gnd1" )
			)
			( pin "T1P17.GND2"
				( objectStatus "@baseboard_fab2_lib.baseboard_fab2(sch_1):page271_i36:gnd2" )
			)
			( pin "T1P24.1"
				( objectStatus "@baseboard_fab2_lib.baseboard_fab2(sch_1):page271_i38:\1\" )
			)
			( pin "T1P24.2"
				( objectStatus "@baseboard_fab2_lib.baseboard_fab2(sch_1):page271_i38:\2\" )
			)
			( pin "T1P24.GND1"
				( objectStatus "@baseboard_fab2_lib.baseboard_fab2(sch_1):page271_i38:gnd1" )
			)
			( pin "T1P24.GND2"
				( objectStatus "@baseboard_fab2_lib.baseboard_fab2(sch_1):page271_i38:gnd2" )
			)
			( pin "T1P19.1"
				( objectStatus "@baseboard_fab2_lib.baseboard_fab2(sch_1):page271_i39:\1\" )
			)
			( pin "T1P19.2"
				( objectStatus "@baseboard_fab2_lib.baseboard_fab2(sch_1):page271_i39:\2\" )
			)
			( pin "T1P19.GND1"
				( objectStatus "@baseboard_fab2_lib.baseboard_fab2(sch_1):page271_i39:gnd1" )
			)
			( pin "T1P19.GND2"
				( objectStatus "@baseboard_fab2_lib.baseboard_fab2(sch_1):page271_i39:gnd2" )
			)
			( pin "T1P22.1"
				( objectStatus "@baseboard_fab2_lib.baseboard_fab2(sch_1):page271_i45:\1\" )
			)
			( pin "T1P22.2"
				( objectStatus "@baseboard_fab2_lib.baseboard_fab2(sch_1):page271_i45:\2\" )
			)
			( pin "T1P22.GND1"
				( objectStatus "@baseboard_fab2_lib.baseboard_fab2(sch_1):page271_i45:gnd1" )
			)
			( pin "T1P22.GND2"
				( objectStatus "@baseboard_fab2_lib.baseboard_fab2(sch_1):page271_i45:gnd2" )
			)
			( pin "T1P23.1"
				( objectStatus "@baseboard_fab2_lib.baseboard_fab2(sch_1):page271_i47:\1\" )
			)
			( pin "T1P23.2"
				( objectStatus "@baseboard_fab2_lib.baseboard_fab2(sch_1):page271_i47:\2\" )
			)
			( pin "T1P23.GND1"
				( objectStatus "@baseboard_fab2_lib.baseboard_fab2(sch_1):page271_i47:gnd1" )
			)
			( pin "T1P23.GND2"
				( objectStatus "@baseboard_fab2_lib.baseboard_fab2(sch_1):page271_i47:gnd2" )
			)
			( pin "T1P25.1"
				( objectStatus "@baseboard_fab2_lib.baseboard_fab2(sch_1):page271_i50:\1\" )
			)
			( pin "T1P25.GND1"
				( objectStatus "@baseboard_fab2_lib.baseboard_fab2(sch_1):page271_i50:gnd1" )
			)
			( pin "T1P26.1"
				( objectStatus "@baseboard_fab2_lib.baseboard_fab2(sch_1):page271_i52:\1\" )
			)
			( pin "T1P26.GND1"
				( objectStatus "@baseboard_fab2_lib.baseboard_fab2(sch_1):page271_i52:gnd1" )
			)
			( pin "T1P27.1"
				( objectStatus "@baseboard_fab2_lib.baseboard_fab2(sch_1):page271_i54:\1\" )
			)
			( pin "T1P27.GND1"
				( objectStatus "@baseboard_fab2_lib.baseboard_fab2(sch_1):page271_i54:gnd1" )
			)
			( pin "T1P29.1"
				( objectStatus "@baseboard_fab2_lib.baseboard_fab2(sch_1):page271_i56:\1\" )
			)
			( pin "T1P29.GND1"
				( objectStatus "@baseboard_fab2_lib.baseboard_fab2(sch_1):page271_i56:gnd1" )
			)
			( pin "T1P28.1"
				( objectStatus "@baseboard_fab2_lib.baseboard_fab2(sch_1):page271_i60:\1\" )
			)
			( pin "T1P28.GND1"
				( objectStatus "@baseboard_fab2_lib.baseboard_fab2(sch_1):page271_i60:gnd1" )
			)
			( pin "T1P30.1"
				( objectStatus "@baseboard_fab2_lib.baseboard_fab2(sch_1):page271_i61:\1\" )
			)
			( pin "T1P30.GND1"
				( objectStatus "@baseboard_fab2_lib.baseboard_fab2(sch_1):page271_i61:gnd1" )
			)
			( pin "T1P34.1"
				( objectStatus "@baseboard_fab2_lib.baseboard_fab2(sch_1):page271_i62:\1\" )
			)
			( pin "T1P34.GND1"
				( objectStatus "@baseboard_fab2_lib.baseboard_fab2(sch_1):page271_i62:gnd1" )
			)
			( pin "T1P36.1"
				( objectStatus "@baseboard_fab2_lib.baseboard_fab2(sch_1):page271_i63:\1\" )
			)
			( pin "T1P36.GND1"
				( objectStatus "@baseboard_fab2_lib.baseboard_fab2(sch_1):page271_i63:gnd1" )
			)
			( pin "T1P35.1"
				( objectStatus "@baseboard_fab2_lib.baseboard_fab2(sch_1):page271_i67:\1\" )
			)
			( pin "T1P35.GND1"
				( objectStatus "@baseboard_fab2_lib.baseboard_fab2(sch_1):page271_i67:gnd1" )
			)
			( pin "T1P31.1"
				( objectStatus "@baseboard_fab2_lib.baseboard_fab2(sch_1):page271_i71:\1\" )
			)
			( pin "T1P31.GND1"
				( objectStatus "@baseboard_fab2_lib.baseboard_fab2(sch_1):page271_i71:gnd1" )
			)
			( pin "T1P32.1"
				( objectStatus "@baseboard_fab2_lib.baseboard_fab2(sch_1):page271_i72:\1\" )
			)
			( pin "T1P32.GND1"
				( objectStatus "@baseboard_fab2_lib.baseboard_fab2(sch_1):page271_i72:gnd1" )
			)
			( pin "T1P33.1"
				( objectStatus "@baseboard_fab2_lib.baseboard_fab2(sch_1):page271_i73:\1\" )
			)
			( pin "T1P33.GND1"
				( objectStatus "@baseboard_fab2_lib.baseboard_fab2(sch_1):page271_i73:gnd1" )
			)
			( pin "R7W6.1"
				( objectStatus "@baseboard_fab2_lib.baseboard_fab2(sch_1):page118_i176:a" )
			)
			( pin "R7W6.2"
				( objectStatus "@baseboard_fab2_lib.baseboard_fab2(sch_1):page118_i176:b" )
			)
			( pin "R7W8.1"
				( objectStatus "@baseboard_fab2_lib.baseboard_fab2(sch_1):page120_i269:a" )
			)
			( pin "R7W8.2"
				( objectStatus "@baseboard_fab2_lib.baseboard_fab2(sch_1):page120_i269:b" )
			)
			( pin "R7W9.1"
				( objectStatus "@baseboard_fab2_lib.baseboard_fab2(sch_1):page118_i177:a" )
			)
			( pin "R7W9.2"
				( objectStatus "@baseboard_fab2_lib.baseboard_fab2(sch_1):page118_i177:b" )
			)
			( pin "R7W10.1"
				( objectStatus "@baseboard_fab2_lib.baseboard_fab2(sch_1):page120_i270:a" )
			)
			( pin "R7W10.2"
				( objectStatus "@baseboard_fab2_lib.baseboard_fab2(sch_1):page120_i270:b" )
			)
			( pin "R7W12.1"
				( objectStatus "@baseboard_fab2_lib.baseboard_fab2(sch_1):page120_i271:a" )
			)
			( pin "R7W12.2"
				( objectStatus "@baseboard_fab2_lib.baseboard_fab2(sch_1):page120_i271:b" )
			)
			( pin "R7W11.1"
				( objectStatus "@baseboard_fab2_lib.baseboard_fab2(sch_1):page120_i273:a" )
			)
			( pin "R7W11.2"
				( objectStatus "@baseboard_fab2_lib.baseboard_fab2(sch_1):page120_i273:b" )
			)
			( pin "R25W187.1"
				( objectStatus "@baseboard_fab2_lib.baseboard_fab2(sch_1):page268_i66:a" )
			)
			( pin "R25W187.2"
				( objectStatus "@baseboard_fab2_lib.baseboard_fab2(sch_1):page268_i66:b" )
			)
			( pin "R1W40.1"
				( objectStatus "@baseboard_fab2_lib.baseboard_fab2(sch_1):page188_i128:a" )
			)
			( pin "R1W40.2"
				( objectStatus "@baseboard_fab2_lib.baseboard_fab2(sch_1):page188_i128:b" )
			)
			( pin "R1W41.1"
				( objectStatus "@baseboard_fab2_lib.baseboard_fab2(sch_1):page188_i129:a" )
			)
			( pin "R1W41.2"
				( objectStatus "@baseboard_fab2_lib.baseboard_fab2(sch_1):page188_i129:b" )
			)
			( pin "R7W13.1"
				( objectStatus "@baseboard_fab2_lib.baseboard_fab2(sch_1):page119_i226:a" )
			)
			( pin "R7W13.2"
				( objectStatus "@baseboard_fab2_lib.baseboard_fab2(sch_1):page119_i226:b" )
			)
			( pin "R7W14.1"
				( objectStatus "@baseboard_fab2_lib.baseboard_fab2(sch_1):page120_i274:a" )
			)
			( pin "R7W14.2"
				( objectStatus "@baseboard_fab2_lib.baseboard_fab2(sch_1):page120_i274:b" )
			)
			( pin "R7W15.1"
				( objectStatus "@baseboard_fab2_lib.baseboard_fab2(sch_1):page119_i227:a" )
			)
			( pin "R7W15.2"
				( objectStatus "@baseboard_fab2_lib.baseboard_fab2(sch_1):page119_i227:b" )
			)
			( pin "R8C21.1"
				( objectStatus "@baseboard_fab2_lib.baseboard_fab2(sch_1):page120_i275:a" )
			)
			( pin "R8C21.2"
				( objectStatus "@baseboard_fab2_lib.baseboard_fab2(sch_1):page120_i275:b" )
			)
			( pin "R2U50.1"
				( objectStatus "@baseboard_fab2_lib.baseboard_fab2(sch_1):page119_i228:a" )
			)
			( pin "R2U50.2"
				( objectStatus "@baseboard_fab2_lib.baseboard_fab2(sch_1):page119_i228:b" )
			)
			( pin "R1W42.1"
				( objectStatus "@baseboard_fab2_lib.baseboard_fab2(sch_1):page188_i131:a" )
			)
			( pin "R1W42.2"
				( objectStatus "@baseboard_fab2_lib.baseboard_fab2(sch_1):page188_i131:b" )
			)
			( pin "R1W43.1"
				( objectStatus "@baseboard_fab2_lib.baseboard_fab2(sch_1):page188_i132:a" )
			)
			( pin "R1W43.2"
				( objectStatus "@baseboard_fab2_lib.baseboard_fab2(sch_1):page188_i132:b" )
			)
			( pin "R1W44.1"
				( objectStatus "@baseboard_fab2_lib.baseboard_fab2(sch_1):page188_i133:a" )
			)
			( pin "R1W44.2"
				( objectStatus "@baseboard_fab2_lib.baseboard_fab2(sch_1):page188_i133:b" )
			)
			( pin "R1W45.1"
				( objectStatus "@baseboard_fab2_lib.baseboard_fab2(sch_1):page188_i134:a" )
			)
			( pin "R1W45.2"
				( objectStatus "@baseboard_fab2_lib.baseboard_fab2(sch_1):page188_i134:b" )
			)
			( pin "R7W18.1"
				( objectStatus "@baseboard_fab2_lib.baseboard_fab2(sch_1):page120_i277:a" )
			)
			( pin "R7W18.2"
				( objectStatus "@baseboard_fab2_lib.baseboard_fab2(sch_1):page120_i277:b" )
			)
			( pin "R9P7.1"
				( objectStatus "@baseboard_fab2_lib.baseboard_fab2(sch_1):page200_i252:a" )
			)
			( pin "R9P7.2"
				( objectStatus "@baseboard_fab2_lib.baseboard_fab2(sch_1):page200_i252:b" )
			)
			( pin "L1M2.1"
				( objectStatus "@baseboard_fab2_lib.baseboard_fab2(sch_1):page176_i181:a1" )
			)
			( pin "L1M2.2"
				( objectStatus "@baseboard_fab2_lib.baseboard_fab2(sch_1):page176_i181:a2" )
			)
			( pin "L1M2.3"
				( objectStatus "@baseboard_fab2_lib.baseboard_fab2(sch_1):page176_i181:b1" )
			)
			( pin "L1M2.4"
				( objectStatus "@baseboard_fab2_lib.baseboard_fab2(sch_1):page176_i181:b2" )
			)
			( pin "L7G2.2"
				( objectStatus "@baseboard_fab2_lib.baseboard_fab2(sch_1):page216_i155:f" )
			)
			( pin "L7G2.1"
				( objectStatus "@baseboard_fab2_lib.baseboard_fab2(sch_1):page216_i155:s" )
			)
			( pin "R1D20.1"
				( objectStatus "@baseboard_fab2_lib.baseboard_fab2(sch_1):page200_i253:a" )
			)
			( pin "R1D20.2"
				( objectStatus "@baseboard_fab2_lib.baseboard_fab2(sch_1):page200_i253:b" )
			)
			( pin "R9L9.1"
				( objectStatus "@baseboard_fab2_lib.baseboard_fab2(sch_1):page227_i154:a" )
			)
			( pin "R9L9.2"
				( objectStatus "@baseboard_fab2_lib.baseboard_fab2(sch_1):page227_i154:b" )
			)
			( pin "R9L4.1"
				( objectStatus "@baseboard_fab2_lib.baseboard_fab2(sch_1):page227_i155:a" )
			)
			( pin "R9L4.2"
				( objectStatus "@baseboard_fab2_lib.baseboard_fab2(sch_1):page227_i155:b" )
			)
			( pin "C8C1.1"
				( objectStatus "@baseboard_fab2_lib.baseboard_fab2(sch_1):page118_i178:a" )
			)
			( pin "C8C1.2"
				( objectStatus "@baseboard_fab2_lib.baseboard_fab2(sch_1):page118_i178:b" )
			)
			( pin "C8C2.1"
				( objectStatus "@baseboard_fab2_lib.baseboard_fab2(sch_1):page118_i179:a" )
			)
			( pin "C8C2.2"
				( objectStatus "@baseboard_fab2_lib.baseboard_fab2(sch_1):page118_i179:b" )
			)
			( pin "R9T8.1"
				( objectStatus "@baseboard_fab2_lib.baseboard_fab2(sch_1):page181_i137:a" )
			)
			( pin "R9T8.2"
				( objectStatus "@baseboard_fab2_lib.baseboard_fab2(sch_1):page181_i137:b" )
			)
			( pin "C25W101.1"
				( objectStatus "@baseboard_fab2_lib.baseboard_fab2(sch_1):page269_i79:a" )
			)
			( pin "C25W101.2"
				( objectStatus "@baseboard_fab2_lib.baseboard_fab2(sch_1):page269_i79:b" )
			)
			( pin "R8W10.1"
				( objectStatus "@baseboard_fab2_lib.baseboard_fab2(sch_1):page245_i56:a" )
			)
			( pin "R8W10.2"
				( objectStatus "@baseboard_fab2_lib.baseboard_fab2(sch_1):page245_i56:b" )
			)
			( pin "R8W11.1"
				( objectStatus "@baseboard_fab2_lib.baseboard_fab2(sch_1):page245_i57:a" )
			)
			( pin "R8W11.2"
				( objectStatus "@baseboard_fab2_lib.baseboard_fab2(sch_1):page245_i57:b" )
			)
			( pin "R8W12.1"
				( objectStatus "@baseboard_fab2_lib.baseboard_fab2(sch_1):page245_i58:a" )
			)
			( pin "R8W12.2"
				( objectStatus "@baseboard_fab2_lib.baseboard_fab2(sch_1):page245_i58:b" )
			)
			( pin "R8W13.1"
				( objectStatus "@baseboard_fab2_lib.baseboard_fab2(sch_1):page245_i59:a" )
			)
			( pin "R8W13.2"
				( objectStatus "@baseboard_fab2_lib.baseboard_fab2(sch_1):page245_i59:b" )
			)
			( pin "R8W14.1"
				( objectStatus "@baseboard_fab2_lib.baseboard_fab2(sch_1):page245_i60:a" )
			)
			( pin "R8W14.2"
				( objectStatus "@baseboard_fab2_lib.baseboard_fab2(sch_1):page245_i60:b" )
			)
			( pin "U8W1.2"
				( objectStatus "@baseboard_fab2_lib.baseboard_fab2(sch_1):page245_i64:a" )
			)
			( pin "U8W1.4"
				( objectStatus "@baseboard_fab2_lib.baseboard_fab2(sch_1):page245_i64:b" )
			)
			( pin "U8W1.1"
				( objectStatus "@baseboard_fab2_lib.baseboard_fab2(sch_1):page245_i64:oe_n" )
			)
			( pin "U8W2.4"
				( objectStatus "@baseboard_fab2_lib.baseboard_fab2(sch_1):page245_i66:a" )
			)
			( pin "U8W2.3"
				( objectStatus "@baseboard_fab2_lib.baseboard_fab2(sch_1):page245_i66:b0" )
			)
			( pin "U8W2.1"
				( objectStatus "@baseboard_fab2_lib.baseboard_fab2(sch_1):page245_i66:b1" )
			)
			( pin "U8W2.2"
				( objectStatus "@baseboard_fab2_lib.baseboard_fab2(sch_1):page245_i66:gnd" )
			)
			( pin "U8W2.6"
				( objectStatus "@baseboard_fab2_lib.baseboard_fab2(sch_1):page245_i66:s" )
			)
			( pin "U8W2.5"
				( objectStatus "@baseboard_fab2_lib.baseboard_fab2(sch_1):page245_i66:vcc" )
			)
			( pin "C8W6.1"
				( objectStatus "@baseboard_fab2_lib.baseboard_fab2(sch_1):page245_i71:a" )
			)
			( pin "C8W6.2"
				( objectStatus "@baseboard_fab2_lib.baseboard_fab2(sch_1):page245_i71:b" )
			)
			( pin "C8W5.1"
				( objectStatus "@baseboard_fab2_lib.baseboard_fab2(sch_1):page245_i74:a" )
			)
			( pin "C8W5.2"
				( objectStatus "@baseboard_fab2_lib.baseboard_fab2(sch_1):page245_i74:b" )
			)
			( pin "R8W15.1"
				( objectStatus "@baseboard_fab2_lib.baseboard_fab2(sch_1):page245_i78:a" )
			)
			( pin "R8W15.2"
				( objectStatus "@baseboard_fab2_lib.baseboard_fab2(sch_1):page245_i78:b" )
			)
			( pin "R7W19.1"
				( objectStatus "@baseboard_fab2_lib.baseboard_fab2(sch_1):page118_i180:a" )
			)
			( pin "R7W19.2"
				( objectStatus "@baseboard_fab2_lib.baseboard_fab2(sch_1):page118_i180:b" )
			)
			( pin "R7W20.1"
				( objectStatus "@baseboard_fab2_lib.baseboard_fab2(sch_1):page120_i278:a" )
			)
			( pin "R7W20.2"
				( objectStatus "@baseboard_fab2_lib.baseboard_fab2(sch_1):page120_i278:b" )
			)
			( pin "R1T4.1"
				( objectStatus "@baseboard_fab2_lib.baseboard_fab2(sch_1):page164_i100:a" )
			)
			( pin "R1T4.2"
				( objectStatus "@baseboard_fab2_lib.baseboard_fab2(sch_1):page164_i100:b" )
			)
			( pin "R25W101.1"
				( objectStatus "@baseboard_fab2_lib.baseboard_fab2(sch_1):page150_i241:a" )
			)
			( pin "R25W101.2"
				( objectStatus "@baseboard_fab2_lib.baseboard_fab2(sch_1):page150_i241:b" )
			)
			( pin "U6W12.4"
				( objectStatus "@baseboard_fab2_lib.baseboard_fab2(sch_1):page176_i182:a" )
			)
			( pin "U6W12.3"
				( objectStatus "@baseboard_fab2_lib.baseboard_fab2(sch_1):page176_i182:b0" )
			)
			( pin "U6W12.1"
				( objectStatus "@baseboard_fab2_lib.baseboard_fab2(sch_1):page176_i182:b1" )
			)
			( pin "U6W12.2"
				( objectStatus "@baseboard_fab2_lib.baseboard_fab2(sch_1):page176_i182:gnd" )
			)
			( pin "U6W12.6"
				( objectStatus "@baseboard_fab2_lib.baseboard_fab2(sch_1):page176_i182:s" )
			)
			( pin "U6W12.5"
				( objectStatus "@baseboard_fab2_lib.baseboard_fab2(sch_1):page176_i182:vcc" )
			)
			( pin "F30W1.1"
				( objectStatus "@baseboard_fab2_lib.baseboard_fab2(sch_1):page253_i44:\1\" )
			)
			( pin "F30W1.2"
				( objectStatus "@baseboard_fab2_lib.baseboard_fab2(sch_1):page253_i44:\2\" )
			)
			( pin "R7W22.1"
				( objectStatus "@baseboard_fab2_lib.baseboard_fab2(sch_1):page119_i230:a" )
			)
			( pin "R7W22.2"
				( objectStatus "@baseboard_fab2_lib.baseboard_fab2(sch_1):page119_i230:b" )
			)
			( pin "R7W21.1"
				( objectStatus "@baseboard_fab2_lib.baseboard_fab2(sch_1):page118_i183:a" )
			)
			( pin "R7W21.2"
				( objectStatus "@baseboard_fab2_lib.baseboard_fab2(sch_1):page118_i183:b" )
			)
			( pin "R25W115.1"
				( objectStatus "@baseboard_fab2_lib.baseboard_fab2(sch_1):page150_i242:a" )
			)
			( pin "R25W115.2"
				( objectStatus "@baseboard_fab2_lib.baseboard_fab2(sch_1):page150_i242:b" )
			)
			( pin "R6P48.1"
				( objectStatus "@baseboard_fab2_lib.baseboard_fab2(sch_1):page102_i115:a" )
			)
			( pin "R6P48.2"
				( objectStatus "@baseboard_fab2_lib.baseboard_fab2(sch_1):page102_i115:b" )
			)
			( bus "M_A_BA"
				( memberType ( signal ) )
				( member ( signalRef "M_A_BA<0>") )
				( member ( signalRef "M_A_BA<1>") )
				( objectStatus "@baseboard_fab2_lib.baseboard_fab2(sch_1):m_a_ba" )
			)
			( bus "M_A_BG"
				( memberType ( signal ) )
				( member ( signalRef "M_A_BG<0>") )
				( member ( signalRef "M_A_BG<1>") )
				( objectStatus "@baseboard_fab2_lib.baseboard_fab2(sch_1):m_a_bg" )
			)
			( bus "M_A_C"
				( memberType ( signal ) )
				( member ( signalRef "M_A_C<2>") )
				( objectStatus "@baseboard_fab2_lib.baseboard_fab2(sch_1):m_a_c" )
			)
			( bus "M_A_CKE"
				( memberType ( signal ) )
				( member ( signalRef "M_A_CKE<0>") )
				( member ( signalRef "M_A_CKE<1>") )
				( member ( signalRef "M_A_CKE<2>") )
				( member ( signalRef "M_A_CKE<3>") )
				( objectStatus "@baseboard_fab2_lib.baseboard_fab2(sch_1):m_a_cke" )
			)
			( bus "M_A_CLK_DN"
				( memberType ( signal ) )
				( member ( signalRef "M_A_CLK_DN<0>") )
				( member ( signalRef "M_A_CLK_DN<1>") )
				( member ( signalRef "M_A_CLK_DN<2>") )
				( member ( signalRef "M_A_CLK_DN<3>") )
				( objectStatus "@baseboard_fab2_lib.baseboard_fab2(sch_1):m_a_clk_dn" )
			)
			( bus "M_A_CLK_DP"
				( memberType ( signal ) )
				( member ( signalRef "M_A_CLK_DP<0>") )
				( member ( signalRef "M_A_CLK_DP<1>") )
				( member ( signalRef "M_A_CLK_DP<2>") )
				( member ( signalRef "M_A_CLK_DP<3>") )
				( objectStatus "@baseboard_fab2_lib.baseboard_fab2(sch_1):m_a_clk_dp" )
			)
			( bus "M_A_CS_N"
				( memberType ( signal ) )
				( member ( signalRef "M_A_CS_N<0>") )
				( member ( signalRef "M_A_CS_N<1>") )
				( member ( signalRef "M_A_CS_N<2>") )
				( member ( signalRef "M_A_CS_N<3>") )
				( member ( signalRef "M_A_CS_N<4>") )
				( member ( signalRef "M_A_CS_N<5>") )
				( member ( signalRef "M_A_CS_N<6>") )
				( member ( signalRef "M_A_CS_N<7>") )
				( objectStatus "@baseboard_fab2_lib.baseboard_fab2(sch_1):m_a_cs_n" )
			)
			( bus "M_A_DQ"
				( memberType ( signal ) )
				( member ( signalRef "M_A_DQ<0>") )
				( member ( signalRef "M_A_DQ<1>") )
				( member ( signalRef "M_A_DQ<2>") )
				( member ( signalRef "M_A_DQ<3>") )
				( member ( signalRef "M_A_DQ<4>") )
				( member ( signalRef "M_A_DQ<5>") )
				( member ( signalRef "M_A_DQ<6>") )
				( member ( signalRef "M_A_DQ<7>") )
				( member ( signalRef "M_A_DQ<8>") )
				( member ( signalRef "M_A_DQ<9>") )
				( member ( signalRef "M_A_DQ<10>") )
				( member ( signalRef "M_A_DQ<11>") )
				( member ( signalRef "M_A_DQ<12>") )
				( member ( signalRef "M_A_DQ<13>") )
				( member ( signalRef "M_A_DQ<14>") )
				( member ( signalRef "M_A_DQ<15>") )
				( member ( signalRef "M_A_DQ<16>") )
				( member ( signalRef "M_A_DQ<17>") )
				( member ( signalRef "M_A_DQ<18>") )
				( member ( signalRef "M_A_DQ<19>") )
				( member ( signalRef "M_A_DQ<20>") )
				( member ( signalRef "M_A_DQ<21>") )
				( member ( signalRef "M_A_DQ<22>") )
				( member ( signalRef "M_A_DQ<23>") )
				( member ( signalRef "M_A_DQ<24>") )
				( member ( signalRef "M_A_DQ<25>") )
				( member ( signalRef "M_A_DQ<26>") )
				( member ( signalRef "M_A_DQ<27>") )
				( member ( signalRef "M_A_DQ<28>") )
				( member ( signalRef "M_A_DQ<29>") )
				( member ( signalRef "M_A_DQ<30>") )
				( member ( signalRef "M_A_DQ<31>") )
				( member ( signalRef "M_A_DQ<32>") )
				( member ( signalRef "M_A_DQ<33>") )
				( member ( signalRef "M_A_DQ<34>") )
				( member ( signalRef "M_A_DQ<35>") )
				( member ( signalRef "M_A_DQ<36>") )
				( member ( signalRef "M_A_DQ<37>") )
				( member ( signalRef "M_A_DQ<38>") )
				( member ( signalRef "M_A_DQ<39>") )
				( member ( signalRef "M_A_DQ<40>") )
				( member ( signalRef "M_A_DQ<41>") )
				( member ( signalRef "M_A_DQ<42>") )
				( member ( signalRef "M_A_DQ<43>") )
				( member ( signalRef "M_A_DQ<44>") )
				( member ( signalRef "M_A_DQ<45>") )
				( member ( signalRef "M_A_DQ<46>") )
				( member ( signalRef "M_A_DQ<47>") )
				( member ( signalRef "M_A_DQ<48>") )
				( member ( signalRef "M_A_DQ<49>") )
				( member ( signalRef "M_A_DQ<50>") )
				( member ( signalRef "M_A_DQ<51>") )
				( member ( signalRef "M_A_DQ<52>") )
				( member ( signalRef "M_A_DQ<53>") )
				( member ( signalRef "M_A_DQ<54>") )
				( member ( signalRef "M_A_DQ<55>") )
				( member ( signalRef "M_A_DQ<56>") )
				( member ( signalRef "M_A_DQ<57>") )
				( member ( signalRef "M_A_DQ<58>") )
				( member ( signalRef "M_A_DQ<59>") )
				( member ( signalRef "M_A_DQ<60>") )
				( member ( signalRef "M_A_DQ<61>") )
				( member ( signalRef "M_A_DQ<62>") )
				( member ( signalRef "M_A_DQ<63>") )
				( objectStatus "@baseboard_fab2_lib.baseboard_fab2(sch_1):m_a_dq" )
			)
			( bus "M_A_DQS_DN"
				( memberType ( signal ) )
				( member ( signalRef "M_A_DQS_DN<0>") )
				( member ( signalRef "M_A_DQS_DN<1>") )
				( member ( signalRef "M_A_DQS_DN<2>") )
				( member ( signalRef "M_A_DQS_DN<3>") )
				( member ( signalRef "M_A_DQS_DN<4>") )
				( member ( signalRef "M_A_DQS_DN<5>") )
				( member ( signalRef "M_A_DQS_DN<6>") )
				( member ( signalRef "M_A_DQS_DN<7>") )
				( member ( signalRef "M_A_DQS_DN<8>") )
				( member ( signalRef "M_A_DQS_DN<9>") )
				( member ( signalRef "M_A_DQS_DN<10>") )
				( member ( signalRef "M_A_DQS_DN<11>") )
				( member ( signalRef "M_A_DQS_DN<12>") )
				( member ( signalRef "M_A_DQS_DN<13>") )
				( member ( signalRef "M_A_DQS_DN<14>") )
				( member ( signalRef "M_A_DQS_DN<15>") )
				( member ( signalRef "M_A_DQS_DN<16>") )
				( member ( signalRef "M_A_DQS_DN<17>") )
				( objectStatus "@baseboard_fab2_lib.baseboard_fab2(sch_1):m_a_dqs_dn" )
			)
			( bus "M_A_DQS_DP"
				( memberType ( signal ) )
				( member ( signalRef "M_A_DQS_DP<0>") )
				( member ( signalRef "M_A_DQS_DP<1>") )
				( member ( signalRef "M_A_DQS_DP<2>") )
				( member ( signalRef "M_A_DQS_DP<3>") )
				( member ( signalRef "M_A_DQS_DP<4>") )
				( member ( signalRef "M_A_DQS_DP<5>") )
				( member ( signalRef "M_A_DQS_DP<6>") )
				( member ( signalRef "M_A_DQS_DP<7>") )
				( member ( signalRef "M_A_DQS_DP<8>") )
				( member ( signalRef "M_A_DQS_DP<9>") )
				( member ( signalRef "M_A_DQS_DP<10>") )
				( member ( signalRef "M_A_DQS_DP<11>") )
				( member ( signalRef "M_A_DQS_DP<12>") )
				( member ( signalRef "M_A_DQS_DP<13>") )
				( member ( signalRef "M_A_DQS_DP<14>") )
				( member ( signalRef "M_A_DQS_DP<15>") )
				( member ( signalRef "M_A_DQS_DP<16>") )
				( member ( signalRef "M_A_DQS_DP<17>") )
				( objectStatus "@baseboard_fab2_lib.baseboard_fab2(sch_1):m_a_dqs_dp" )
			)
			( bus "M_A_ECC"
				( memberType ( signal ) )
				( member ( signalRef "M_A_ECC<0>") )
				( member ( signalRef "M_A_ECC<1>") )
				( member ( signalRef "M_A_ECC<2>") )
				( member ( signalRef "M_A_ECC<3>") )
				( member ( signalRef "M_A_ECC<4>") )
				( member ( signalRef "M_A_ECC<5>") )
				( member ( signalRef "M_A_ECC<6>") )
				( member ( signalRef "M_A_ECC<7>") )
				( objectStatus "@baseboard_fab2_lib.baseboard_fab2(sch_1):m_a_ecc" )
			)
			( bus "M_A_MA"
				( memberType ( signal ) )
				( member ( signalRef "M_A_MA<0>") )
				( member ( signalRef "M_A_MA<1>") )
				( member ( signalRef "M_A_MA<2>") )
				( member ( signalRef "M_A_MA<3>") )
				( member ( signalRef "M_A_MA<4>") )
				( member ( signalRef "M_A_MA<5>") )
				( member ( signalRef "M_A_MA<6>") )
				( member ( signalRef "M_A_MA<7>") )
				( member ( signalRef "M_A_MA<8>") )
				( member ( signalRef "M_A_MA<9>") )
				( member ( signalRef "M_A_MA<10>") )
				( member ( signalRef "M_A_MA<11>") )
				( member ( signalRef "M_A_MA<12>") )
				( member ( signalRef "M_A_MA<13>") )
				( member ( signalRef "M_A_MA<14>") )
				( member ( signalRef "M_A_MA<15>") )
				( member ( signalRef "M_A_MA<16>") )
				( member ( signalRef "M_A_MA<17>") )
				( objectStatus "@baseboard_fab2_lib.baseboard_fab2(sch_1):m_a_ma" )
			)
			( bus "M_A_ODT"
				( memberType ( signal ) )
				( member ( signalRef "M_A_ODT<0>") )
				( member ( signalRef "M_A_ODT<1>") )
				( member ( signalRef "M_A_ODT<2>") )
				( member ( signalRef "M_A_ODT<3>") )
				( objectStatus "@baseboard_fab2_lib.baseboard_fab2(sch_1):m_a_odt" )
			)
			( bus "M_B_BA"
				( memberType ( signal ) )
				( member ( signalRef "M_B_BA<0>") )
				( member ( signalRef "M_B_BA<1>") )
				( objectStatus "@baseboard_fab2_lib.baseboard_fab2(sch_1):m_b_ba" )
			)
			( bus "M_B_BG"
				( memberType ( signal ) )
				( member ( signalRef "M_B_BG<0>") )
				( member ( signalRef "M_B_BG<1>") )
				( objectStatus "@baseboard_fab2_lib.baseboard_fab2(sch_1):m_b_bg" )
			)
			( bus "M_B_C"
				( memberType ( signal ) )
				( member ( signalRef "M_B_C<2>") )
				( objectStatus "@baseboard_fab2_lib.baseboard_fab2(sch_1):m_b_c" )
			)
			( bus "M_B_CKE"
				( memberType ( signal ) )
				( member ( signalRef "M_B_CKE<0>") )
				( member ( signalRef "M_B_CKE<1>") )
				( member ( signalRef "M_B_CKE<2>") )
				( member ( signalRef "M_B_CKE<3>") )
				( objectStatus "@baseboard_fab2_lib.baseboard_fab2(sch_1):m_b_cke" )
			)
			( bus "M_B_CLK_DN"
				( memberType ( signal ) )
				( member ( signalRef "M_B_CLK_DN<0>") )
				( member ( signalRef "M_B_CLK_DN<1>") )
				( member ( signalRef "M_B_CLK_DN<2>") )
				( member ( signalRef "M_B_CLK_DN<3>") )
				( objectStatus "@baseboard_fab2_lib.baseboard_fab2(sch_1):m_b_clk_dn" )
			)
			( bus "M_B_CLK_DP"
				( memberType ( signal ) )
				( member ( signalRef "M_B_CLK_DP<0>") )
				( member ( signalRef "M_B_CLK_DP<1>") )
				( member ( signalRef "M_B_CLK_DP<2>") )
				( member ( signalRef "M_B_CLK_DP<3>") )
				( objectStatus "@baseboard_fab2_lib.baseboard_fab2(sch_1):m_b_clk_dp" )
			)
			( bus "M_B_CS_N"
				( memberType ( signal ) )
				( member ( signalRef "M_B_CS_N<0>") )
				( member ( signalRef "M_B_CS_N<1>") )
				( member ( signalRef "M_B_CS_N<2>") )
				( member ( signalRef "M_B_CS_N<3>") )
				( member ( signalRef "M_B_CS_N<4>") )
				( member ( signalRef "M_B_CS_N<5>") )
				( member ( signalRef "M_B_CS_N<6>") )
				( member ( signalRef "M_B_CS_N<7>") )
				( objectStatus "@baseboard_fab2_lib.baseboard_fab2(sch_1):m_b_cs_n" )
			)
			( bus "M_B_DQ"
				( memberType ( signal ) )
				( member ( signalRef "M_B_DQ<0>") )
				( member ( signalRef "M_B_DQ<1>") )
				( member ( signalRef "M_B_DQ<2>") )
				( member ( signalRef "M_B_DQ<3>") )
				( member ( signalRef "M_B_DQ<4>") )
				( member ( signalRef "M_B_DQ<5>") )
				( member ( signalRef "M_B_DQ<6>") )
				( member ( signalRef "M_B_DQ<7>") )
				( member ( signalRef "M_B_DQ<8>") )
				( member ( signalRef "M_B_DQ<9>") )
				( member ( signalRef "M_B_DQ<10>") )
				( member ( signalRef "M_B_DQ<11>") )
				( member ( signalRef "M_B_DQ<12>") )
				( member ( signalRef "M_B_DQ<13>") )
				( member ( signalRef "M_B_DQ<14>") )
				( member ( signalRef "M_B_DQ<15>") )
				( member ( signalRef "M_B_DQ<16>") )
				( member ( signalRef "M_B_DQ<17>") )
				( member ( signalRef "M_B_DQ<18>") )
				( member ( signalRef "M_B_DQ<19>") )
				( member ( signalRef "M_B_DQ<20>") )
				( member ( signalRef "M_B_DQ<21>") )
				( member ( signalRef "M_B_DQ<22>") )
				( member ( signalRef "M_B_DQ<23>") )
				( member ( signalRef "M_B_DQ<24>") )
				( member ( signalRef "M_B_DQ<25>") )
				( member ( signalRef "M_B_DQ<26>") )
				( member ( signalRef "M_B_DQ<27>") )
				( member ( signalRef "M_B_DQ<28>") )
				( member ( signalRef "M_B_DQ<29>") )
				( member ( signalRef "M_B_DQ<30>") )
				( member ( signalRef "M_B_DQ<31>") )
				( member ( signalRef "M_B_DQ<32>") )
				( member ( signalRef "M_B_DQ<33>") )
				( member ( signalRef "M_B_DQ<34>") )
				( member ( signalRef "M_B_DQ<35>") )
				( member ( signalRef "M_B_DQ<36>") )
				( member ( signalRef "M_B_DQ<37>") )
				( member ( signalRef "M_B_DQ<38>") )
				( member ( signalRef "M_B_DQ<39>") )
				( member ( signalRef "M_B_DQ<40>") )
				( member ( signalRef "M_B_DQ<41>") )
				( member ( signalRef "M_B_DQ<42>") )
				( member ( signalRef "M_B_DQ<43>") )
				( member ( signalRef "M_B_DQ<44>") )
				( member ( signalRef "M_B_DQ<45>") )
				( member ( signalRef "M_B_DQ<46>") )
				( member ( signalRef "M_B_DQ<47>") )
				( member ( signalRef "M_B_DQ<48>") )
				( member ( signalRef "M_B_DQ<49>") )
				( member ( signalRef "M_B_DQ<50>") )
				( member ( signalRef "M_B_DQ<51>") )
				( member ( signalRef "M_B_DQ<52>") )
				( member ( signalRef "M_B_DQ<53>") )
				( member ( signalRef "M_B_DQ<54>") )
				( member ( signalRef "M_B_DQ<55>") )
				( member ( signalRef "M_B_DQ<56>") )
				( member ( signalRef "M_B_DQ<57>") )
				( member ( signalRef "M_B_DQ<58>") )
				( member ( signalRef "M_B_DQ<59>") )
				( member ( signalRef "M_B_DQ<60>") )
				( member ( signalRef "M_B_DQ<61>") )
				( member ( signalRef "M_B_DQ<62>") )
				( member ( signalRef "M_B_DQ<63>") )
				( objectStatus "@baseboard_fab2_lib.baseboard_fab2(sch_1):m_b_dq" )
			)
			( bus "M_B_DQS_DN"
				( memberType ( signal ) )
				( member ( signalRef "M_B_DQS_DN<0>") )
				( member ( signalRef "M_B_DQS_DN<1>") )
				( member ( signalRef "M_B_DQS_DN<2>") )
				( member ( signalRef "M_B_DQS_DN<3>") )
				( member ( signalRef "M_B_DQS_DN<4>") )
				( member ( signalRef "M_B_DQS_DN<5>") )
				( member ( signalRef "M_B_DQS_DN<6>") )
				( member ( signalRef "M_B_DQS_DN<7>") )
				( member ( signalRef "M_B_DQS_DN<8>") )
				( member ( signalRef "M_B_DQS_DN<9>") )
				( member ( signalRef "M_B_DQS_DN<10>") )
				( member ( signalRef "M_B_DQS_DN<11>") )
				( member ( signalRef "M_B_DQS_DN<12>") )
				( member ( signalRef "M_B_DQS_DN<13>") )
				( member ( signalRef "M_B_DQS_DN<14>") )
				( member ( signalRef "M_B_DQS_DN<15>") )
				( member ( signalRef "M_B_DQS_DN<16>") )
				( member ( signalRef "M_B_DQS_DN<17>") )
				( objectStatus "@baseboard_fab2_lib.baseboard_fab2(sch_1):m_b_dqs_dn" )
			)
			( bus "M_B_DQS_DP"
				( memberType ( signal ) )
				( member ( signalRef "M_B_DQS_DP<0>") )
				( member ( signalRef "M_B_DQS_DP<1>") )
				( member ( signalRef "M_B_DQS_DP<2>") )
				( member ( signalRef "M_B_DQS_DP<3>") )
				( member ( signalRef "M_B_DQS_DP<4>") )
				( member ( signalRef "M_B_DQS_DP<5>") )
				( member ( signalRef "M_B_DQS_DP<6>") )
				( member ( signalRef "M_B_DQS_DP<7>") )
				( member ( signalRef "M_B_DQS_DP<8>") )
				( member ( signalRef "M_B_DQS_DP<9>") )
				( member ( signalRef "M_B_DQS_DP<10>") )
				( member ( signalRef "M_B_DQS_DP<11>") )
				( member ( signalRef "M_B_DQS_DP<12>") )
				( member ( signalRef "M_B_DQS_DP<13>") )
				( member ( signalRef "M_B_DQS_DP<14>") )
				( member ( signalRef "M_B_DQS_DP<15>") )
				( member ( signalRef "M_B_DQS_DP<16>") )
				( member ( signalRef "M_B_DQS_DP<17>") )
				( objectStatus "@baseboard_fab2_lib.baseboard_fab2(sch_1):m_b_dqs_dp" )
			)
			( bus "M_B_ECC"
				( memberType ( signal ) )
				( member ( signalRef "M_B_ECC<0>") )
				( member ( signalRef "M_B_ECC<1>") )
				( member ( signalRef "M_B_ECC<2>") )
				( member ( signalRef "M_B_ECC<3>") )
				( member ( signalRef "M_B_ECC<4>") )
				( member ( signalRef "M_B_ECC<5>") )
				( member ( signalRef "M_B_ECC<6>") )
				( member ( signalRef "M_B_ECC<7>") )
				( objectStatus "@baseboard_fab2_lib.baseboard_fab2(sch_1):m_b_ecc" )
			)
			( bus "M_B_MA"
				( memberType ( signal ) )
				( member ( signalRef "M_B_MA<0>") )
				( member ( signalRef "M_B_MA<1>") )
				( member ( signalRef "M_B_MA<2>") )
				( member ( signalRef "M_B_MA<3>") )
				( member ( signalRef "M_B_MA<4>") )
				( member ( signalRef "M_B_MA<5>") )
				( member ( signalRef "M_B_MA<6>") )
				( member ( signalRef "M_B_MA<7>") )
				( member ( signalRef "M_B_MA<8>") )
				( member ( signalRef "M_B_MA<9>") )
				( member ( signalRef "M_B_MA<10>") )
				( member ( signalRef "M_B_MA<11>") )
				( member ( signalRef "M_B_MA<12>") )
				( member ( signalRef "M_B_MA<13>") )
				( member ( signalRef "M_B_MA<14>") )
				( member ( signalRef "M_B_MA<15>") )
				( member ( signalRef "M_B_MA<16>") )
				( member ( signalRef "M_B_MA<17>") )
				( objectStatus "@baseboard_fab2_lib.baseboard_fab2(sch_1):m_b_ma" )
			)
			( bus "M_B_ODT"
				( memberType ( signal ) )
				( member ( signalRef "M_B_ODT<0>") )
				( member ( signalRef "M_B_ODT<1>") )
				( member ( signalRef "M_B_ODT<2>") )
				( member ( signalRef "M_B_ODT<3>") )
				( objectStatus "@baseboard_fab2_lib.baseboard_fab2(sch_1):m_b_odt" )
			)
			( bus "M_C_BA"
				( memberType ( signal ) )
				( member ( signalRef "M_C_BA<0>") )
				( member ( signalRef "M_C_BA<1>") )
				( objectStatus "@baseboard_fab2_lib.baseboard_fab2(sch_1):m_c_ba" )
			)
			( bus "M_C_BG"
				( memberType ( signal ) )
				( member ( signalRef "M_C_BG<0>") )
				( member ( signalRef "M_C_BG<1>") )
				( objectStatus "@baseboard_fab2_lib.baseboard_fab2(sch_1):m_c_bg" )
			)
			( bus "M_C_C"
				( memberType ( signal ) )
				( member ( signalRef "M_C_C<2>") )
				( objectStatus "@baseboard_fab2_lib.baseboard_fab2(sch_1):m_c_c" )
			)
			( bus "M_C_CKE"
				( memberType ( signal ) )
				( member ( signalRef "M_C_CKE<0>") )
				( member ( signalRef "M_C_CKE<1>") )
				( member ( signalRef "M_C_CKE<2>") )
				( member ( signalRef "M_C_CKE<3>") )
				( objectStatus "@baseboard_fab2_lib.baseboard_fab2(sch_1):m_c_cke" )
			)
			( bus "M_C_CLK_DN"
				( memberType ( signal ) )
				( member ( signalRef "M_C_CLK_DN<0>") )
				( member ( signalRef "M_C_CLK_DN<1>") )
				( member ( signalRef "M_C_CLK_DN<2>") )
				( member ( signalRef "M_C_CLK_DN<3>") )
				( objectStatus "@baseboard_fab2_lib.baseboard_fab2(sch_1):m_c_clk_dn" )
			)
			( bus "M_C_CLK_DP"
				( memberType ( signal ) )
				( member ( signalRef "M_C_CLK_DP<0>") )
				( member ( signalRef "M_C_CLK_DP<1>") )
				( member ( signalRef "M_C_CLK_DP<2>") )
				( member ( signalRef "M_C_CLK_DP<3>") )
				( objectStatus "@baseboard_fab2_lib.baseboard_fab2(sch_1):m_c_clk_dp" )
			)
			( bus "M_C_CS_N"
				( memberType ( signal ) )
				( member ( signalRef "M_C_CS_N<0>") )
				( member ( signalRef "M_C_CS_N<1>") )
				( member ( signalRef "M_C_CS_N<2>") )
				( member ( signalRef "M_C_CS_N<3>") )
				( member ( signalRef "M_C_CS_N<4>") )
				( member ( signalRef "M_C_CS_N<5>") )
				( member ( signalRef "M_C_CS_N<6>") )
				( member ( signalRef "M_C_CS_N<7>") )
				( objectStatus "@baseboard_fab2_lib.baseboard_fab2(sch_1):m_c_cs_n" )
			)
			( bus "M_C_DQ"
				( memberType ( signal ) )
				( member ( signalRef "M_C_DQ<0>") )
				( member ( signalRef "M_C_DQ<1>") )
				( member ( signalRef "M_C_DQ<2>") )
				( member ( signalRef "M_C_DQ<3>") )
				( member ( signalRef "M_C_DQ<4>") )
				( member ( signalRef "M_C_DQ<5>") )
				( member ( signalRef "M_C_DQ<6>") )
				( member ( signalRef "M_C_DQ<7>") )
				( member ( signalRef "M_C_DQ<8>") )
				( member ( signalRef "M_C_DQ<9>") )
				( member ( signalRef "M_C_DQ<10>") )
				( member ( signalRef "M_C_DQ<11>") )
				( member ( signalRef "M_C_DQ<12>") )
				( member ( signalRef "M_C_DQ<13>") )
				( member ( signalRef "M_C_DQ<14>") )
				( member ( signalRef "M_C_DQ<15>") )
				( member ( signalRef "M_C_DQ<16>") )
				( member ( signalRef "M_C_DQ<17>") )
				( member ( signalRef "M_C_DQ<18>") )
				( member ( signalRef "M_C_DQ<19>") )
				( member ( signalRef "M_C_DQ<20>") )
				( member ( signalRef "M_C_DQ<21>") )
				( member ( signalRef "M_C_DQ<22>") )
				( member ( signalRef "M_C_DQ<23>") )
				( member ( signalRef "M_C_DQ<24>") )
				( member ( signalRef "M_C_DQ<25>") )
				( member ( signalRef "M_C_DQ<26>") )
				( member ( signalRef "M_C_DQ<27>") )
				( member ( signalRef "M_C_DQ<28>") )
				( member ( signalRef "M_C_DQ<29>") )
				( member ( signalRef "M_C_DQ<30>") )
				( member ( signalRef "M_C_DQ<31>") )
				( member ( signalRef "M_C_DQ<32>") )
				( member ( signalRef "M_C_DQ<33>") )
				( member ( signalRef "M_C_DQ<34>") )
				( member ( signalRef "M_C_DQ<35>") )
				( member ( signalRef "M_C_DQ<36>") )
				( member ( signalRef "M_C_DQ<37>") )
				( member ( signalRef "M_C_DQ<38>") )
				( member ( signalRef "M_C_DQ<39>") )
				( member ( signalRef "M_C_DQ<40>") )
				( member ( signalRef "M_C_DQ<41>") )
				( member ( signalRef "M_C_DQ<42>") )
				( member ( signalRef "M_C_DQ<43>") )
				( member ( signalRef "M_C_DQ<44>") )
				( member ( signalRef "M_C_DQ<45>") )
				( member ( signalRef "M_C_DQ<46>") )
				( member ( signalRef "M_C_DQ<47>") )
				( member ( signalRef "M_C_DQ<48>") )
				( member ( signalRef "M_C_DQ<49>") )
				( member ( signalRef "M_C_DQ<50>") )
				( member ( signalRef "M_C_DQ<51>") )
				( member ( signalRef "M_C_DQ<52>") )
				( member ( signalRef "M_C_DQ<53>") )
				( member ( signalRef "M_C_DQ<54>") )
				( member ( signalRef "M_C_DQ<55>") )
				( member ( signalRef "M_C_DQ<56>") )
				( member ( signalRef "M_C_DQ<57>") )
				( member ( signalRef "M_C_DQ<58>") )
				( member ( signalRef "M_C_DQ<59>") )
				( member ( signalRef "M_C_DQ<60>") )
				( member ( signalRef "M_C_DQ<61>") )
				( member ( signalRef "M_C_DQ<62>") )
				( member ( signalRef "M_C_DQ<63>") )
				( objectStatus "@baseboard_fab2_lib.baseboard_fab2(sch_1):m_c_dq" )
			)
			( bus "M_C_DQS_DN"
				( memberType ( signal ) )
				( member ( signalRef "M_C_DQS_DN<0>") )
				( member ( signalRef "M_C_DQS_DN<1>") )
				( member ( signalRef "M_C_DQS_DN<2>") )
				( member ( signalRef "M_C_DQS_DN<3>") )
				( member ( signalRef "M_C_DQS_DN<4>") )
				( member ( signalRef "M_C_DQS_DN<5>") )
				( member ( signalRef "M_C_DQS_DN<6>") )
				( member ( signalRef "M_C_DQS_DN<7>") )
				( member ( signalRef "M_C_DQS_DN<8>") )
				( member ( signalRef "M_C_DQS_DN<9>") )
				( member ( signalRef "M_C_DQS_DN<10>") )
				( member ( signalRef "M_C_DQS_DN<11>") )
				( member ( signalRef "M_C_DQS_DN<12>") )
				( member ( signalRef "M_C_DQS_DN<13>") )
				( member ( signalRef "M_C_DQS_DN<14>") )
				( member ( signalRef "M_C_DQS_DN<15>") )
				( member ( signalRef "M_C_DQS_DN<16>") )
				( member ( signalRef "M_C_DQS_DN<17>") )
				( objectStatus "@baseboard_fab2_lib.baseboard_fab2(sch_1):m_c_dqs_dn" )
			)
			( bus "M_C_DQS_DP"
				( memberType ( signal ) )
				( member ( signalRef "M_C_DQS_DP<0>") )
				( member ( signalRef "M_C_DQS_DP<1>") )
				( member ( signalRef "M_C_DQS_DP<2>") )
				( member ( signalRef "M_C_DQS_DP<3>") )
				( member ( signalRef "M_C_DQS_DP<4>") )
				( member ( signalRef "M_C_DQS_DP<5>") )
				( member ( signalRef "M_C_DQS_DP<6>") )
				( member ( signalRef "M_C_DQS_DP<7>") )
				( member ( signalRef "M_C_DQS_DP<8>") )
				( member ( signalRef "M_C_DQS_DP<9>") )
				( member ( signalRef "M_C_DQS_DP<10>") )
				( member ( signalRef "M_C_DQS_DP<11>") )
				( member ( signalRef "M_C_DQS_DP<12>") )
				( member ( signalRef "M_C_DQS_DP<13>") )
				( member ( signalRef "M_C_DQS_DP<14>") )
				( member ( signalRef "M_C_DQS_DP<15>") )
				( member ( signalRef "M_C_DQS_DP<16>") )
				( member ( signalRef "M_C_DQS_DP<17>") )
				( objectStatus "@baseboard_fab2_lib.baseboard_fab2(sch_1):m_c_dqs_dp" )
			)
			( bus "M_C_ECC"
				( memberType ( signal ) )
				( member ( signalRef "M_C_ECC<0>") )
				( member ( signalRef "M_C_ECC<1>") )
				( member ( signalRef "M_C_ECC<2>") )
				( member ( signalRef "M_C_ECC<3>") )
				( member ( signalRef "M_C_ECC<4>") )
				( member ( signalRef "M_C_ECC<5>") )
				( member ( signalRef "M_C_ECC<6>") )
				( member ( signalRef "M_C_ECC<7>") )
				( objectStatus "@baseboard_fab2_lib.baseboard_fab2(sch_1):m_c_ecc" )
			)
			( bus "M_C_MA"
				( memberType ( signal ) )
				( member ( signalRef "M_C_MA<0>") )
				( member ( signalRef "M_C_MA<1>") )
				( member ( signalRef "M_C_MA<2>") )
				( member ( signalRef "M_C_MA<3>") )
				( member ( signalRef "M_C_MA<4>") )
				( member ( signalRef "M_C_MA<5>") )
				( member ( signalRef "M_C_MA<6>") )
				( member ( signalRef "M_C_MA<7>") )
				( member ( signalRef "M_C_MA<8>") )
				( member ( signalRef "M_C_MA<9>") )
				( member ( signalRef "M_C_MA<10>") )
				( member ( signalRef "M_C_MA<11>") )
				( member ( signalRef "M_C_MA<12>") )
				( member ( signalRef "M_C_MA<13>") )
				( member ( signalRef "M_C_MA<14>") )
				( member ( signalRef "M_C_MA<15>") )
				( member ( signalRef "M_C_MA<16>") )
				( member ( signalRef "M_C_MA<17>") )
				( objectStatus "@baseboard_fab2_lib.baseboard_fab2(sch_1):m_c_ma" )
			)
			( bus "M_C_ODT"
				( memberType ( signal ) )
				( member ( signalRef "M_C_ODT<0>") )
				( member ( signalRef "M_C_ODT<1>") )
				( member ( signalRef "M_C_ODT<2>") )
				( member ( signalRef "M_C_ODT<3>") )
				( objectStatus "@baseboard_fab2_lib.baseboard_fab2(sch_1):m_c_odt" )
			)
			( bus "M_D_BA"
				( memberType ( signal ) )
				( member ( signalRef "M_D_BA<0>") )
				( member ( signalRef "M_D_BA<1>") )
				( objectStatus "@baseboard_fab2_lib.baseboard_fab2(sch_1):m_d_ba" )
			)
			( bus "M_D_BG"
				( memberType ( signal ) )
				( member ( signalRef "M_D_BG<0>") )
				( member ( signalRef "M_D_BG<1>") )
				( objectStatus "@baseboard_fab2_lib.baseboard_fab2(sch_1):m_d_bg" )
			)
			( bus "M_D_C"
				( memberType ( signal ) )
				( member ( signalRef "M_D_C<2>") )
				( objectStatus "@baseboard_fab2_lib.baseboard_fab2(sch_1):m_d_c" )
			)
			( bus "M_D_CKE"
				( memberType ( signal ) )
				( member ( signalRef "M_D_CKE<0>") )
				( member ( signalRef "M_D_CKE<1>") )
				( member ( signalRef "M_D_CKE<2>") )
				( member ( signalRef "M_D_CKE<3>") )
				( objectStatus "@baseboard_fab2_lib.baseboard_fab2(sch_1):m_d_cke" )
			)
			( bus "M_D_CLK_DN"
				( memberType ( signal ) )
				( member ( signalRef "M_D_CLK_DN<0>") )
				( member ( signalRef "M_D_CLK_DN<1>") )
				( member ( signalRef "M_D_CLK_DN<2>") )
				( member ( signalRef "M_D_CLK_DN<3>") )
				( objectStatus "@baseboard_fab2_lib.baseboard_fab2(sch_1):m_d_clk_dn" )
			)
			( bus "M_D_CLK_DP"
				( memberType ( signal ) )
				( member ( signalRef "M_D_CLK_DP<0>") )
				( member ( signalRef "M_D_CLK_DP<1>") )
				( member ( signalRef "M_D_CLK_DP<2>") )
				( member ( signalRef "M_D_CLK_DP<3>") )
				( objectStatus "@baseboard_fab2_lib.baseboard_fab2(sch_1):m_d_clk_dp" )
			)
			( bus "M_D_CS_N"
				( memberType ( signal ) )
				( member ( signalRef "M_D_CS_N<0>") )
				( member ( signalRef "M_D_CS_N<1>") )
				( member ( signalRef "M_D_CS_N<2>") )
				( member ( signalRef "M_D_CS_N<3>") )
				( member ( signalRef "M_D_CS_N<4>") )
				( member ( signalRef "M_D_CS_N<5>") )
				( member ( signalRef "M_D_CS_N<6>") )
				( member ( signalRef "M_D_CS_N<7>") )
				( objectStatus "@baseboard_fab2_lib.baseboard_fab2(sch_1):m_d_cs_n" )
			)
			( bus "M_D_DQ"
				( memberType ( signal ) )
				( member ( signalRef "M_D_DQ<0>") )
				( member ( signalRef "M_D_DQ<1>") )
				( member ( signalRef "M_D_DQ<2>") )
				( member ( signalRef "M_D_DQ<3>") )
				( member ( signalRef "M_D_DQ<4>") )
				( member ( signalRef "M_D_DQ<5>") )
				( member ( signalRef "M_D_DQ<6>") )
				( member ( signalRef "M_D_DQ<7>") )
				( member ( signalRef "M_D_DQ<8>") )
				( member ( signalRef "M_D_DQ<9>") )
				( member ( signalRef "M_D_DQ<10>") )
				( member ( signalRef "M_D_DQ<11>") )
				( member ( signalRef "M_D_DQ<12>") )
				( member ( signalRef "M_D_DQ<13>") )
				( member ( signalRef "M_D_DQ<14>") )
				( member ( signalRef "M_D_DQ<15>") )
				( member ( signalRef "M_D_DQ<16>") )
				( member ( signalRef "M_D_DQ<17>") )
				( member ( signalRef "M_D_DQ<18>") )
				( member ( signalRef "M_D_DQ<19>") )
				( member ( signalRef "M_D_DQ<20>") )
				( member ( signalRef "M_D_DQ<21>") )
				( member ( signalRef "M_D_DQ<22>") )
				( member ( signalRef "M_D_DQ<23>") )
				( member ( signalRef "M_D_DQ<24>") )
				( member ( signalRef "M_D_DQ<25>") )
				( member ( signalRef "M_D_DQ<26>") )
				( member ( signalRef "M_D_DQ<27>") )
				( member ( signalRef "M_D_DQ<28>") )
				( member ( signalRef "M_D_DQ<29>") )
				( member ( signalRef "M_D_DQ<30>") )
				( member ( signalRef "M_D_DQ<31>") )
				( member ( signalRef "M_D_DQ<32>") )
				( member ( signalRef "M_D_DQ<33>") )
				( member ( signalRef "M_D_DQ<34>") )
				( member ( signalRef "M_D_DQ<35>") )
				( member ( signalRef "M_D_DQ<36>") )
				( member ( signalRef "M_D_DQ<37>") )
				( member ( signalRef "M_D_DQ<38>") )
				( member ( signalRef "M_D_DQ<39>") )
				( member ( signalRef "M_D_DQ<40>") )
				( member ( signalRef "M_D_DQ<41>") )
				( member ( signalRef "M_D_DQ<42>") )
				( member ( signalRef "M_D_DQ<43>") )
				( member ( signalRef "M_D_DQ<44>") )
				( member ( signalRef "M_D_DQ<45>") )
				( member ( signalRef "M_D_DQ<46>") )
				( member ( signalRef "M_D_DQ<47>") )
				( member ( signalRef "M_D_DQ<48>") )
				( member ( signalRef "M_D_DQ<49>") )
				( member ( signalRef "M_D_DQ<50>") )
				( member ( signalRef "M_D_DQ<51>") )
				( member ( signalRef "M_D_DQ<52>") )
				( member ( signalRef "M_D_DQ<53>") )
				( member ( signalRef "M_D_DQ<54>") )
				( member ( signalRef "M_D_DQ<55>") )
				( member ( signalRef "M_D_DQ<56>") )
				( member ( signalRef "M_D_DQ<57>") )
				( member ( signalRef "M_D_DQ<58>") )
				( member ( signalRef "M_D_DQ<59>") )
				( member ( signalRef "M_D_DQ<60>") )
				( member ( signalRef "M_D_DQ<61>") )
				( member ( signalRef "M_D_DQ<62>") )
				( member ( signalRef "M_D_DQ<63>") )
				( objectStatus "@baseboard_fab2_lib.baseboard_fab2(sch_1):m_d_dq" )
			)
			( bus "M_D_DQS_DN"
				( memberType ( signal ) )
				( member ( signalRef "M_D_DQS_DN<0>") )
				( member ( signalRef "M_D_DQS_DN<1>") )
				( member ( signalRef "M_D_DQS_DN<2>") )
				( member ( signalRef "M_D_DQS_DN<3>") )
				( member ( signalRef "M_D_DQS_DN<4>") )
				( member ( signalRef "M_D_DQS_DN<5>") )
				( member ( signalRef "M_D_DQS_DN<6>") )
				( member ( signalRef "M_D_DQS_DN<7>") )
				( member ( signalRef "M_D_DQS_DN<8>") )
				( member ( signalRef "M_D_DQS_DN<9>") )
				( member ( signalRef "M_D_DQS_DN<10>") )
				( member ( signalRef "M_D_DQS_DN<11>") )
				( member ( signalRef "M_D_DQS_DN<12>") )
				( member ( signalRef "M_D_DQS_DN<13>") )
				( member ( signalRef "M_D_DQS_DN<14>") )
				( member ( signalRef "M_D_DQS_DN<15>") )
				( member ( signalRef "M_D_DQS_DN<16>") )
				( member ( signalRef "M_D_DQS_DN<17>") )
				( objectStatus "@baseboard_fab2_lib.baseboard_fab2(sch_1):m_d_dqs_dn" )
			)
			( bus "M_D_DQS_DP"
				( memberType ( signal ) )
				( member ( signalRef "M_D_DQS_DP<0>") )
				( member ( signalRef "M_D_DQS_DP<1>") )
				( member ( signalRef "M_D_DQS_DP<2>") )
				( member ( signalRef "M_D_DQS_DP<3>") )
				( member ( signalRef "M_D_DQS_DP<4>") )
				( member ( signalRef "M_D_DQS_DP<5>") )
				( member ( signalRef "M_D_DQS_DP<6>") )
				( member ( signalRef "M_D_DQS_DP<7>") )
				( member ( signalRef "M_D_DQS_DP<8>") )
				( member ( signalRef "M_D_DQS_DP<9>") )
				( member ( signalRef "M_D_DQS_DP<10>") )
				( member ( signalRef "M_D_DQS_DP<11>") )
				( member ( signalRef "M_D_DQS_DP<12>") )
				( member ( signalRef "M_D_DQS_DP<13>") )
				( member ( signalRef "M_D_DQS_DP<14>") )
				( member ( signalRef "M_D_DQS_DP<15>") )
				( member ( signalRef "M_D_DQS_DP<16>") )
				( member ( signalRef "M_D_DQS_DP<17>") )
				( objectStatus "@baseboard_fab2_lib.baseboard_fab2(sch_1):m_d_dqs_dp" )
			)
			( bus "M_D_ECC"
				( memberType ( signal ) )
				( member ( signalRef "M_D_ECC<0>") )
				( member ( signalRef "M_D_ECC<1>") )
				( member ( signalRef "M_D_ECC<2>") )
				( member ( signalRef "M_D_ECC<3>") )
				( member ( signalRef "M_D_ECC<4>") )
				( member ( signalRef "M_D_ECC<5>") )
				( member ( signalRef "M_D_ECC<6>") )
				( member ( signalRef "M_D_ECC<7>") )
				( objectStatus "@baseboard_fab2_lib.baseboard_fab2(sch_1):m_d_ecc" )
			)
			( bus "M_D_MA"
				( memberType ( signal ) )
				( member ( signalRef "M_D_MA<0>") )
				( member ( signalRef "M_D_MA<1>") )
				( member ( signalRef "M_D_MA<2>") )
				( member ( signalRef "M_D_MA<3>") )
				( member ( signalRef "M_D_MA<4>") )
				( member ( signalRef "M_D_MA<5>") )
				( member ( signalRef "M_D_MA<6>") )
				( member ( signalRef "M_D_MA<7>") )
				( member ( signalRef "M_D_MA<8>") )
				( member ( signalRef "M_D_MA<9>") )
				( member ( signalRef "M_D_MA<10>") )
				( member ( signalRef "M_D_MA<11>") )
				( member ( signalRef "M_D_MA<12>") )
				( member ( signalRef "M_D_MA<13>") )
				( member ( signalRef "M_D_MA<14>") )
				( member ( signalRef "M_D_MA<15>") )
				( member ( signalRef "M_D_MA<16>") )
				( member ( signalRef "M_D_MA<17>") )
				( objectStatus "@baseboard_fab2_lib.baseboard_fab2(sch_1):m_d_ma" )
			)
			( bus "M_D_ODT"
				( memberType ( signal ) )
				( member ( signalRef "M_D_ODT<0>") )
				( member ( signalRef "M_D_ODT<1>") )
				( member ( signalRef "M_D_ODT<2>") )
				( member ( signalRef "M_D_ODT<3>") )
				( objectStatus "@baseboard_fab2_lib.baseboard_fab2(sch_1):m_d_odt" )
			)
			( bus "M_E_BA"
				( memberType ( signal ) )
				( member ( signalRef "M_E_BA<0>") )
				( member ( signalRef "M_E_BA<1>") )
				( objectStatus "@baseboard_fab2_lib.baseboard_fab2(sch_1):m_e_ba" )
			)
			( bus "M_E_BG"
				( memberType ( signal ) )
				( member ( signalRef "M_E_BG<0>") )
				( member ( signalRef "M_E_BG<1>") )
				( objectStatus "@baseboard_fab2_lib.baseboard_fab2(sch_1):m_e_bg" )
			)
			( bus "M_E_C"
				( memberType ( signal ) )
				( member ( signalRef "M_E_C<2>") )
				( objectStatus "@baseboard_fab2_lib.baseboard_fab2(sch_1):m_e_c" )
			)
			( bus "M_E_CKE"
				( memberType ( signal ) )
				( member ( signalRef "M_E_CKE<0>") )
				( member ( signalRef "M_E_CKE<1>") )
				( member ( signalRef "M_E_CKE<2>") )
				( member ( signalRef "M_E_CKE<3>") )
				( objectStatus "@baseboard_fab2_lib.baseboard_fab2(sch_1):m_e_cke" )
			)
			( bus "M_E_CLK_DN"
				( memberType ( signal ) )
				( member ( signalRef "M_E_CLK_DN<0>") )
				( member ( signalRef "M_E_CLK_DN<1>") )
				( member ( signalRef "M_E_CLK_DN<2>") )
				( member ( signalRef "M_E_CLK_DN<3>") )
				( objectStatus "@baseboard_fab2_lib.baseboard_fab2(sch_1):m_e_clk_dn" )
			)
			( bus "M_E_CLK_DP"
				( memberType ( signal ) )
				( member ( signalRef "M_E_CLK_DP<0>") )
				( member ( signalRef "M_E_CLK_DP<1>") )
				( member ( signalRef "M_E_CLK_DP<2>") )
				( member ( signalRef "M_E_CLK_DP<3>") )
				( objectStatus "@baseboard_fab2_lib.baseboard_fab2(sch_1):m_e_clk_dp" )
			)
			( bus "M_E_CS_N"
				( memberType ( signal ) )
				( member ( signalRef "M_E_CS_N<0>") )
				( member ( signalRef "M_E_CS_N<1>") )
				( member ( signalRef "M_E_CS_N<2>") )
				( member ( signalRef "M_E_CS_N<3>") )
				( member ( signalRef "M_E_CS_N<4>") )
				( member ( signalRef "M_E_CS_N<5>") )
				( member ( signalRef "M_E_CS_N<6>") )
				( member ( signalRef "M_E_CS_N<7>") )
				( objectStatus "@baseboard_fab2_lib.baseboard_fab2(sch_1):m_e_cs_n" )
			)
			( bus "M_E_DQ"
				( memberType ( signal ) )
				( member ( signalRef "M_E_DQ<0>") )
				( member ( signalRef "M_E_DQ<1>") )
				( member ( signalRef "M_E_DQ<2>") )
				( member ( signalRef "M_E_DQ<3>") )
				( member ( signalRef "M_E_DQ<4>") )
				( member ( signalRef "M_E_DQ<5>") )
				( member ( signalRef "M_E_DQ<6>") )
				( member ( signalRef "M_E_DQ<7>") )
				( member ( signalRef "M_E_DQ<8>") )
				( member ( signalRef "M_E_DQ<9>") )
				( member ( signalRef "M_E_DQ<10>") )
				( member ( signalRef "M_E_DQ<11>") )
				( member ( signalRef "M_E_DQ<12>") )
				( member ( signalRef "M_E_DQ<13>") )
				( member ( signalRef "M_E_DQ<14>") )
				( member ( signalRef "M_E_DQ<15>") )
				( member ( signalRef "M_E_DQ<16>") )
				( member ( signalRef "M_E_DQ<17>") )
				( member ( signalRef "M_E_DQ<18>") )
				( member ( signalRef "M_E_DQ<19>") )
				( member ( signalRef "M_E_DQ<20>") )
				( member ( signalRef "M_E_DQ<21>") )
				( member ( signalRef "M_E_DQ<22>") )
				( member ( signalRef "M_E_DQ<23>") )
				( member ( signalRef "M_E_DQ<24>") )
				( member ( signalRef "M_E_DQ<25>") )
				( member ( signalRef "M_E_DQ<26>") )
				( member ( signalRef "M_E_DQ<27>") )
				( member ( signalRef "M_E_DQ<28>") )
				( member ( signalRef "M_E_DQ<29>") )
				( member ( signalRef "M_E_DQ<30>") )
				( member ( signalRef "M_E_DQ<31>") )
				( member ( signalRef "M_E_DQ<32>") )
				( member ( signalRef "M_E_DQ<33>") )
				( member ( signalRef "M_E_DQ<34>") )
				( member ( signalRef "M_E_DQ<35>") )
				( member ( signalRef "M_E_DQ<36>") )
				( member ( signalRef "M_E_DQ<37>") )
				( member ( signalRef "M_E_DQ<38>") )
				( member ( signalRef "M_E_DQ<39>") )
				( member ( signalRef "M_E_DQ<40>") )
				( member ( signalRef "M_E_DQ<41>") )
				( member ( signalRef "M_E_DQ<42>") )
				( member ( signalRef "M_E_DQ<43>") )
				( member ( signalRef "M_E_DQ<44>") )
				( member ( signalRef "M_E_DQ<45>") )
				( member ( signalRef "M_E_DQ<46>") )
				( member ( signalRef "M_E_DQ<47>") )
				( member ( signalRef "M_E_DQ<48>") )
				( member ( signalRef "M_E_DQ<49>") )
				( member ( signalRef "M_E_DQ<50>") )
				( member ( signalRef "M_E_DQ<51>") )
				( member ( signalRef "M_E_DQ<52>") )
				( member ( signalRef "M_E_DQ<53>") )
				( member ( signalRef "M_E_DQ<54>") )
				( member ( signalRef "M_E_DQ<55>") )
				( member ( signalRef "M_E_DQ<56>") )
				( member ( signalRef "M_E_DQ<57>") )
				( member ( signalRef "M_E_DQ<58>") )
				( member ( signalRef "M_E_DQ<59>") )
				( member ( signalRef "M_E_DQ<60>") )
				( member ( signalRef "M_E_DQ<61>") )
				( member ( signalRef "M_E_DQ<62>") )
				( member ( signalRef "M_E_DQ<63>") )
				( objectStatus "@baseboard_fab2_lib.baseboard_fab2(sch_1):m_e_dq" )
			)
			( bus "M_E_DQS_DN"
				( memberType ( signal ) )
				( member ( signalRef "M_E_DQS_DN<0>") )
				( member ( signalRef "M_E_DQS_DN<1>") )
				( member ( signalRef "M_E_DQS_DN<2>") )
				( member ( signalRef "M_E_DQS_DN<3>") )
				( member ( signalRef "M_E_DQS_DN<4>") )
				( member ( signalRef "M_E_DQS_DN<5>") )
				( member ( signalRef "M_E_DQS_DN<6>") )
				( member ( signalRef "M_E_DQS_DN<7>") )
				( member ( signalRef "M_E_DQS_DN<8>") )
				( member ( signalRef "M_E_DQS_DN<9>") )
				( member ( signalRef "M_E_DQS_DN<10>") )
				( member ( signalRef "M_E_DQS_DN<11>") )
				( member ( signalRef "M_E_DQS_DN<12>") )
				( member ( signalRef "M_E_DQS_DN<13>") )
				( member ( signalRef "M_E_DQS_DN<14>") )
				( member ( signalRef "M_E_DQS_DN<15>") )
				( member ( signalRef "M_E_DQS_DN<16>") )
				( member ( signalRef "M_E_DQS_DN<17>") )
				( objectStatus "@baseboard_fab2_lib.baseboard_fab2(sch_1):m_e_dqs_dn" )
			)
			( bus "M_E_DQS_DP"
				( memberType ( signal ) )
				( member ( signalRef "M_E_DQS_DP<0>") )
				( member ( signalRef "M_E_DQS_DP<1>") )
				( member ( signalRef "M_E_DQS_DP<2>") )
				( member ( signalRef "M_E_DQS_DP<3>") )
				( member ( signalRef "M_E_DQS_DP<4>") )
				( member ( signalRef "M_E_DQS_DP<5>") )
				( member ( signalRef "M_E_DQS_DP<6>") )
				( member ( signalRef "M_E_DQS_DP<7>") )
				( member ( signalRef "M_E_DQS_DP<8>") )
				( member ( signalRef "M_E_DQS_DP<9>") )
				( member ( signalRef "M_E_DQS_DP<10>") )
				( member ( signalRef "M_E_DQS_DP<11>") )
				( member ( signalRef "M_E_DQS_DP<12>") )
				( member ( signalRef "M_E_DQS_DP<13>") )
				( member ( signalRef "M_E_DQS_DP<14>") )
				( member ( signalRef "M_E_DQS_DP<15>") )
				( member ( signalRef "M_E_DQS_DP<16>") )
				( member ( signalRef "M_E_DQS_DP<17>") )
				( objectStatus "@baseboard_fab2_lib.baseboard_fab2(sch_1):m_e_dqs_dp" )
			)
			( bus "M_E_ECC"
				( memberType ( signal ) )
				( member ( signalRef "M_E_ECC<0>") )
				( member ( signalRef "M_E_ECC<1>") )
				( member ( signalRef "M_E_ECC<2>") )
				( member ( signalRef "M_E_ECC<3>") )
				( member ( signalRef "M_E_ECC<4>") )
				( member ( signalRef "M_E_ECC<5>") )
				( member ( signalRef "M_E_ECC<6>") )
				( member ( signalRef "M_E_ECC<7>") )
				( objectStatus "@baseboard_fab2_lib.baseboard_fab2(sch_1):m_e_ecc" )
			)
			( bus "M_E_MA"
				( memberType ( signal ) )
				( member ( signalRef "M_E_MA<0>") )
				( member ( signalRef "M_E_MA<1>") )
				( member ( signalRef "M_E_MA<2>") )
				( member ( signalRef "M_E_MA<3>") )
				( member ( signalRef "M_E_MA<4>") )
				( member ( signalRef "M_E_MA<5>") )
				( member ( signalRef "M_E_MA<6>") )
				( member ( signalRef "M_E_MA<7>") )
				( member ( signalRef "M_E_MA<8>") )
				( member ( signalRef "M_E_MA<9>") )
				( member ( signalRef "M_E_MA<10>") )
				( member ( signalRef "M_E_MA<11>") )
				( member ( signalRef "M_E_MA<12>") )
				( member ( signalRef "M_E_MA<13>") )
				( member ( signalRef "M_E_MA<14>") )
				( member ( signalRef "M_E_MA<15>") )
				( member ( signalRef "M_E_MA<16>") )
				( member ( signalRef "M_E_MA<17>") )
				( objectStatus "@baseboard_fab2_lib.baseboard_fab2(sch_1):m_e_ma" )
			)
			( bus "M_E_ODT"
				( memberType ( signal ) )
				( member ( signalRef "M_E_ODT<0>") )
				( member ( signalRef "M_E_ODT<1>") )
				( member ( signalRef "M_E_ODT<2>") )
				( member ( signalRef "M_E_ODT<3>") )
				( objectStatus "@baseboard_fab2_lib.baseboard_fab2(sch_1):m_e_odt" )
			)
			( bus "M_F_BA"
				( memberType ( signal ) )
				( member ( signalRef "M_F_BA<0>") )
				( member ( signalRef "M_F_BA<1>") )
				( objectStatus "@baseboard_fab2_lib.baseboard_fab2(sch_1):m_f_ba" )
			)
			( bus "M_F_BG"
				( memberType ( signal ) )
				( member ( signalRef "M_F_BG<0>") )
				( member ( signalRef "M_F_BG<1>") )
				( objectStatus "@baseboard_fab2_lib.baseboard_fab2(sch_1):m_f_bg" )
			)
			( bus "M_F_C"
				( memberType ( signal ) )
				( member ( signalRef "M_F_C<2>") )
				( objectStatus "@baseboard_fab2_lib.baseboard_fab2(sch_1):m_f_c" )
			)
			( bus "M_F_CKE"
				( memberType ( signal ) )
				( member ( signalRef "M_F_CKE<0>") )
				( member ( signalRef "M_F_CKE<1>") )
				( member ( signalRef "M_F_CKE<2>") )
				( member ( signalRef "M_F_CKE<3>") )
				( objectStatus "@baseboard_fab2_lib.baseboard_fab2(sch_1):m_f_cke" )
			)
			( bus "M_F_CLK_DN"
				( memberType ( signal ) )
				( member ( signalRef "M_F_CLK_DN<0>") )
				( member ( signalRef "M_F_CLK_DN<1>") )
				( member ( signalRef "M_F_CLK_DN<2>") )
				( member ( signalRef "M_F_CLK_DN<3>") )
				( objectStatus "@baseboard_fab2_lib.baseboard_fab2(sch_1):m_f_clk_dn" )
			)
			( bus "M_F_CLK_DP"
				( memberType ( signal ) )
				( member ( signalRef "M_F_CLK_DP<0>") )
				( member ( signalRef "M_F_CLK_DP<1>") )
				( member ( signalRef "M_F_CLK_DP<2>") )
				( member ( signalRef "M_F_CLK_DP<3>") )
				( objectStatus "@baseboard_fab2_lib.baseboard_fab2(sch_1):m_f_clk_dp" )
			)
			( bus "M_F_CS_N"
				( memberType ( signal ) )
				( member ( signalRef "M_F_CS_N<0>") )
				( member ( signalRef "M_F_CS_N<1>") )
				( member ( signalRef "M_F_CS_N<2>") )
				( member ( signalRef "M_F_CS_N<3>") )
				( member ( signalRef "M_F_CS_N<4>") )
				( member ( signalRef "M_F_CS_N<5>") )
				( member ( signalRef "M_F_CS_N<6>") )
				( member ( signalRef "M_F_CS_N<7>") )
				( objectStatus "@baseboard_fab2_lib.baseboard_fab2(sch_1):m_f_cs_n" )
			)
			( bus "M_F_DQ"
				( memberType ( signal ) )
				( member ( signalRef "M_F_DQ<0>") )
				( member ( signalRef "M_F_DQ<1>") )
				( member ( signalRef "M_F_DQ<2>") )
				( member ( signalRef "M_F_DQ<3>") )
				( member ( signalRef "M_F_DQ<4>") )
				( member ( signalRef "M_F_DQ<5>") )
				( member ( signalRef "M_F_DQ<6>") )
				( member ( signalRef "M_F_DQ<7>") )
				( member ( signalRef "M_F_DQ<8>") )
				( member ( signalRef "M_F_DQ<9>") )
				( member ( signalRef "M_F_DQ<10>") )
				( member ( signalRef "M_F_DQ<11>") )
				( member ( signalRef "M_F_DQ<12>") )
				( member ( signalRef "M_F_DQ<13>") )
				( member ( signalRef "M_F_DQ<14>") )
				( member ( signalRef "M_F_DQ<15>") )
				( member ( signalRef "M_F_DQ<16>") )
				( member ( signalRef "M_F_DQ<17>") )
				( member ( signalRef "M_F_DQ<18>") )
				( member ( signalRef "M_F_DQ<19>") )
				( member ( signalRef "M_F_DQ<20>") )
				( member ( signalRef "M_F_DQ<21>") )
				( member ( signalRef "M_F_DQ<22>") )
				( member ( signalRef "M_F_DQ<23>") )
				( member ( signalRef "M_F_DQ<24>") )
				( member ( signalRef "M_F_DQ<25>") )
				( member ( signalRef "M_F_DQ<26>") )
				( member ( signalRef "M_F_DQ<27>") )
				( member ( signalRef "M_F_DQ<28>") )
				( member ( signalRef "M_F_DQ<29>") )
				( member ( signalRef "M_F_DQ<30>") )
				( member ( signalRef "M_F_DQ<31>") )
				( member ( signalRef "M_F_DQ<32>") )
				( member ( signalRef "M_F_DQ<33>") )
				( member ( signalRef "M_F_DQ<34>") )
				( member ( signalRef "M_F_DQ<35>") )
				( member ( signalRef "M_F_DQ<36>") )
				( member ( signalRef "M_F_DQ<37>") )
				( member ( signalRef "M_F_DQ<38>") )
				( member ( signalRef "M_F_DQ<39>") )
				( member ( signalRef "M_F_DQ<40>") )
				( member ( signalRef "M_F_DQ<41>") )
				( member ( signalRef "M_F_DQ<42>") )
				( member ( signalRef "M_F_DQ<43>") )
				( member ( signalRef "M_F_DQ<44>") )
				( member ( signalRef "M_F_DQ<45>") )
				( member ( signalRef "M_F_DQ<46>") )
				( member ( signalRef "M_F_DQ<47>") )
				( member ( signalRef "M_F_DQ<48>") )
				( member ( signalRef "M_F_DQ<49>") )
				( member ( signalRef "M_F_DQ<50>") )
				( member ( signalRef "M_F_DQ<51>") )
				( member ( signalRef "M_F_DQ<52>") )
				( member ( signalRef "M_F_DQ<53>") )
				( member ( signalRef "M_F_DQ<54>") )
				( member ( signalRef "M_F_DQ<55>") )
				( member ( signalRef "M_F_DQ<56>") )
				( member ( signalRef "M_F_DQ<57>") )
				( member ( signalRef "M_F_DQ<58>") )
				( member ( signalRef "M_F_DQ<59>") )
				( member ( signalRef "M_F_DQ<60>") )
				( member ( signalRef "M_F_DQ<61>") )
				( member ( signalRef "M_F_DQ<62>") )
				( member ( signalRef "M_F_DQ<63>") )
				( objectStatus "@baseboard_fab2_lib.baseboard_fab2(sch_1):m_f_dq" )
			)
			( bus "M_F_DQS_DN"
				( memberType ( signal ) )
				( member ( signalRef "M_F_DQS_DN<0>") )
				( member ( signalRef "M_F_DQS_DN<1>") )
				( member ( signalRef "M_F_DQS_DN<2>") )
				( member ( signalRef "M_F_DQS_DN<3>") )
				( member ( signalRef "M_F_DQS_DN<4>") )
				( member ( signalRef "M_F_DQS_DN<5>") )
				( member ( signalRef "M_F_DQS_DN<6>") )
				( member ( signalRef "M_F_DQS_DN<7>") )
				( member ( signalRef "M_F_DQS_DN<8>") )
				( member ( signalRef "M_F_DQS_DN<9>") )
				( member ( signalRef "M_F_DQS_DN<10>") )
				( member ( signalRef "M_F_DQS_DN<11>") )
				( member ( signalRef "M_F_DQS_DN<12>") )
				( member ( signalRef "M_F_DQS_DN<13>") )
				( member ( signalRef "M_F_DQS_DN<14>") )
				( member ( signalRef "M_F_DQS_DN<15>") )
				( member ( signalRef "M_F_DQS_DN<16>") )
				( member ( signalRef "M_F_DQS_DN<17>") )
				( objectStatus "@baseboard_fab2_lib.baseboard_fab2(sch_1):m_f_dqs_dn" )
			)
			( bus "M_F_DQS_DP"
				( memberType ( signal ) )
				( member ( signalRef "M_F_DQS_DP<0>") )
				( member ( signalRef "M_F_DQS_DP<1>") )
				( member ( signalRef "M_F_DQS_DP<2>") )
				( member ( signalRef "M_F_DQS_DP<3>") )
				( member ( signalRef "M_F_DQS_DP<4>") )
				( member ( signalRef "M_F_DQS_DP<5>") )
				( member ( signalRef "M_F_DQS_DP<6>") )
				( member ( signalRef "M_F_DQS_DP<7>") )
				( member ( signalRef "M_F_DQS_DP<8>") )
				( member ( signalRef "M_F_DQS_DP<9>") )
				( member ( signalRef "M_F_DQS_DP<10>") )
				( member ( signalRef "M_F_DQS_DP<11>") )
				( member ( signalRef "M_F_DQS_DP<12>") )
				( member ( signalRef "M_F_DQS_DP<13>") )
				( member ( signalRef "M_F_DQS_DP<14>") )
				( member ( signalRef "M_F_DQS_DP<15>") )
				( member ( signalRef "M_F_DQS_DP<16>") )
				( member ( signalRef "M_F_DQS_DP<17>") )
				( objectStatus "@baseboard_fab2_lib.baseboard_fab2(sch_1):m_f_dqs_dp" )
			)
			( bus "M_F_ECC"
				( memberType ( signal ) )
				( member ( signalRef "M_F_ECC<0>") )
				( member ( signalRef "M_F_ECC<1>") )
				( member ( signalRef "M_F_ECC<2>") )
				( member ( signalRef "M_F_ECC<3>") )
				( member ( signalRef "M_F_ECC<4>") )
				( member ( signalRef "M_F_ECC<5>") )
				( member ( signalRef "M_F_ECC<6>") )
				( member ( signalRef "M_F_ECC<7>") )
				( objectStatus "@baseboard_fab2_lib.baseboard_fab2(sch_1):m_f_ecc" )
			)
			( bus "M_F_MA"
				( memberType ( signal ) )
				( member ( signalRef "M_F_MA<0>") )
				( member ( signalRef "M_F_MA<1>") )
				( member ( signalRef "M_F_MA<2>") )
				( member ( signalRef "M_F_MA<3>") )
				( member ( signalRef "M_F_MA<4>") )
				( member ( signalRef "M_F_MA<5>") )
				( member ( signalRef "M_F_MA<6>") )
				( member ( signalRef "M_F_MA<7>") )
				( member ( signalRef "M_F_MA<8>") )
				( member ( signalRef "M_F_MA<9>") )
				( member ( signalRef "M_F_MA<10>") )
				( member ( signalRef "M_F_MA<11>") )
				( member ( signalRef "M_F_MA<12>") )
				( member ( signalRef "M_F_MA<13>") )
				( member ( signalRef "M_F_MA<14>") )
				( member ( signalRef "M_F_MA<15>") )
				( member ( signalRef "M_F_MA<16>") )
				( member ( signalRef "M_F_MA<17>") )
				( objectStatus "@baseboard_fab2_lib.baseboard_fab2(sch_1):m_f_ma" )
			)
			( bus "M_F_ODT"
				( memberType ( signal ) )
				( member ( signalRef "M_F_ODT<0>") )
				( member ( signalRef "M_F_ODT<1>") )
				( member ( signalRef "M_F_ODT<2>") )
				( member ( signalRef "M_F_ODT<3>") )
				( objectStatus "@baseboard_fab2_lib.baseboard_fab2(sch_1):m_f_odt" )
			)
			( bus "DMI_CPU0_PCH_RX_C_DN"
				( memberType ( signal ) )
				( member ( signalRef "DMI_CPU0_PCH_RX_C_DN<0>") )
				( member ( signalRef "DMI_CPU0_PCH_RX_C_DN<1>") )
				( member ( signalRef "DMI_CPU0_PCH_RX_C_DN<2>") )
				( member ( signalRef "DMI_CPU0_PCH_RX_C_DN<3>") )
				( objectStatus "@baseboard_fab2_lib.baseboard_fab2(sch_1):dmi_cpu0_pch_rx_c_dn" )
			)
			( bus "DMI_CPU0_PCH_RX_C_DP"
				( memberType ( signal ) )
				( member ( signalRef "DMI_CPU0_PCH_RX_C_DP<0>") )
				( member ( signalRef "DMI_CPU0_PCH_RX_C_DP<1>") )
				( member ( signalRef "DMI_CPU0_PCH_RX_C_DP<2>") )
				( member ( signalRef "DMI_CPU0_PCH_RX_C_DP<3>") )
				( objectStatus "@baseboard_fab2_lib.baseboard_fab2(sch_1):dmi_cpu0_pch_rx_c_dp" )
			)
			( bus "DMI_CPU0_PCH_TX_DN"
				( memberType ( signal ) )
				( member ( signalRef "DMI_CPU0_PCH_TX_DN<0>") )
				( member ( signalRef "DMI_CPU0_PCH_TX_DN<1>") )
				( member ( signalRef "DMI_CPU0_PCH_TX_DN<2>") )
				( member ( signalRef "DMI_CPU0_PCH_TX_DN<3>") )
				( objectStatus "@baseboard_fab2_lib.baseboard_fab2(sch_1):dmi_cpu0_pch_tx_dn" )
			)
			( bus "DMI_CPU0_PCH_TX_DP"
				( memberType ( signal ) )
				( member ( signalRef "DMI_CPU0_PCH_TX_DP<0>") )
				( member ( signalRef "DMI_CPU0_PCH_TX_DP<1>") )
				( member ( signalRef "DMI_CPU0_PCH_TX_DP<2>") )
				( member ( signalRef "DMI_CPU0_PCH_TX_DP<3>") )
				( objectStatus "@baseboard_fab2_lib.baseboard_fab2(sch_1):dmi_cpu0_pch_tx_dp" )
			)
			( bus "P3E_CPU0_PE1_PCH_RXN"
				( memberType ( signal ) )
				( member ( signalRef "P3E_CPU0_PE1_PCH_RXN<8>") )
				( member ( signalRef "P3E_CPU0_PE1_PCH_RXN<9>") )
				( member ( signalRef "P3E_CPU0_PE1_PCH_RXN<10>") )
				( member ( signalRef "P3E_CPU0_PE1_PCH_RXN<11>") )
				( member ( signalRef "P3E_CPU0_PE1_PCH_RXN<12>") )
				( member ( signalRef "P3E_CPU0_PE1_PCH_RXN<13>") )
				( member ( signalRef "P3E_CPU0_PE1_PCH_RXN<14>") )
				( member ( signalRef "P3E_CPU0_PE1_PCH_RXN<15>") )
				( member ( signalRef "P3E_CPU0_PE1_PCH_RXN<0>") )
				( member ( signalRef "P3E_CPU0_PE1_PCH_RXN<1>") )
				( member ( signalRef "P3E_CPU0_PE1_PCH_RXN<2>") )
				( member ( signalRef "P3E_CPU0_PE1_PCH_RXN<3>") )
				( member ( signalRef "P3E_CPU0_PE1_PCH_RXN<4>") )
				( member ( signalRef "P3E_CPU0_PE1_PCH_RXN<5>") )
				( member ( signalRef "P3E_CPU0_PE1_PCH_RXN<6>") )
				( member ( signalRef "P3E_CPU0_PE1_PCH_RXN<7>") )
				( objectStatus "@baseboard_fab2_lib.baseboard_fab2(sch_1):p3e_cpu0_pe1_pch_rxn" )
			)
			( bus "P3E_CPU0_PE1_PCH_RXP"
				( memberType ( signal ) )
				( member ( signalRef "P3E_CPU0_PE1_PCH_RXP<8>") )
				( member ( signalRef "P3E_CPU0_PE1_PCH_RXP<9>") )
				( member ( signalRef "P3E_CPU0_PE1_PCH_RXP<10>") )
				( member ( signalRef "P3E_CPU0_PE1_PCH_RXP<11>") )
				( member ( signalRef "P3E_CPU0_PE1_PCH_RXP<12>") )
				( member ( signalRef "P3E_CPU0_PE1_PCH_RXP<13>") )
				( member ( signalRef "P3E_CPU0_PE1_PCH_RXP<14>") )
				( member ( signalRef "P3E_CPU0_PE1_PCH_RXP<15>") )
				( member ( signalRef "P3E_CPU0_PE1_PCH_RXP<0>") )
				( member ( signalRef "P3E_CPU0_PE1_PCH_RXP<1>") )
				( member ( signalRef "P3E_CPU0_PE1_PCH_RXP<2>") )
				( member ( signalRef "P3E_CPU0_PE1_PCH_RXP<3>") )
				( member ( signalRef "P3E_CPU0_PE1_PCH_RXP<4>") )
				( member ( signalRef "P3E_CPU0_PE1_PCH_RXP<5>") )
				( member ( signalRef "P3E_CPU0_PE1_PCH_RXP<6>") )
				( member ( signalRef "P3E_CPU0_PE1_PCH_RXP<7>") )
				( objectStatus "@baseboard_fab2_lib.baseboard_fab2(sch_1):p3e_cpu0_pe1_pch_rxp" )
			)
			( bus "P3E_CPU0_PE1_PCH_TXN"
				( memberType ( signal ) )
				( member ( signalRef "P3E_CPU0_PE1_PCH_TXN<8>") )
				( member ( signalRef "P3E_CPU0_PE1_PCH_TXN<9>") )
				( member ( signalRef "P3E_CPU0_PE1_PCH_TXN<10>") )
				( member ( signalRef "P3E_CPU0_PE1_PCH_TXN<11>") )
				( member ( signalRef "P3E_CPU0_PE1_PCH_TXN<12>") )
				( member ( signalRef "P3E_CPU0_PE1_PCH_TXN<13>") )
				( member ( signalRef "P3E_CPU0_PE1_PCH_TXN<14>") )
				( member ( signalRef "P3E_CPU0_PE1_PCH_TXN<15>") )
				( member ( signalRef "P3E_CPU0_PE1_PCH_TXN<0>") )
				( member ( signalRef "P3E_CPU0_PE1_PCH_TXN<1>") )
				( member ( signalRef "P3E_CPU0_PE1_PCH_TXN<2>") )
				( member ( signalRef "P3E_CPU0_PE1_PCH_TXN<3>") )
				( member ( signalRef "P3E_CPU0_PE1_PCH_TXN<4>") )
				( member ( signalRef "P3E_CPU0_PE1_PCH_TXN<5>") )
				( member ( signalRef "P3E_CPU0_PE1_PCH_TXN<6>") )
				( member ( signalRef "P3E_CPU0_PE1_PCH_TXN<7>") )
				( objectStatus "@baseboard_fab2_lib.baseboard_fab2(sch_1):p3e_cpu0_pe1_pch_txn" )
			)
			( bus "P3E_CPU0_PE1_PCH_TXP"
				( memberType ( signal ) )
				( member ( signalRef "P3E_CPU0_PE1_PCH_TXP<8>") )
				( member ( signalRef "P3E_CPU0_PE1_PCH_TXP<9>") )
				( member ( signalRef "P3E_CPU0_PE1_PCH_TXP<10>") )
				( member ( signalRef "P3E_CPU0_PE1_PCH_TXP<11>") )
				( member ( signalRef "P3E_CPU0_PE1_PCH_TXP<12>") )
				( member ( signalRef "P3E_CPU0_PE1_PCH_TXP<13>") )
				( member ( signalRef "P3E_CPU0_PE1_PCH_TXP<14>") )
				( member ( signalRef "P3E_CPU0_PE1_PCH_TXP<15>") )
				( member ( signalRef "P3E_CPU0_PE1_PCH_TXP<0>") )
				( member ( signalRef "P3E_CPU0_PE1_PCH_TXP<1>") )
				( member ( signalRef "P3E_CPU0_PE1_PCH_TXP<2>") )
				( member ( signalRef "P3E_CPU0_PE1_PCH_TXP<3>") )
				( member ( signalRef "P3E_CPU0_PE1_PCH_TXP<4>") )
				( member ( signalRef "P3E_CPU0_PE1_PCH_TXP<5>") )
				( member ( signalRef "P3E_CPU0_PE1_PCH_TXP<6>") )
				( member ( signalRef "P3E_CPU0_PE1_PCH_TXP<7>") )
				( objectStatus "@baseboard_fab2_lib.baseboard_fab2(sch_1):p3e_cpu0_pe1_pch_txp" )
			)
			( bus "P3E_CPU0_PE1_SS_RXN"
				( memberType ( signal ) )
				( member ( signalRef "P3E_CPU0_PE1_SS_RXN<0>") )
				( member ( signalRef "P3E_CPU0_PE1_SS_RXN<1>") )
				( member ( signalRef "P3E_CPU0_PE1_SS_RXN<2>") )
				( member ( signalRef "P3E_CPU0_PE1_SS_RXN<3>") )
				( member ( signalRef "P3E_CPU0_PE1_SS_RXN<4>") )
				( member ( signalRef "P3E_CPU0_PE1_SS_RXN<5>") )
				( member ( signalRef "P3E_CPU0_PE1_SS_RXN<6>") )
				( member ( signalRef "P3E_CPU0_PE1_SS_RXN<7>") )
				( objectStatus "@baseboard_fab2_lib.baseboard_fab2(sch_1):p3e_cpu0_pe1_ss_rxn" )
			)
			( bus "P3E_CPU0_PE1_SS_RXP"
				( memberType ( signal ) )
				( member ( signalRef "P3E_CPU0_PE1_SS_RXP<0>") )
				( member ( signalRef "P3E_CPU0_PE1_SS_RXP<1>") )
				( member ( signalRef "P3E_CPU0_PE1_SS_RXP<2>") )
				( member ( signalRef "P3E_CPU0_PE1_SS_RXP<3>") )
				( member ( signalRef "P3E_CPU0_PE1_SS_RXP<4>") )
				( member ( signalRef "P3E_CPU0_PE1_SS_RXP<5>") )
				( member ( signalRef "P3E_CPU0_PE1_SS_RXP<6>") )
				( member ( signalRef "P3E_CPU0_PE1_SS_RXP<7>") )
				( objectStatus "@baseboard_fab2_lib.baseboard_fab2(sch_1):p3e_cpu0_pe1_ss_rxp" )
			)
			( bus "P3E_CPU0_PE1_SS_TXN"
				( memberType ( signal ) )
				( member ( signalRef "P3E_CPU0_PE1_SS_TXN<0>") )
				( member ( signalRef "P3E_CPU0_PE1_SS_TXN<1>") )
				( member ( signalRef "P3E_CPU0_PE1_SS_TXN<2>") )
				( member ( signalRef "P3E_CPU0_PE1_SS_TXN<3>") )
				( member ( signalRef "P3E_CPU0_PE1_SS_TXN<4>") )
				( member ( signalRef "P3E_CPU0_PE1_SS_TXN<5>") )
				( member ( signalRef "P3E_CPU0_PE1_SS_TXN<6>") )
				( member ( signalRef "P3E_CPU0_PE1_SS_TXN<7>") )
				( objectStatus "@baseboard_fab2_lib.baseboard_fab2(sch_1):p3e_cpu0_pe1_ss_txn" )
			)
			( bus "P3E_CPU0_PE1_SS_TXP"
				( memberType ( signal ) )
				( member ( signalRef "P3E_CPU0_PE1_SS_TXP<0>") )
				( member ( signalRef "P3E_CPU0_PE1_SS_TXP<1>") )
				( member ( signalRef "P3E_CPU0_PE1_SS_TXP<2>") )
				( member ( signalRef "P3E_CPU0_PE1_SS_TXP<3>") )
				( member ( signalRef "P3E_CPU0_PE1_SS_TXP<4>") )
				( member ( signalRef "P3E_CPU0_PE1_SS_TXP<5>") )
				( member ( signalRef "P3E_CPU0_PE1_SS_TXP<6>") )
				( member ( signalRef "P3E_CPU0_PE1_SS_TXP<7>") )
				( objectStatus "@baseboard_fab2_lib.baseboard_fab2(sch_1):p3e_cpu0_pe1_ss_txp" )
			)
			( bus "P3E_CPU0_PE2_SS_RXN"
				( memberType ( signal ) )
				( member ( signalRef "P3E_CPU0_PE2_SS_RXN<0>") )
				( member ( signalRef "P3E_CPU0_PE2_SS_RXN<1>") )
				( member ( signalRef "P3E_CPU0_PE2_SS_RXN<2>") )
				( member ( signalRef "P3E_CPU0_PE2_SS_RXN<3>") )
				( member ( signalRef "P3E_CPU0_PE2_SS_RXN<4>") )
				( member ( signalRef "P3E_CPU0_PE2_SS_RXN<5>") )
				( member ( signalRef "P3E_CPU0_PE2_SS_RXN<6>") )
				( member ( signalRef "P3E_CPU0_PE2_SS_RXN<7>") )
				( member ( signalRef "P3E_CPU0_PE2_SS_RXN<8>") )
				( member ( signalRef "P3E_CPU0_PE2_SS_RXN<9>") )
				( member ( signalRef "P3E_CPU0_PE2_SS_RXN<10>") )
				( member ( signalRef "P3E_CPU0_PE2_SS_RXN<11>") )
				( member ( signalRef "P3E_CPU0_PE2_SS_RXN<12>") )
				( member ( signalRef "P3E_CPU0_PE2_SS_RXN<13>") )
				( member ( signalRef "P3E_CPU0_PE2_SS_RXN<14>") )
				( member ( signalRef "P3E_CPU0_PE2_SS_RXN<15>") )
				( objectStatus "@baseboard_fab2_lib.baseboard_fab2(sch_1):p3e_cpu0_pe2_ss_rxn" )
			)
			( bus "P3E_CPU0_PE2_SS_RXP"
				( memberType ( signal ) )
				( member ( signalRef "P3E_CPU0_PE2_SS_RXP<0>") )
				( member ( signalRef "P3E_CPU0_PE2_SS_RXP<1>") )
				( member ( signalRef "P3E_CPU0_PE2_SS_RXP<2>") )
				( member ( signalRef "P3E_CPU0_PE2_SS_RXP<3>") )
				( member ( signalRef "P3E_CPU0_PE2_SS_RXP<4>") )
				( member ( signalRef "P3E_CPU0_PE2_SS_RXP<5>") )
				( member ( signalRef "P3E_CPU0_PE2_SS_RXP<6>") )
				( member ( signalRef "P3E_CPU0_PE2_SS_RXP<7>") )
				( member ( signalRef "P3E_CPU0_PE2_SS_RXP<8>") )
				( member ( signalRef "P3E_CPU0_PE2_SS_RXP<9>") )
				( member ( signalRef "P3E_CPU0_PE2_SS_RXP<10>") )
				( member ( signalRef "P3E_CPU0_PE2_SS_RXP<11>") )
				( member ( signalRef "P3E_CPU0_PE2_SS_RXP<12>") )
				( member ( signalRef "P3E_CPU0_PE2_SS_RXP<13>") )
				( member ( signalRef "P3E_CPU0_PE2_SS_RXP<14>") )
				( member ( signalRef "P3E_CPU0_PE2_SS_RXP<15>") )
				( objectStatus "@baseboard_fab2_lib.baseboard_fab2(sch_1):p3e_cpu0_pe2_ss_rxp" )
			)
			( bus "P3E_CPU0_PE2_SS_TXN"
				( memberType ( signal ) )
				( member ( signalRef "P3E_CPU0_PE2_SS_TXN<0>") )
				( member ( signalRef "P3E_CPU0_PE2_SS_TXN<1>") )
				( member ( signalRef "P3E_CPU0_PE2_SS_TXN<2>") )
				( member ( signalRef "P3E_CPU0_PE2_SS_TXN<3>") )
				( member ( signalRef "P3E_CPU0_PE2_SS_TXN<4>") )
				( member ( signalRef "P3E_CPU0_PE2_SS_TXN<5>") )
				( member ( signalRef "P3E_CPU0_PE2_SS_TXN<6>") )
				( member ( signalRef "P3E_CPU0_PE2_SS_TXN<7>") )
				( member ( signalRef "P3E_CPU0_PE2_SS_TXN<8>") )
				( member ( signalRef "P3E_CPU0_PE2_SS_TXN<9>") )
				( member ( signalRef "P3E_CPU0_PE2_SS_TXN<10>") )
				( member ( signalRef "P3E_CPU0_PE2_SS_TXN<11>") )
				( member ( signalRef "P3E_CPU0_PE2_SS_TXN<12>") )
				( member ( signalRef "P3E_CPU0_PE2_SS_TXN<13>") )
				( member ( signalRef "P3E_CPU0_PE2_SS_TXN<14>") )
				( member ( signalRef "P3E_CPU0_PE2_SS_TXN<15>") )
				( objectStatus "@baseboard_fab2_lib.baseboard_fab2(sch_1):p3e_cpu0_pe2_ss_txn" )
			)
			( bus "P3E_CPU0_PE2_SS_TXP"
				( memberType ( signal ) )
				( member ( signalRef "P3E_CPU0_PE2_SS_TXP<0>") )
				( member ( signalRef "P3E_CPU0_PE2_SS_TXP<1>") )
				( member ( signalRef "P3E_CPU0_PE2_SS_TXP<2>") )
				( member ( signalRef "P3E_CPU0_PE2_SS_TXP<3>") )
				( member ( signalRef "P3E_CPU0_PE2_SS_TXP<4>") )
				( member ( signalRef "P3E_CPU0_PE2_SS_TXP<5>") )
				( member ( signalRef "P3E_CPU0_PE2_SS_TXP<6>") )
				( member ( signalRef "P3E_CPU0_PE2_SS_TXP<7>") )
				( member ( signalRef "P3E_CPU0_PE2_SS_TXP<8>") )
				( member ( signalRef "P3E_CPU0_PE2_SS_TXP<9>") )
				( member ( signalRef "P3E_CPU0_PE2_SS_TXP<10>") )
				( member ( signalRef "P3E_CPU0_PE2_SS_TXP<11>") )
				( member ( signalRef "P3E_CPU0_PE2_SS_TXP<12>") )
				( member ( signalRef "P3E_CPU0_PE2_SS_TXP<13>") )
				( member ( signalRef "P3E_CPU0_PE2_SS_TXP<14>") )
				( member ( signalRef "P3E_CPU0_PE2_SS_TXP<15>") )
				( objectStatus "@baseboard_fab2_lib.baseboard_fab2(sch_1):p3e_cpu0_pe2_ss_txp" )
			)
			( bus "P3E_CPU0_PE3_OCP_RXN"
				( memberType ( signal ) )
				( member ( signalRef "P3E_CPU0_PE3_OCP_RXN<0>") )
				( member ( signalRef "P3E_CPU0_PE3_OCP_RXN<1>") )
				( member ( signalRef "P3E_CPU0_PE3_OCP_RXN<2>") )
				( member ( signalRef "P3E_CPU0_PE3_OCP_RXN<3>") )
				( member ( signalRef "P3E_CPU0_PE3_OCP_RXN<4>") )
				( member ( signalRef "P3E_CPU0_PE3_OCP_RXN<5>") )
				( member ( signalRef "P3E_CPU0_PE3_OCP_RXN<6>") )
				( member ( signalRef "P3E_CPU0_PE3_OCP_RXN<7>") )
				( member ( signalRef "P3E_CPU0_PE3_OCP_RXN<8>") )
				( member ( signalRef "P3E_CPU0_PE3_OCP_RXN<9>") )
				( member ( signalRef "P3E_CPU0_PE3_OCP_RXN<10>") )
				( member ( signalRef "P3E_CPU0_PE3_OCP_RXN<11>") )
				( member ( signalRef "P3E_CPU0_PE3_OCP_RXN<12>") )
				( member ( signalRef "P3E_CPU0_PE3_OCP_RXN<13>") )
				( member ( signalRef "P3E_CPU0_PE3_OCP_RXN<14>") )
				( member ( signalRef "P3E_CPU0_PE3_OCP_RXN<15>") )
				( objectStatus "@baseboard_fab2_lib.baseboard_fab2(sch_1):p3e_cpu0_pe3_ocp_rxn" )
			)
			( bus "P3E_CPU0_PE3_OCP_RXP"
				( memberType ( signal ) )
				( member ( signalRef "P3E_CPU0_PE3_OCP_RXP<0>") )
				( member ( signalRef "P3E_CPU0_PE3_OCP_RXP<1>") )
				( member ( signalRef "P3E_CPU0_PE3_OCP_RXP<2>") )
				( member ( signalRef "P3E_CPU0_PE3_OCP_RXP<3>") )
				( member ( signalRef "P3E_CPU0_PE3_OCP_RXP<4>") )
				( member ( signalRef "P3E_CPU0_PE3_OCP_RXP<5>") )
				( member ( signalRef "P3E_CPU0_PE3_OCP_RXP<6>") )
				( member ( signalRef "P3E_CPU0_PE3_OCP_RXP<7>") )
				( member ( signalRef "P3E_CPU0_PE3_OCP_RXP<8>") )
				( member ( signalRef "P3E_CPU0_PE3_OCP_RXP<9>") )
				( member ( signalRef "P3E_CPU0_PE3_OCP_RXP<10>") )
				( member ( signalRef "P3E_CPU0_PE3_OCP_RXP<11>") )
				( member ( signalRef "P3E_CPU0_PE3_OCP_RXP<12>") )
				( member ( signalRef "P3E_CPU0_PE3_OCP_RXP<13>") )
				( member ( signalRef "P3E_CPU0_PE3_OCP_RXP<14>") )
				( member ( signalRef "P3E_CPU0_PE3_OCP_RXP<15>") )
				( objectStatus "@baseboard_fab2_lib.baseboard_fab2(sch_1):p3e_cpu0_pe3_ocp_rxp" )
			)
			( bus "P3E_CPU0_PE3_OCP_TXN"
				( memberType ( signal ) )
				( member ( signalRef "P3E_CPU0_PE3_OCP_TXN<0>") )
				( member ( signalRef "P3E_CPU0_PE3_OCP_TXN<1>") )
				( member ( signalRef "P3E_CPU0_PE3_OCP_TXN<2>") )
				( member ( signalRef "P3E_CPU0_PE3_OCP_TXN<3>") )
				( member ( signalRef "P3E_CPU0_PE3_OCP_TXN<4>") )
				( member ( signalRef "P3E_CPU0_PE3_OCP_TXN<5>") )
				( member ( signalRef "P3E_CPU0_PE3_OCP_TXN<6>") )
				( member ( signalRef "P3E_CPU0_PE3_OCP_TXN<7>") )
				( member ( signalRef "P3E_CPU0_PE3_OCP_TXN<8>") )
				( member ( signalRef "P3E_CPU0_PE3_OCP_TXN<9>") )
				( member ( signalRef "P3E_CPU0_PE3_OCP_TXN<10>") )
				( member ( signalRef "P3E_CPU0_PE3_OCP_TXN<11>") )
				( member ( signalRef "P3E_CPU0_PE3_OCP_TXN<12>") )
				( member ( signalRef "P3E_CPU0_PE3_OCP_TXN<13>") )
				( member ( signalRef "P3E_CPU0_PE3_OCP_TXN<14>") )
				( member ( signalRef "P3E_CPU0_PE3_OCP_TXN<15>") )
				( objectStatus "@baseboard_fab2_lib.baseboard_fab2(sch_1):p3e_cpu0_pe3_ocp_txn" )
			)
			( bus "P3E_CPU0_PE3_OCP_TXP"
				( memberType ( signal ) )
				( member ( signalRef "P3E_CPU0_PE3_OCP_TXP<0>") )
				( member ( signalRef "P3E_CPU0_PE3_OCP_TXP<1>") )
				( member ( signalRef "P3E_CPU0_PE3_OCP_TXP<2>") )
				( member ( signalRef "P3E_CPU0_PE3_OCP_TXP<3>") )
				( member ( signalRef "P3E_CPU0_PE3_OCP_TXP<4>") )
				( member ( signalRef "P3E_CPU0_PE3_OCP_TXP<5>") )
				( member ( signalRef "P3E_CPU0_PE3_OCP_TXP<6>") )
				( member ( signalRef "P3E_CPU0_PE3_OCP_TXP<7>") )
				( member ( signalRef "P3E_CPU0_PE3_OCP_TXP<8>") )
				( member ( signalRef "P3E_CPU0_PE3_OCP_TXP<9>") )
				( member ( signalRef "P3E_CPU0_PE3_OCP_TXP<10>") )
				( member ( signalRef "P3E_CPU0_PE3_OCP_TXP<11>") )
				( member ( signalRef "P3E_CPU0_PE3_OCP_TXP<12>") )
				( member ( signalRef "P3E_CPU0_PE3_OCP_TXP<13>") )
				( member ( signalRef "P3E_CPU0_PE3_OCP_TXP<14>") )
				( member ( signalRef "P3E_CPU0_PE3_OCP_TXP<15>") )
				( objectStatus "@baseboard_fab2_lib.baseboard_fab2(sch_1):p3e_cpu0_pe3_ocp_txp" )
			)
			( bus "UPI_CPU0_CPU1_P0P0_DN"
				( memberType ( signal ) )
				( member ( signalRef "UPI_CPU0_CPU1_P0P0_DN<0>") )
				( member ( signalRef "UPI_CPU0_CPU1_P0P0_DN<1>") )
				( member ( signalRef "UPI_CPU0_CPU1_P0P0_DN<2>") )
				( member ( signalRef "UPI_CPU0_CPU1_P0P0_DN<3>") )
				( member ( signalRef "UPI_CPU0_CPU1_P0P0_DN<4>") )
				( member ( signalRef "UPI_CPU0_CPU1_P0P0_DN<5>") )
				( member ( signalRef "UPI_CPU0_CPU1_P0P0_DN<6>") )
				( member ( signalRef "UPI_CPU0_CPU1_P0P0_DN<7>") )
				( member ( signalRef "UPI_CPU0_CPU1_P0P0_DN<8>") )
				( member ( signalRef "UPI_CPU0_CPU1_P0P0_DN<9>") )
				( member ( signalRef "UPI_CPU0_CPU1_P0P0_DN<10>") )
				( member ( signalRef "UPI_CPU0_CPU1_P0P0_DN<11>") )
				( member ( signalRef "UPI_CPU0_CPU1_P0P0_DN<12>") )
				( member ( signalRef "UPI_CPU0_CPU1_P0P0_DN<13>") )
				( member ( signalRef "UPI_CPU0_CPU1_P0P0_DN<14>") )
				( member ( signalRef "UPI_CPU0_CPU1_P0P0_DN<15>") )
				( member ( signalRef "UPI_CPU0_CPU1_P0P0_DN<16>") )
				( member ( signalRef "UPI_CPU0_CPU1_P0P0_DN<17>") )
				( member ( signalRef "UPI_CPU0_CPU1_P0P0_DN<18>") )
				( member ( signalRef "UPI_CPU0_CPU1_P0P0_DN<19>") )
				( objectStatus "@baseboard_fab2_lib.baseboard_fab2(sch_1):upi_cpu0_cpu1_p0p0_dn" )
			)
			( bus "UPI_CPU0_CPU1_P0P0_DP"
				( memberType ( signal ) )
				( member ( signalRef "UPI_CPU0_CPU1_P0P0_DP<0>") )
				( member ( signalRef "UPI_CPU0_CPU1_P0P0_DP<1>") )
				( member ( signalRef "UPI_CPU0_CPU1_P0P0_DP<2>") )
				( member ( signalRef "UPI_CPU0_CPU1_P0P0_DP<3>") )
				( member ( signalRef "UPI_CPU0_CPU1_P0P0_DP<4>") )
				( member ( signalRef "UPI_CPU0_CPU1_P0P0_DP<5>") )
				( member ( signalRef "UPI_CPU0_CPU1_P0P0_DP<6>") )
				( member ( signalRef "UPI_CPU0_CPU1_P0P0_DP<7>") )
				( member ( signalRef "UPI_CPU0_CPU1_P0P0_DP<8>") )
				( member ( signalRef "UPI_CPU0_CPU1_P0P0_DP<9>") )
				( member ( signalRef "UPI_CPU0_CPU1_P0P0_DP<10>") )
				( member ( signalRef "UPI_CPU0_CPU1_P0P0_DP<11>") )
				( member ( signalRef "UPI_CPU0_CPU1_P0P0_DP<12>") )
				( member ( signalRef "UPI_CPU0_CPU1_P0P0_DP<13>") )
				( member ( signalRef "UPI_CPU0_CPU1_P0P0_DP<14>") )
				( member ( signalRef "UPI_CPU0_CPU1_P0P0_DP<15>") )
				( member ( signalRef "UPI_CPU0_CPU1_P0P0_DP<16>") )
				( member ( signalRef "UPI_CPU0_CPU1_P0P0_DP<17>") )
				( member ( signalRef "UPI_CPU0_CPU1_P0P0_DP<18>") )
				( member ( signalRef "UPI_CPU0_CPU1_P0P0_DP<19>") )
				( objectStatus "@baseboard_fab2_lib.baseboard_fab2(sch_1):upi_cpu0_cpu1_p0p0_dp" )
			)
			( bus "UPI_CPU1_CPU0_P0P0_DN"
				( memberType ( signal ) )
				( member ( signalRef "UPI_CPU1_CPU0_P0P0_DN<0>") )
				( member ( signalRef "UPI_CPU1_CPU0_P0P0_DN<1>") )
				( member ( signalRef "UPI_CPU1_CPU0_P0P0_DN<2>") )
				( member ( signalRef "UPI_CPU1_CPU0_P0P0_DN<3>") )
				( member ( signalRef "UPI_CPU1_CPU0_P0P0_DN<4>") )
				( member ( signalRef "UPI_CPU1_CPU0_P0P0_DN<5>") )
				( member ( signalRef "UPI_CPU1_CPU0_P0P0_DN<6>") )
				( member ( signalRef "UPI_CPU1_CPU0_P0P0_DN<7>") )
				( member ( signalRef "UPI_CPU1_CPU0_P0P0_DN<8>") )
				( member ( signalRef "UPI_CPU1_CPU0_P0P0_DN<9>") )
				( member ( signalRef "UPI_CPU1_CPU0_P0P0_DN<10>") )
				( member ( signalRef "UPI_CPU1_CPU0_P0P0_DN<11>") )
				( member ( signalRef "UPI_CPU1_CPU0_P0P0_DN<12>") )
				( member ( signalRef "UPI_CPU1_CPU0_P0P0_DN<13>") )
				( member ( signalRef "UPI_CPU1_CPU0_P0P0_DN<14>") )
				( member ( signalRef "UPI_CPU1_CPU0_P0P0_DN<15>") )
				( member ( signalRef "UPI_CPU1_CPU0_P0P0_DN<16>") )
				( member ( signalRef "UPI_CPU1_CPU0_P0P0_DN<17>") )
				( member ( signalRef "UPI_CPU1_CPU0_P0P0_DN<18>") )
				( member ( signalRef "UPI_CPU1_CPU0_P0P0_DN<19>") )
				( objectStatus "@baseboard_fab2_lib.baseboard_fab2(sch_1):upi_cpu1_cpu0_p0p0_dn" )
			)
			( bus "UPI_CPU1_CPU0_P0P0_DP"
				( memberType ( signal ) )
				( member ( signalRef "UPI_CPU1_CPU0_P0P0_DP<0>") )
				( member ( signalRef "UPI_CPU1_CPU0_P0P0_DP<1>") )
				( member ( signalRef "UPI_CPU1_CPU0_P0P0_DP<2>") )
				( member ( signalRef "UPI_CPU1_CPU0_P0P0_DP<3>") )
				( member ( signalRef "UPI_CPU1_CPU0_P0P0_DP<4>") )
				( member ( signalRef "UPI_CPU1_CPU0_P0P0_DP<5>") )
				( member ( signalRef "UPI_CPU1_CPU0_P0P0_DP<6>") )
				( member ( signalRef "UPI_CPU1_CPU0_P0P0_DP<7>") )
				( member ( signalRef "UPI_CPU1_CPU0_P0P0_DP<8>") )
				( member ( signalRef "UPI_CPU1_CPU0_P0P0_DP<9>") )
				( member ( signalRef "UPI_CPU1_CPU0_P0P0_DP<10>") )
				( member ( signalRef "UPI_CPU1_CPU0_P0P0_DP<11>") )
				( member ( signalRef "UPI_CPU1_CPU0_P0P0_DP<12>") )
				( member ( signalRef "UPI_CPU1_CPU0_P0P0_DP<13>") )
				( member ( signalRef "UPI_CPU1_CPU0_P0P0_DP<14>") )
				( member ( signalRef "UPI_CPU1_CPU0_P0P0_DP<15>") )
				( member ( signalRef "UPI_CPU1_CPU0_P0P0_DP<16>") )
				( member ( signalRef "UPI_CPU1_CPU0_P0P0_DP<17>") )
				( member ( signalRef "UPI_CPU1_CPU0_P0P0_DP<18>") )
				( member ( signalRef "UPI_CPU1_CPU0_P0P0_DP<19>") )
				( objectStatus "@baseboard_fab2_lib.baseboard_fab2(sch_1):upi_cpu1_cpu0_p0p0_dp" )
			)
			( bus "UPI_CPU0_CPU1_P1P1_DN"
				( memberType ( signal ) )
				( member ( signalRef "UPI_CPU0_CPU1_P1P1_DN<0>") )
				( member ( signalRef "UPI_CPU0_CPU1_P1P1_DN<1>") )
				( member ( signalRef "UPI_CPU0_CPU1_P1P1_DN<2>") )
				( member ( signalRef "UPI_CPU0_CPU1_P1P1_DN<3>") )
				( member ( signalRef "UPI_CPU0_CPU1_P1P1_DN<4>") )
				( member ( signalRef "UPI_CPU0_CPU1_P1P1_DN<5>") )
				( member ( signalRef "UPI_CPU0_CPU1_P1P1_DN<6>") )
				( member ( signalRef "UPI_CPU0_CPU1_P1P1_DN<7>") )
				( member ( signalRef "UPI_CPU0_CPU1_P1P1_DN<8>") )
				( member ( signalRef "UPI_CPU0_CPU1_P1P1_DN<9>") )
				( member ( signalRef "UPI_CPU0_CPU1_P1P1_DN<10>") )
				( member ( signalRef "UPI_CPU0_CPU1_P1P1_DN<11>") )
				( member ( signalRef "UPI_CPU0_CPU1_P1P1_DN<12>") )
				( member ( signalRef "UPI_CPU0_CPU1_P1P1_DN<13>") )
				( member ( signalRef "UPI_CPU0_CPU1_P1P1_DN<14>") )
				( member ( signalRef "UPI_CPU0_CPU1_P1P1_DN<15>") )
				( member ( signalRef "UPI_CPU0_CPU1_P1P1_DN<16>") )
				( member ( signalRef "UPI_CPU0_CPU1_P1P1_DN<17>") )
				( member ( signalRef "UPI_CPU0_CPU1_P1P1_DN<18>") )
				( member ( signalRef "UPI_CPU0_CPU1_P1P1_DN<19>") )
				( objectStatus "@baseboard_fab2_lib.baseboard_fab2(sch_1):upi_cpu0_cpu1_p1p1_dn" )
			)
			( bus "UPI_CPU0_CPU1_P1P1_DP"
				( memberType ( signal ) )
				( member ( signalRef "UPI_CPU0_CPU1_P1P1_DP<0>") )
				( member ( signalRef "UPI_CPU0_CPU1_P1P1_DP<1>") )
				( member ( signalRef "UPI_CPU0_CPU1_P1P1_DP<2>") )
				( member ( signalRef "UPI_CPU0_CPU1_P1P1_DP<3>") )
				( member ( signalRef "UPI_CPU0_CPU1_P1P1_DP<4>") )
				( member ( signalRef "UPI_CPU0_CPU1_P1P1_DP<5>") )
				( member ( signalRef "UPI_CPU0_CPU1_P1P1_DP<6>") )
				( member ( signalRef "UPI_CPU0_CPU1_P1P1_DP<7>") )
				( member ( signalRef "UPI_CPU0_CPU1_P1P1_DP<8>") )
				( member ( signalRef "UPI_CPU0_CPU1_P1P1_DP<9>") )
				( member ( signalRef "UPI_CPU0_CPU1_P1P1_DP<10>") )
				( member ( signalRef "UPI_CPU0_CPU1_P1P1_DP<11>") )
				( member ( signalRef "UPI_CPU0_CPU1_P1P1_DP<12>") )
				( member ( signalRef "UPI_CPU0_CPU1_P1P1_DP<13>") )
				( member ( signalRef "UPI_CPU0_CPU1_P1P1_DP<14>") )
				( member ( signalRef "UPI_CPU0_CPU1_P1P1_DP<15>") )
				( member ( signalRef "UPI_CPU0_CPU1_P1P1_DP<16>") )
				( member ( signalRef "UPI_CPU0_CPU1_P1P1_DP<17>") )
				( member ( signalRef "UPI_CPU0_CPU1_P1P1_DP<18>") )
				( member ( signalRef "UPI_CPU0_CPU1_P1P1_DP<19>") )
				( objectStatus "@baseboard_fab2_lib.baseboard_fab2(sch_1):upi_cpu0_cpu1_p1p1_dp" )
			)
			( bus "UPI_CPU1_CPU0_P1P1_DN"
				( memberType ( signal ) )
				( member ( signalRef "UPI_CPU1_CPU0_P1P1_DN<0>") )
				( member ( signalRef "UPI_CPU1_CPU0_P1P1_DN<1>") )
				( member ( signalRef "UPI_CPU1_CPU0_P1P1_DN<2>") )
				( member ( signalRef "UPI_CPU1_CPU0_P1P1_DN<3>") )
				( member ( signalRef "UPI_CPU1_CPU0_P1P1_DN<4>") )
				( member ( signalRef "UPI_CPU1_CPU0_P1P1_DN<5>") )
				( member ( signalRef "UPI_CPU1_CPU0_P1P1_DN<6>") )
				( member ( signalRef "UPI_CPU1_CPU0_P1P1_DN<7>") )
				( member ( signalRef "UPI_CPU1_CPU0_P1P1_DN<8>") )
				( member ( signalRef "UPI_CPU1_CPU0_P1P1_DN<9>") )
				( member ( signalRef "UPI_CPU1_CPU0_P1P1_DN<10>") )
				( member ( signalRef "UPI_CPU1_CPU0_P1P1_DN<11>") )
				( member ( signalRef "UPI_CPU1_CPU0_P1P1_DN<12>") )
				( member ( signalRef "UPI_CPU1_CPU0_P1P1_DN<13>") )
				( member ( signalRef "UPI_CPU1_CPU0_P1P1_DN<14>") )
				( member ( signalRef "UPI_CPU1_CPU0_P1P1_DN<15>") )
				( member ( signalRef "UPI_CPU1_CPU0_P1P1_DN<16>") )
				( member ( signalRef "UPI_CPU1_CPU0_P1P1_DN<17>") )
				( member ( signalRef "UPI_CPU1_CPU0_P1P1_DN<18>") )
				( member ( signalRef "UPI_CPU1_CPU0_P1P1_DN<19>") )
				( objectStatus "@baseboard_fab2_lib.baseboard_fab2(sch_1):upi_cpu1_cpu0_p1p1_dn" )
			)
			( bus "UPI_CPU1_CPU0_P1P1_DP"
				( memberType ( signal ) )
				( member ( signalRef "UPI_CPU1_CPU0_P1P1_DP<0>") )
				( member ( signalRef "UPI_CPU1_CPU0_P1P1_DP<1>") )
				( member ( signalRef "UPI_CPU1_CPU0_P1P1_DP<2>") )
				( member ( signalRef "UPI_CPU1_CPU0_P1P1_DP<3>") )
				( member ( signalRef "UPI_CPU1_CPU0_P1P1_DP<4>") )
				( member ( signalRef "UPI_CPU1_CPU0_P1P1_DP<5>") )
				( member ( signalRef "UPI_CPU1_CPU0_P1P1_DP<6>") )
				( member ( signalRef "UPI_CPU1_CPU0_P1P1_DP<7>") )
				( member ( signalRef "UPI_CPU1_CPU0_P1P1_DP<8>") )
				( member ( signalRef "UPI_CPU1_CPU0_P1P1_DP<9>") )
				( member ( signalRef "UPI_CPU1_CPU0_P1P1_DP<10>") )
				( member ( signalRef "UPI_CPU1_CPU0_P1P1_DP<11>") )
				( member ( signalRef "UPI_CPU1_CPU0_P1P1_DP<12>") )
				( member ( signalRef "UPI_CPU1_CPU0_P1P1_DP<13>") )
				( member ( signalRef "UPI_CPU1_CPU0_P1P1_DP<14>") )
				( member ( signalRef "UPI_CPU1_CPU0_P1P1_DP<15>") )
				( member ( signalRef "UPI_CPU1_CPU0_P1P1_DP<16>") )
				( member ( signalRef "UPI_CPU1_CPU0_P1P1_DP<17>") )
				( member ( signalRef "UPI_CPU1_CPU0_P1P1_DP<18>") )
				( member ( signalRef "UPI_CPU1_CPU0_P1P1_DP<19>") )
				( objectStatus "@baseboard_fab2_lib.baseboard_fab2(sch_1):upi_cpu1_cpu0_p1p1_dp" )
			)
			( bus "M_G_BA"
				( memberType ( signal ) )
				( member ( signalRef "M_G_BA<0>") )
				( member ( signalRef "M_G_BA<1>") )
				( objectStatus "@baseboard_fab2_lib.baseboard_fab2(sch_1):m_g_ba" )
			)
			( bus "M_G_BG"
				( memberType ( signal ) )
				( member ( signalRef "M_G_BG<0>") )
				( member ( signalRef "M_G_BG<1>") )
				( objectStatus "@baseboard_fab2_lib.baseboard_fab2(sch_1):m_g_bg" )
			)
			( bus "M_G_C"
				( memberType ( signal ) )
				( member ( signalRef "M_G_C<2>") )
				( objectStatus "@baseboard_fab2_lib.baseboard_fab2(sch_1):m_g_c" )
			)
			( bus "M_G_CKE"
				( memberType ( signal ) )
				( member ( signalRef "M_G_CKE<0>") )
				( member ( signalRef "M_G_CKE<1>") )
				( member ( signalRef "M_G_CKE<2>") )
				( member ( signalRef "M_G_CKE<3>") )
				( objectStatus "@baseboard_fab2_lib.baseboard_fab2(sch_1):m_g_cke" )
			)
			( bus "M_G_CLK_DN"
				( memberType ( signal ) )
				( member ( signalRef "M_G_CLK_DN<0>") )
				( member ( signalRef "M_G_CLK_DN<1>") )
				( member ( signalRef "M_G_CLK_DN<2>") )
				( member ( signalRef "M_G_CLK_DN<3>") )
				( objectStatus "@baseboard_fab2_lib.baseboard_fab2(sch_1):m_g_clk_dn" )
			)
			( bus "M_G_CLK_DP"
				( memberType ( signal ) )
				( member ( signalRef "M_G_CLK_DP<0>") )
				( member ( signalRef "M_G_CLK_DP<1>") )
				( member ( signalRef "M_G_CLK_DP<2>") )
				( member ( signalRef "M_G_CLK_DP<3>") )
				( objectStatus "@baseboard_fab2_lib.baseboard_fab2(sch_1):m_g_clk_dp" )
			)
			( bus "M_G_CS_N"
				( memberType ( signal ) )
				( member ( signalRef "M_G_CS_N<0>") )
				( member ( signalRef "M_G_CS_N<1>") )
				( member ( signalRef "M_G_CS_N<2>") )
				( member ( signalRef "M_G_CS_N<3>") )
				( member ( signalRef "M_G_CS_N<4>") )
				( member ( signalRef "M_G_CS_N<5>") )
				( member ( signalRef "M_G_CS_N<6>") )
				( member ( signalRef "M_G_CS_N<7>") )
				( objectStatus "@baseboard_fab2_lib.baseboard_fab2(sch_1):m_g_cs_n" )
			)
			( bus "M_G_DQ"
				( memberType ( signal ) )
				( member ( signalRef "M_G_DQ<0>") )
				( member ( signalRef "M_G_DQ<1>") )
				( member ( signalRef "M_G_DQ<2>") )
				( member ( signalRef "M_G_DQ<3>") )
				( member ( signalRef "M_G_DQ<4>") )
				( member ( signalRef "M_G_DQ<5>") )
				( member ( signalRef "M_G_DQ<6>") )
				( member ( signalRef "M_G_DQ<7>") )
				( member ( signalRef "M_G_DQ<8>") )
				( member ( signalRef "M_G_DQ<9>") )
				( member ( signalRef "M_G_DQ<10>") )
				( member ( signalRef "M_G_DQ<11>") )
				( member ( signalRef "M_G_DQ<12>") )
				( member ( signalRef "M_G_DQ<13>") )
				( member ( signalRef "M_G_DQ<14>") )
				( member ( signalRef "M_G_DQ<15>") )
				( member ( signalRef "M_G_DQ<16>") )
				( member ( signalRef "M_G_DQ<17>") )
				( member ( signalRef "M_G_DQ<18>") )
				( member ( signalRef "M_G_DQ<19>") )
				( member ( signalRef "M_G_DQ<20>") )
				( member ( signalRef "M_G_DQ<21>") )
				( member ( signalRef "M_G_DQ<22>") )
				( member ( signalRef "M_G_DQ<23>") )
				( member ( signalRef "M_G_DQ<24>") )
				( member ( signalRef "M_G_DQ<25>") )
				( member ( signalRef "M_G_DQ<26>") )
				( member ( signalRef "M_G_DQ<27>") )
				( member ( signalRef "M_G_DQ<28>") )
				( member ( signalRef "M_G_DQ<29>") )
				( member ( signalRef "M_G_DQ<30>") )
				( member ( signalRef "M_G_DQ<31>") )
				( member ( signalRef "M_G_DQ<32>") )
				( member ( signalRef "M_G_DQ<33>") )
				( member ( signalRef "M_G_DQ<34>") )
				( member ( signalRef "M_G_DQ<35>") )
				( member ( signalRef "M_G_DQ<36>") )
				( member ( signalRef "M_G_DQ<37>") )
				( member ( signalRef "M_G_DQ<38>") )
				( member ( signalRef "M_G_DQ<39>") )
				( member ( signalRef "M_G_DQ<40>") )
				( member ( signalRef "M_G_DQ<41>") )
				( member ( signalRef "M_G_DQ<42>") )
				( member ( signalRef "M_G_DQ<43>") )
				( member ( signalRef "M_G_DQ<44>") )
				( member ( signalRef "M_G_DQ<45>") )
				( member ( signalRef "M_G_DQ<46>") )
				( member ( signalRef "M_G_DQ<47>") )
				( member ( signalRef "M_G_DQ<48>") )
				( member ( signalRef "M_G_DQ<49>") )
				( member ( signalRef "M_G_DQ<50>") )
				( member ( signalRef "M_G_DQ<51>") )
				( member ( signalRef "M_G_DQ<52>") )
				( member ( signalRef "M_G_DQ<53>") )
				( member ( signalRef "M_G_DQ<54>") )
				( member ( signalRef "M_G_DQ<55>") )
				( member ( signalRef "M_G_DQ<56>") )
				( member ( signalRef "M_G_DQ<57>") )
				( member ( signalRef "M_G_DQ<58>") )
				( member ( signalRef "M_G_DQ<59>") )
				( member ( signalRef "M_G_DQ<60>") )
				( member ( signalRef "M_G_DQ<61>") )
				( member ( signalRef "M_G_DQ<62>") )
				( member ( signalRef "M_G_DQ<63>") )
				( objectStatus "@baseboard_fab2_lib.baseboard_fab2(sch_1):m_g_dq" )
			)
			( bus "M_G_DQS_DN"
				( memberType ( signal ) )
				( member ( signalRef "M_G_DQS_DN<0>") )
				( member ( signalRef "M_G_DQS_DN<1>") )
				( member ( signalRef "M_G_DQS_DN<2>") )
				( member ( signalRef "M_G_DQS_DN<3>") )
				( member ( signalRef "M_G_DQS_DN<4>") )
				( member ( signalRef "M_G_DQS_DN<5>") )
				( member ( signalRef "M_G_DQS_DN<6>") )
				( member ( signalRef "M_G_DQS_DN<7>") )
				( member ( signalRef "M_G_DQS_DN<8>") )
				( member ( signalRef "M_G_DQS_DN<9>") )
				( member ( signalRef "M_G_DQS_DN<10>") )
				( member ( signalRef "M_G_DQS_DN<11>") )
				( member ( signalRef "M_G_DQS_DN<12>") )
				( member ( signalRef "M_G_DQS_DN<13>") )
				( member ( signalRef "M_G_DQS_DN<14>") )
				( member ( signalRef "M_G_DQS_DN<15>") )
				( member ( signalRef "M_G_DQS_DN<16>") )
				( member ( signalRef "M_G_DQS_DN<17>") )
				( objectStatus "@baseboard_fab2_lib.baseboard_fab2(sch_1):m_g_dqs_dn" )
			)
			( bus "M_G_DQS_DP"
				( memberType ( signal ) )
				( member ( signalRef "M_G_DQS_DP<0>") )
				( member ( signalRef "M_G_DQS_DP<1>") )
				( member ( signalRef "M_G_DQS_DP<2>") )
				( member ( signalRef "M_G_DQS_DP<3>") )
				( member ( signalRef "M_G_DQS_DP<4>") )
				( member ( signalRef "M_G_DQS_DP<5>") )
				( member ( signalRef "M_G_DQS_DP<6>") )
				( member ( signalRef "M_G_DQS_DP<7>") )
				( member ( signalRef "M_G_DQS_DP<8>") )
				( member ( signalRef "M_G_DQS_DP<9>") )
				( member ( signalRef "M_G_DQS_DP<10>") )
				( member ( signalRef "M_G_DQS_DP<11>") )
				( member ( signalRef "M_G_DQS_DP<12>") )
				( member ( signalRef "M_G_DQS_DP<13>") )
				( member ( signalRef "M_G_DQS_DP<14>") )
				( member ( signalRef "M_G_DQS_DP<15>") )
				( member ( signalRef "M_G_DQS_DP<16>") )
				( member ( signalRef "M_G_DQS_DP<17>") )
				( objectStatus "@baseboard_fab2_lib.baseboard_fab2(sch_1):m_g_dqs_dp" )
			)
			( bus "M_G_ECC"
				( memberType ( signal ) )
				( member ( signalRef "M_G_ECC<0>") )
				( member ( signalRef "M_G_ECC<1>") )
				( member ( signalRef "M_G_ECC<2>") )
				( member ( signalRef "M_G_ECC<3>") )
				( member ( signalRef "M_G_ECC<4>") )
				( member ( signalRef "M_G_ECC<5>") )
				( member ( signalRef "M_G_ECC<6>") )
				( member ( signalRef "M_G_ECC<7>") )
				( objectStatus "@baseboard_fab2_lib.baseboard_fab2(sch_1):m_g_ecc" )
			)
			( bus "M_G_MA"
				( memberType ( signal ) )
				( member ( signalRef "M_G_MA<0>") )
				( member ( signalRef "M_G_MA<1>") )
				( member ( signalRef "M_G_MA<2>") )
				( member ( signalRef "M_G_MA<3>") )
				( member ( signalRef "M_G_MA<4>") )
				( member ( signalRef "M_G_MA<5>") )
				( member ( signalRef "M_G_MA<6>") )
				( member ( signalRef "M_G_MA<7>") )
				( member ( signalRef "M_G_MA<8>") )
				( member ( signalRef "M_G_MA<9>") )
				( member ( signalRef "M_G_MA<10>") )
				( member ( signalRef "M_G_MA<11>") )
				( member ( signalRef "M_G_MA<12>") )
				( member ( signalRef "M_G_MA<13>") )
				( member ( signalRef "M_G_MA<14>") )
				( member ( signalRef "M_G_MA<15>") )
				( member ( signalRef "M_G_MA<16>") )
				( member ( signalRef "M_G_MA<17>") )
				( objectStatus "@baseboard_fab2_lib.baseboard_fab2(sch_1):m_g_ma" )
			)
			( bus "M_G_ODT"
				( memberType ( signal ) )
				( member ( signalRef "M_G_ODT<0>") )
				( member ( signalRef "M_G_ODT<1>") )
				( member ( signalRef "M_G_ODT<2>") )
				( member ( signalRef "M_G_ODT<3>") )
				( objectStatus "@baseboard_fab2_lib.baseboard_fab2(sch_1):m_g_odt" )
			)
			( bus "M_H_BA"
				( memberType ( signal ) )
				( member ( signalRef "M_H_BA<0>") )
				( member ( signalRef "M_H_BA<1>") )
				( objectStatus "@baseboard_fab2_lib.baseboard_fab2(sch_1):m_h_ba" )
			)
			( bus "M_H_BG"
				( memberType ( signal ) )
				( member ( signalRef "M_H_BG<0>") )
				( member ( signalRef "M_H_BG<1>") )
				( objectStatus "@baseboard_fab2_lib.baseboard_fab2(sch_1):m_h_bg" )
			)
			( bus "M_H_C"
				( memberType ( signal ) )
				( member ( signalRef "M_H_C<2>") )
				( objectStatus "@baseboard_fab2_lib.baseboard_fab2(sch_1):m_h_c" )
			)
			( bus "M_H_CKE"
				( memberType ( signal ) )
				( member ( signalRef "M_H_CKE<0>") )
				( member ( signalRef "M_H_CKE<1>") )
				( member ( signalRef "M_H_CKE<2>") )
				( member ( signalRef "M_H_CKE<3>") )
				( objectStatus "@baseboard_fab2_lib.baseboard_fab2(sch_1):m_h_cke" )
			)
			( bus "M_H_CLK_DN"
				( memberType ( signal ) )
				( member ( signalRef "M_H_CLK_DN<0>") )
				( member ( signalRef "M_H_CLK_DN<1>") )
				( member ( signalRef "M_H_CLK_DN<2>") )
				( member ( signalRef "M_H_CLK_DN<3>") )
				( objectStatus "@baseboard_fab2_lib.baseboard_fab2(sch_1):m_h_clk_dn" )
			)
			( bus "M_H_CLK_DP"
				( memberType ( signal ) )
				( member ( signalRef "M_H_CLK_DP<0>") )
				( member ( signalRef "M_H_CLK_DP<1>") )
				( member ( signalRef "M_H_CLK_DP<2>") )
				( member ( signalRef "M_H_CLK_DP<3>") )
				( objectStatus "@baseboard_fab2_lib.baseboard_fab2(sch_1):m_h_clk_dp" )
			)
			( bus "M_H_CS_N"
				( memberType ( signal ) )
				( member ( signalRef "M_H_CS_N<0>") )
				( member ( signalRef "M_H_CS_N<1>") )
				( member ( signalRef "M_H_CS_N<2>") )
				( member ( signalRef "M_H_CS_N<3>") )
				( member ( signalRef "M_H_CS_N<4>") )
				( member ( signalRef "M_H_CS_N<5>") )
				( member ( signalRef "M_H_CS_N<6>") )
				( member ( signalRef "M_H_CS_N<7>") )
				( objectStatus "@baseboard_fab2_lib.baseboard_fab2(sch_1):m_h_cs_n" )
			)
			( bus "M_H_DQ"
				( memberType ( signal ) )
				( member ( signalRef "M_H_DQ<0>") )
				( member ( signalRef "M_H_DQ<1>") )
				( member ( signalRef "M_H_DQ<2>") )
				( member ( signalRef "M_H_DQ<3>") )
				( member ( signalRef "M_H_DQ<4>") )
				( member ( signalRef "M_H_DQ<5>") )
				( member ( signalRef "M_H_DQ<6>") )
				( member ( signalRef "M_H_DQ<7>") )
				( member ( signalRef "M_H_DQ<8>") )
				( member ( signalRef "M_H_DQ<9>") )
				( member ( signalRef "M_H_DQ<10>") )
				( member ( signalRef "M_H_DQ<11>") )
				( member ( signalRef "M_H_DQ<12>") )
				( member ( signalRef "M_H_DQ<13>") )
				( member ( signalRef "M_H_DQ<14>") )
				( member ( signalRef "M_H_DQ<15>") )
				( member ( signalRef "M_H_DQ<16>") )
				( member ( signalRef "M_H_DQ<17>") )
				( member ( signalRef "M_H_DQ<18>") )
				( member ( signalRef "M_H_DQ<19>") )
				( member ( signalRef "M_H_DQ<20>") )
				( member ( signalRef "M_H_DQ<21>") )
				( member ( signalRef "M_H_DQ<22>") )
				( member ( signalRef "M_H_DQ<23>") )
				( member ( signalRef "M_H_DQ<24>") )
				( member ( signalRef "M_H_DQ<25>") )
				( member ( signalRef "M_H_DQ<26>") )
				( member ( signalRef "M_H_DQ<27>") )
				( member ( signalRef "M_H_DQ<28>") )
				( member ( signalRef "M_H_DQ<29>") )
				( member ( signalRef "M_H_DQ<30>") )
				( member ( signalRef "M_H_DQ<31>") )
				( member ( signalRef "M_H_DQ<32>") )
				( member ( signalRef "M_H_DQ<33>") )
				( member ( signalRef "M_H_DQ<34>") )
				( member ( signalRef "M_H_DQ<35>") )
				( member ( signalRef "M_H_DQ<36>") )
				( member ( signalRef "M_H_DQ<37>") )
				( member ( signalRef "M_H_DQ<38>") )
				( member ( signalRef "M_H_DQ<39>") )
				( member ( signalRef "M_H_DQ<40>") )
				( member ( signalRef "M_H_DQ<41>") )
				( member ( signalRef "M_H_DQ<42>") )
				( member ( signalRef "M_H_DQ<43>") )
				( member ( signalRef "M_H_DQ<44>") )
				( member ( signalRef "M_H_DQ<45>") )
				( member ( signalRef "M_H_DQ<46>") )
				( member ( signalRef "M_H_DQ<47>") )
				( member ( signalRef "M_H_DQ<48>") )
				( member ( signalRef "M_H_DQ<49>") )
				( member ( signalRef "M_H_DQ<50>") )
				( member ( signalRef "M_H_DQ<51>") )
				( member ( signalRef "M_H_DQ<52>") )
				( member ( signalRef "M_H_DQ<53>") )
				( member ( signalRef "M_H_DQ<54>") )
				( member ( signalRef "M_H_DQ<55>") )
				( member ( signalRef "M_H_DQ<56>") )
				( member ( signalRef "M_H_DQ<57>") )
				( member ( signalRef "M_H_DQ<58>") )
				( member ( signalRef "M_H_DQ<59>") )
				( member ( signalRef "M_H_DQ<60>") )
				( member ( signalRef "M_H_DQ<61>") )
				( member ( signalRef "M_H_DQ<62>") )
				( member ( signalRef "M_H_DQ<63>") )
				( objectStatus "@baseboard_fab2_lib.baseboard_fab2(sch_1):m_h_dq" )
			)
			( bus "M_H_DQS_DN"
				( memberType ( signal ) )
				( member ( signalRef "M_H_DQS_DN<0>") )
				( member ( signalRef "M_H_DQS_DN<1>") )
				( member ( signalRef "M_H_DQS_DN<2>") )
				( member ( signalRef "M_H_DQS_DN<3>") )
				( member ( signalRef "M_H_DQS_DN<4>") )
				( member ( signalRef "M_H_DQS_DN<5>") )
				( member ( signalRef "M_H_DQS_DN<6>") )
				( member ( signalRef "M_H_DQS_DN<7>") )
				( member ( signalRef "M_H_DQS_DN<8>") )
				( member ( signalRef "M_H_DQS_DN<9>") )
				( member ( signalRef "M_H_DQS_DN<10>") )
				( member ( signalRef "M_H_DQS_DN<11>") )
				( member ( signalRef "M_H_DQS_DN<12>") )
				( member ( signalRef "M_H_DQS_DN<13>") )
				( member ( signalRef "M_H_DQS_DN<14>") )
				( member ( signalRef "M_H_DQS_DN<15>") )
				( member ( signalRef "M_H_DQS_DN<16>") )
				( member ( signalRef "M_H_DQS_DN<17>") )
				( objectStatus "@baseboard_fab2_lib.baseboard_fab2(sch_1):m_h_dqs_dn" )
			)
			( bus "M_H_DQS_DP"
				( memberType ( signal ) )
				( member ( signalRef "M_H_DQS_DP<0>") )
				( member ( signalRef "M_H_DQS_DP<1>") )
				( member ( signalRef "M_H_DQS_DP<2>") )
				( member ( signalRef "M_H_DQS_DP<3>") )
				( member ( signalRef "M_H_DQS_DP<4>") )
				( member ( signalRef "M_H_DQS_DP<5>") )
				( member ( signalRef "M_H_DQS_DP<6>") )
				( member ( signalRef "M_H_DQS_DP<7>") )
				( member ( signalRef "M_H_DQS_DP<8>") )
				( member ( signalRef "M_H_DQS_DP<9>") )
				( member ( signalRef "M_H_DQS_DP<10>") )
				( member ( signalRef "M_H_DQS_DP<11>") )
				( member ( signalRef "M_H_DQS_DP<12>") )
				( member ( signalRef "M_H_DQS_DP<13>") )
				( member ( signalRef "M_H_DQS_DP<14>") )
				( member ( signalRef "M_H_DQS_DP<15>") )
				( member ( signalRef "M_H_DQS_DP<16>") )
				( member ( signalRef "M_H_DQS_DP<17>") )
				( objectStatus "@baseboard_fab2_lib.baseboard_fab2(sch_1):m_h_dqs_dp" )
			)
			( bus "M_H_ECC"
				( memberType ( signal ) )
				( member ( signalRef "M_H_ECC<0>") )
				( member ( signalRef "M_H_ECC<1>") )
				( member ( signalRef "M_H_ECC<2>") )
				( member ( signalRef "M_H_ECC<3>") )
				( member ( signalRef "M_H_ECC<4>") )
				( member ( signalRef "M_H_ECC<5>") )
				( member ( signalRef "M_H_ECC<6>") )
				( member ( signalRef "M_H_ECC<7>") )
				( objectStatus "@baseboard_fab2_lib.baseboard_fab2(sch_1):m_h_ecc" )
			)
			( bus "M_H_MA"
				( memberType ( signal ) )
				( member ( signalRef "M_H_MA<0>") )
				( member ( signalRef "M_H_MA<1>") )
				( member ( signalRef "M_H_MA<2>") )
				( member ( signalRef "M_H_MA<3>") )
				( member ( signalRef "M_H_MA<4>") )
				( member ( signalRef "M_H_MA<5>") )
				( member ( signalRef "M_H_MA<6>") )
				( member ( signalRef "M_H_MA<7>") )
				( member ( signalRef "M_H_MA<8>") )
				( member ( signalRef "M_H_MA<9>") )
				( member ( signalRef "M_H_MA<10>") )
				( member ( signalRef "M_H_MA<11>") )
				( member ( signalRef "M_H_MA<12>") )
				( member ( signalRef "M_H_MA<13>") )
				( member ( signalRef "M_H_MA<14>") )
				( member ( signalRef "M_H_MA<15>") )
				( member ( signalRef "M_H_MA<16>") )
				( member ( signalRef "M_H_MA<17>") )
				( objectStatus "@baseboard_fab2_lib.baseboard_fab2(sch_1):m_h_ma" )
			)
			( bus "M_H_ODT"
				( memberType ( signal ) )
				( member ( signalRef "M_H_ODT<0>") )
				( member ( signalRef "M_H_ODT<1>") )
				( member ( signalRef "M_H_ODT<2>") )
				( member ( signalRef "M_H_ODT<3>") )
				( objectStatus "@baseboard_fab2_lib.baseboard_fab2(sch_1):m_h_odt" )
			)
			( bus "M_J_BA"
				( memberType ( signal ) )
				( member ( signalRef "M_J_BA<0>") )
				( member ( signalRef "M_J_BA<1>") )
				( objectStatus "@baseboard_fab2_lib.baseboard_fab2(sch_1):m_j_ba" )
			)
			( bus "M_J_BG"
				( memberType ( signal ) )
				( member ( signalRef "M_J_BG<0>") )
				( member ( signalRef "M_J_BG<1>") )
				( objectStatus "@baseboard_fab2_lib.baseboard_fab2(sch_1):m_j_bg" )
			)
			( bus "M_J_C"
				( memberType ( signal ) )
				( member ( signalRef "M_J_C<2>") )
				( objectStatus "@baseboard_fab2_lib.baseboard_fab2(sch_1):m_j_c" )
			)
			( bus "M_J_CKE"
				( memberType ( signal ) )
				( member ( signalRef "M_J_CKE<0>") )
				( member ( signalRef "M_J_CKE<1>") )
				( member ( signalRef "M_J_CKE<2>") )
				( member ( signalRef "M_J_CKE<3>") )
				( objectStatus "@baseboard_fab2_lib.baseboard_fab2(sch_1):m_j_cke" )
			)
			( bus "M_J_CLK_DN"
				( memberType ( signal ) )
				( member ( signalRef "M_J_CLK_DN<0>") )
				( member ( signalRef "M_J_CLK_DN<1>") )
				( member ( signalRef "M_J_CLK_DN<2>") )
				( member ( signalRef "M_J_CLK_DN<3>") )
				( objectStatus "@baseboard_fab2_lib.baseboard_fab2(sch_1):m_j_clk_dn" )
			)
			( bus "M_J_CLK_DP"
				( memberType ( signal ) )
				( member ( signalRef "M_J_CLK_DP<0>") )
				( member ( signalRef "M_J_CLK_DP<1>") )
				( member ( signalRef "M_J_CLK_DP<2>") )
				( member ( signalRef "M_J_CLK_DP<3>") )
				( objectStatus "@baseboard_fab2_lib.baseboard_fab2(sch_1):m_j_clk_dp" )
			)
			( bus "M_J_CS_N"
				( memberType ( signal ) )
				( member ( signalRef "M_J_CS_N<0>") )
				( member ( signalRef "M_J_CS_N<1>") )
				( member ( signalRef "M_J_CS_N<2>") )
				( member ( signalRef "M_J_CS_N<3>") )
				( member ( signalRef "M_J_CS_N<4>") )
				( member ( signalRef "M_J_CS_N<5>") )
				( member ( signalRef "M_J_CS_N<6>") )
				( member ( signalRef "M_J_CS_N<7>") )
				( objectStatus "@baseboard_fab2_lib.baseboard_fab2(sch_1):m_j_cs_n" )
			)
			( bus "M_J_DQ"
				( memberType ( signal ) )
				( member ( signalRef "M_J_DQ<0>") )
				( member ( signalRef "M_J_DQ<1>") )
				( member ( signalRef "M_J_DQ<2>") )
				( member ( signalRef "M_J_DQ<3>") )
				( member ( signalRef "M_J_DQ<4>") )
				( member ( signalRef "M_J_DQ<5>") )
				( member ( signalRef "M_J_DQ<6>") )
				( member ( signalRef "M_J_DQ<7>") )
				( member ( signalRef "M_J_DQ<8>") )
				( member ( signalRef "M_J_DQ<9>") )
				( member ( signalRef "M_J_DQ<10>") )
				( member ( signalRef "M_J_DQ<11>") )
				( member ( signalRef "M_J_DQ<12>") )
				( member ( signalRef "M_J_DQ<13>") )
				( member ( signalRef "M_J_DQ<14>") )
				( member ( signalRef "M_J_DQ<15>") )
				( member ( signalRef "M_J_DQ<16>") )
				( member ( signalRef "M_J_DQ<17>") )
				( member ( signalRef "M_J_DQ<18>") )
				( member ( signalRef "M_J_DQ<19>") )
				( member ( signalRef "M_J_DQ<20>") )
				( member ( signalRef "M_J_DQ<21>") )
				( member ( signalRef "M_J_DQ<22>") )
				( member ( signalRef "M_J_DQ<23>") )
				( member ( signalRef "M_J_DQ<24>") )
				( member ( signalRef "M_J_DQ<25>") )
				( member ( signalRef "M_J_DQ<26>") )
				( member ( signalRef "M_J_DQ<27>") )
				( member ( signalRef "M_J_DQ<28>") )
				( member ( signalRef "M_J_DQ<29>") )
				( member ( signalRef "M_J_DQ<30>") )
				( member ( signalRef "M_J_DQ<31>") )
				( member ( signalRef "M_J_DQ<32>") )
				( member ( signalRef "M_J_DQ<33>") )
				( member ( signalRef "M_J_DQ<34>") )
				( member ( signalRef "M_J_DQ<35>") )
				( member ( signalRef "M_J_DQ<36>") )
				( member ( signalRef "M_J_DQ<37>") )
				( member ( signalRef "M_J_DQ<38>") )
				( member ( signalRef "M_J_DQ<39>") )
				( member ( signalRef "M_J_DQ<40>") )
				( member ( signalRef "M_J_DQ<41>") )
				( member ( signalRef "M_J_DQ<42>") )
				( member ( signalRef "M_J_DQ<43>") )
				( member ( signalRef "M_J_DQ<44>") )
				( member ( signalRef "M_J_DQ<45>") )
				( member ( signalRef "M_J_DQ<46>") )
				( member ( signalRef "M_J_DQ<47>") )
				( member ( signalRef "M_J_DQ<48>") )
				( member ( signalRef "M_J_DQ<49>") )
				( member ( signalRef "M_J_DQ<50>") )
				( member ( signalRef "M_J_DQ<51>") )
				( member ( signalRef "M_J_DQ<52>") )
				( member ( signalRef "M_J_DQ<53>") )
				( member ( signalRef "M_J_DQ<54>") )
				( member ( signalRef "M_J_DQ<55>") )
				( member ( signalRef "M_J_DQ<56>") )
				( member ( signalRef "M_J_DQ<57>") )
				( member ( signalRef "M_J_DQ<58>") )
				( member ( signalRef "M_J_DQ<59>") )
				( member ( signalRef "M_J_DQ<60>") )
				( member ( signalRef "M_J_DQ<61>") )
				( member ( signalRef "M_J_DQ<62>") )
				( member ( signalRef "M_J_DQ<63>") )
				( objectStatus "@baseboard_fab2_lib.baseboard_fab2(sch_1):m_j_dq" )
			)
			( bus "M_J_DQS_DN"
				( memberType ( signal ) )
				( member ( signalRef "M_J_DQS_DN<0>") )
				( member ( signalRef "M_J_DQS_DN<1>") )
				( member ( signalRef "M_J_DQS_DN<2>") )
				( member ( signalRef "M_J_DQS_DN<3>") )
				( member ( signalRef "M_J_DQS_DN<4>") )
				( member ( signalRef "M_J_DQS_DN<5>") )
				( member ( signalRef "M_J_DQS_DN<6>") )
				( member ( signalRef "M_J_DQS_DN<7>") )
				( member ( signalRef "M_J_DQS_DN<8>") )
				( member ( signalRef "M_J_DQS_DN<9>") )
				( member ( signalRef "M_J_DQS_DN<10>") )
				( member ( signalRef "M_J_DQS_DN<11>") )
				( member ( signalRef "M_J_DQS_DN<12>") )
				( member ( signalRef "M_J_DQS_DN<13>") )
				( member ( signalRef "M_J_DQS_DN<14>") )
				( member ( signalRef "M_J_DQS_DN<15>") )
				( member ( signalRef "M_J_DQS_DN<16>") )
				( member ( signalRef "M_J_DQS_DN<17>") )
				( objectStatus "@baseboard_fab2_lib.baseboard_fab2(sch_1):m_j_dqs_dn" )
			)
			( bus "M_J_DQS_DP"
				( memberType ( signal ) )
				( member ( signalRef "M_J_DQS_DP<0>") )
				( member ( signalRef "M_J_DQS_DP<1>") )
				( member ( signalRef "M_J_DQS_DP<2>") )
				( member ( signalRef "M_J_DQS_DP<3>") )
				( member ( signalRef "M_J_DQS_DP<4>") )
				( member ( signalRef "M_J_DQS_DP<5>") )
				( member ( signalRef "M_J_DQS_DP<6>") )
				( member ( signalRef "M_J_DQS_DP<7>") )
				( member ( signalRef "M_J_DQS_DP<8>") )
				( member ( signalRef "M_J_DQS_DP<9>") )
				( member ( signalRef "M_J_DQS_DP<10>") )
				( member ( signalRef "M_J_DQS_DP<11>") )
				( member ( signalRef "M_J_DQS_DP<12>") )
				( member ( signalRef "M_J_DQS_DP<13>") )
				( member ( signalRef "M_J_DQS_DP<14>") )
				( member ( signalRef "M_J_DQS_DP<15>") )
				( member ( signalRef "M_J_DQS_DP<16>") )
				( member ( signalRef "M_J_DQS_DP<17>") )
				( objectStatus "@baseboard_fab2_lib.baseboard_fab2(sch_1):m_j_dqs_dp" )
			)
			( bus "M_J_ECC"
				( memberType ( signal ) )
				( member ( signalRef "M_J_ECC<0>") )
				( member ( signalRef "M_J_ECC<1>") )
				( member ( signalRef "M_J_ECC<2>") )
				( member ( signalRef "M_J_ECC<3>") )
				( member ( signalRef "M_J_ECC<4>") )
				( member ( signalRef "M_J_ECC<5>") )
				( member ( signalRef "M_J_ECC<6>") )
				( member ( signalRef "M_J_ECC<7>") )
				( objectStatus "@baseboard_fab2_lib.baseboard_fab2(sch_1):m_j_ecc" )
			)
			( bus "M_J_MA"
				( memberType ( signal ) )
				( member ( signalRef "M_J_MA<0>") )
				( member ( signalRef "M_J_MA<1>") )
				( member ( signalRef "M_J_MA<2>") )
				( member ( signalRef "M_J_MA<3>") )
				( member ( signalRef "M_J_MA<4>") )
				( member ( signalRef "M_J_MA<5>") )
				( member ( signalRef "M_J_MA<6>") )
				( member ( signalRef "M_J_MA<7>") )
				( member ( signalRef "M_J_MA<8>") )
				( member ( signalRef "M_J_MA<9>") )
				( member ( signalRef "M_J_MA<10>") )
				( member ( signalRef "M_J_MA<11>") )
				( member ( signalRef "M_J_MA<12>") )
				( member ( signalRef "M_J_MA<13>") )
				( member ( signalRef "M_J_MA<14>") )
				( member ( signalRef "M_J_MA<15>") )
				( member ( signalRef "M_J_MA<16>") )
				( member ( signalRef "M_J_MA<17>") )
				( objectStatus "@baseboard_fab2_lib.baseboard_fab2(sch_1):m_j_ma" )
			)
			( bus "M_J_ODT"
				( memberType ( signal ) )
				( member ( signalRef "M_J_ODT<0>") )
				( member ( signalRef "M_J_ODT<1>") )
				( member ( signalRef "M_J_ODT<2>") )
				( member ( signalRef "M_J_ODT<3>") )
				( objectStatus "@baseboard_fab2_lib.baseboard_fab2(sch_1):m_j_odt" )
			)
			( bus "M_K_BA"
				( memberType ( signal ) )
				( member ( signalRef "M_K_BA<0>") )
				( member ( signalRef "M_K_BA<1>") )
				( objectStatus "@baseboard_fab2_lib.baseboard_fab2(sch_1):m_k_ba" )
			)
			( bus "M_K_BG"
				( memberType ( signal ) )
				( member ( signalRef "M_K_BG<0>") )
				( member ( signalRef "M_K_BG<1>") )
				( objectStatus "@baseboard_fab2_lib.baseboard_fab2(sch_1):m_k_bg" )
			)
			( bus "M_K_C"
				( memberType ( signal ) )
				( member ( signalRef "M_K_C<2>") )
				( objectStatus "@baseboard_fab2_lib.baseboard_fab2(sch_1):m_k_c" )
			)
			( bus "M_K_CKE"
				( memberType ( signal ) )
				( member ( signalRef "M_K_CKE<0>") )
				( member ( signalRef "M_K_CKE<1>") )
				( member ( signalRef "M_K_CKE<2>") )
				( member ( signalRef "M_K_CKE<3>") )
				( objectStatus "@baseboard_fab2_lib.baseboard_fab2(sch_1):m_k_cke" )
			)
			( bus "M_K_CLK_DN"
				( memberType ( signal ) )
				( member ( signalRef "M_K_CLK_DN<0>") )
				( member ( signalRef "M_K_CLK_DN<1>") )
				( member ( signalRef "M_K_CLK_DN<2>") )
				( member ( signalRef "M_K_CLK_DN<3>") )
				( objectStatus "@baseboard_fab2_lib.baseboard_fab2(sch_1):m_k_clk_dn" )
			)
			( bus "M_K_CLK_DP"
				( memberType ( signal ) )
				( member ( signalRef "M_K_CLK_DP<0>") )
				( member ( signalRef "M_K_CLK_DP<1>") )
				( member ( signalRef "M_K_CLK_DP<2>") )
				( member ( signalRef "M_K_CLK_DP<3>") )
				( objectStatus "@baseboard_fab2_lib.baseboard_fab2(sch_1):m_k_clk_dp" )
			)
			( bus "M_K_CS_N"
				( memberType ( signal ) )
				( member ( signalRef "M_K_CS_N<0>") )
				( member ( signalRef "M_K_CS_N<1>") )
				( member ( signalRef "M_K_CS_N<2>") )
				( member ( signalRef "M_K_CS_N<3>") )
				( member ( signalRef "M_K_CS_N<4>") )
				( member ( signalRef "M_K_CS_N<5>") )
				( member ( signalRef "M_K_CS_N<6>") )
				( member ( signalRef "M_K_CS_N<7>") )
				( objectStatus "@baseboard_fab2_lib.baseboard_fab2(sch_1):m_k_cs_n" )
			)
			( bus "M_K_DQ"
				( memberType ( signal ) )
				( member ( signalRef "M_K_DQ<0>") )
				( member ( signalRef "M_K_DQ<1>") )
				( member ( signalRef "M_K_DQ<2>") )
				( member ( signalRef "M_K_DQ<3>") )
				( member ( signalRef "M_K_DQ<4>") )
				( member ( signalRef "M_K_DQ<5>") )
				( member ( signalRef "M_K_DQ<6>") )
				( member ( signalRef "M_K_DQ<7>") )
				( member ( signalRef "M_K_DQ<8>") )
				( member ( signalRef "M_K_DQ<9>") )
				( member ( signalRef "M_K_DQ<10>") )
				( member ( signalRef "M_K_DQ<11>") )
				( member ( signalRef "M_K_DQ<12>") )
				( member ( signalRef "M_K_DQ<13>") )
				( member ( signalRef "M_K_DQ<14>") )
				( member ( signalRef "M_K_DQ<15>") )
				( member ( signalRef "M_K_DQ<16>") )
				( member ( signalRef "M_K_DQ<17>") )
				( member ( signalRef "M_K_DQ<18>") )
				( member ( signalRef "M_K_DQ<19>") )
				( member ( signalRef "M_K_DQ<20>") )
				( member ( signalRef "M_K_DQ<21>") )
				( member ( signalRef "M_K_DQ<22>") )
				( member ( signalRef "M_K_DQ<23>") )
				( member ( signalRef "M_K_DQ<24>") )
				( member ( signalRef "M_K_DQ<25>") )
				( member ( signalRef "M_K_DQ<26>") )
				( member ( signalRef "M_K_DQ<27>") )
				( member ( signalRef "M_K_DQ<28>") )
				( member ( signalRef "M_K_DQ<29>") )
				( member ( signalRef "M_K_DQ<30>") )
				( member ( signalRef "M_K_DQ<31>") )
				( member ( signalRef "M_K_DQ<32>") )
				( member ( signalRef "M_K_DQ<33>") )
				( member ( signalRef "M_K_DQ<34>") )
				( member ( signalRef "M_K_DQ<35>") )
				( member ( signalRef "M_K_DQ<36>") )
				( member ( signalRef "M_K_DQ<37>") )
				( member ( signalRef "M_K_DQ<38>") )
				( member ( signalRef "M_K_DQ<39>") )
				( member ( signalRef "M_K_DQ<40>") )
				( member ( signalRef "M_K_DQ<41>") )
				( member ( signalRef "M_K_DQ<42>") )
				( member ( signalRef "M_K_DQ<43>") )
				( member ( signalRef "M_K_DQ<44>") )
				( member ( signalRef "M_K_DQ<45>") )
				( member ( signalRef "M_K_DQ<46>") )
				( member ( signalRef "M_K_DQ<47>") )
				( member ( signalRef "M_K_DQ<48>") )
				( member ( signalRef "M_K_DQ<49>") )
				( member ( signalRef "M_K_DQ<50>") )
				( member ( signalRef "M_K_DQ<51>") )
				( member ( signalRef "M_K_DQ<52>") )
				( member ( signalRef "M_K_DQ<53>") )
				( member ( signalRef "M_K_DQ<54>") )
				( member ( signalRef "M_K_DQ<55>") )
				( member ( signalRef "M_K_DQ<56>") )
				( member ( signalRef "M_K_DQ<57>") )
				( member ( signalRef "M_K_DQ<58>") )
				( member ( signalRef "M_K_DQ<59>") )
				( member ( signalRef "M_K_DQ<60>") )
				( member ( signalRef "M_K_DQ<61>") )
				( member ( signalRef "M_K_DQ<62>") )
				( member ( signalRef "M_K_DQ<63>") )
				( objectStatus "@baseboard_fab2_lib.baseboard_fab2(sch_1):m_k_dq" )
			)
			( bus "M_K_DQS_DN"
				( memberType ( signal ) )
				( member ( signalRef "M_K_DQS_DN<0>") )
				( member ( signalRef "M_K_DQS_DN<1>") )
				( member ( signalRef "M_K_DQS_DN<2>") )
				( member ( signalRef "M_K_DQS_DN<3>") )
				( member ( signalRef "M_K_DQS_DN<4>") )
				( member ( signalRef "M_K_DQS_DN<5>") )
				( member ( signalRef "M_K_DQS_DN<6>") )
				( member ( signalRef "M_K_DQS_DN<7>") )
				( member ( signalRef "M_K_DQS_DN<8>") )
				( member ( signalRef "M_K_DQS_DN<9>") )
				( member ( signalRef "M_K_DQS_DN<10>") )
				( member ( signalRef "M_K_DQS_DN<11>") )
				( member ( signalRef "M_K_DQS_DN<12>") )
				( member ( signalRef "M_K_DQS_DN<13>") )
				( member ( signalRef "M_K_DQS_DN<14>") )
				( member ( signalRef "M_K_DQS_DN<15>") )
				( member ( signalRef "M_K_DQS_DN<16>") )
				( member ( signalRef "M_K_DQS_DN<17>") )
				( objectStatus "@baseboard_fab2_lib.baseboard_fab2(sch_1):m_k_dqs_dn" )
			)
			( bus "M_K_DQS_DP"
				( memberType ( signal ) )
				( member ( signalRef "M_K_DQS_DP<0>") )
				( member ( signalRef "M_K_DQS_DP<1>") )
				( member ( signalRef "M_K_DQS_DP<2>") )
				( member ( signalRef "M_K_DQS_DP<3>") )
				( member ( signalRef "M_K_DQS_DP<4>") )
				( member ( signalRef "M_K_DQS_DP<5>") )
				( member ( signalRef "M_K_DQS_DP<6>") )
				( member ( signalRef "M_K_DQS_DP<7>") )
				( member ( signalRef "M_K_DQS_DP<8>") )
				( member ( signalRef "M_K_DQS_DP<9>") )
				( member ( signalRef "M_K_DQS_DP<10>") )
				( member ( signalRef "M_K_DQS_DP<11>") )
				( member ( signalRef "M_K_DQS_DP<12>") )
				( member ( signalRef "M_K_DQS_DP<13>") )
				( member ( signalRef "M_K_DQS_DP<14>") )
				( member ( signalRef "M_K_DQS_DP<15>") )
				( member ( signalRef "M_K_DQS_DP<16>") )
				( member ( signalRef "M_K_DQS_DP<17>") )
				( objectStatus "@baseboard_fab2_lib.baseboard_fab2(sch_1):m_k_dqs_dp" )
			)
			( bus "M_K_ECC"
				( memberType ( signal ) )
				( member ( signalRef "M_K_ECC<0>") )
				( member ( signalRef "M_K_ECC<1>") )
				( member ( signalRef "M_K_ECC<2>") )
				( member ( signalRef "M_K_ECC<3>") )
				( member ( signalRef "M_K_ECC<4>") )
				( member ( signalRef "M_K_ECC<5>") )
				( member ( signalRef "M_K_ECC<6>") )
				( member ( signalRef "M_K_ECC<7>") )
				( objectStatus "@baseboard_fab2_lib.baseboard_fab2(sch_1):m_k_ecc" )
			)
			( bus "M_K_MA"
				( memberType ( signal ) )
				( member ( signalRef "M_K_MA<0>") )
				( member ( signalRef "M_K_MA<1>") )
				( member ( signalRef "M_K_MA<2>") )
				( member ( signalRef "M_K_MA<3>") )
				( member ( signalRef "M_K_MA<4>") )
				( member ( signalRef "M_K_MA<5>") )
				( member ( signalRef "M_K_MA<6>") )
				( member ( signalRef "M_K_MA<7>") )
				( member ( signalRef "M_K_MA<8>") )
				( member ( signalRef "M_K_MA<9>") )
				( member ( signalRef "M_K_MA<10>") )
				( member ( signalRef "M_K_MA<11>") )
				( member ( signalRef "M_K_MA<12>") )
				( member ( signalRef "M_K_MA<13>") )
				( member ( signalRef "M_K_MA<14>") )
				( member ( signalRef "M_K_MA<15>") )
				( member ( signalRef "M_K_MA<16>") )
				( member ( signalRef "M_K_MA<17>") )
				( objectStatus "@baseboard_fab2_lib.baseboard_fab2(sch_1):m_k_ma" )
			)
			( bus "M_K_ODT"
				( memberType ( signal ) )
				( member ( signalRef "M_K_ODT<0>") )
				( member ( signalRef "M_K_ODT<1>") )
				( member ( signalRef "M_K_ODT<2>") )
				( member ( signalRef "M_K_ODT<3>") )
				( objectStatus "@baseboard_fab2_lib.baseboard_fab2(sch_1):m_k_odt" )
			)
			( bus "M_L_BA"
				( memberType ( signal ) )
				( member ( signalRef "M_L_BA<0>") )
				( member ( signalRef "M_L_BA<1>") )
				( objectStatus "@baseboard_fab2_lib.baseboard_fab2(sch_1):m_l_ba" )
			)
			( bus "M_L_BG"
				( memberType ( signal ) )
				( member ( signalRef "M_L_BG<0>") )
				( member ( signalRef "M_L_BG<1>") )
				( objectStatus "@baseboard_fab2_lib.baseboard_fab2(sch_1):m_l_bg" )
			)
			( bus "M_L_C"
				( memberType ( signal ) )
				( member ( signalRef "M_L_C<2>") )
				( objectStatus "@baseboard_fab2_lib.baseboard_fab2(sch_1):m_l_c" )
			)
			( bus "M_L_CKE"
				( memberType ( signal ) )
				( member ( signalRef "M_L_CKE<0>") )
				( member ( signalRef "M_L_CKE<1>") )
				( member ( signalRef "M_L_CKE<2>") )
				( member ( signalRef "M_L_CKE<3>") )
				( objectStatus "@baseboard_fab2_lib.baseboard_fab2(sch_1):m_l_cke" )
			)
			( bus "M_L_CLK_DN"
				( memberType ( signal ) )
				( member ( signalRef "M_L_CLK_DN<0>") )
				( member ( signalRef "M_L_CLK_DN<1>") )
				( member ( signalRef "M_L_CLK_DN<2>") )
				( member ( signalRef "M_L_CLK_DN<3>") )
				( objectStatus "@baseboard_fab2_lib.baseboard_fab2(sch_1):m_l_clk_dn" )
			)
			( bus "M_L_CLK_DP"
				( memberType ( signal ) )
				( member ( signalRef "M_L_CLK_DP<0>") )
				( member ( signalRef "M_L_CLK_DP<1>") )
				( member ( signalRef "M_L_CLK_DP<2>") )
				( member ( signalRef "M_L_CLK_DP<3>") )
				( objectStatus "@baseboard_fab2_lib.baseboard_fab2(sch_1):m_l_clk_dp" )
			)
			( bus "M_L_CS_N"
				( memberType ( signal ) )
				( member ( signalRef "M_L_CS_N<0>") )
				( member ( signalRef "M_L_CS_N<1>") )
				( member ( signalRef "M_L_CS_N<2>") )
				( member ( signalRef "M_L_CS_N<3>") )
				( member ( signalRef "M_L_CS_N<4>") )
				( member ( signalRef "M_L_CS_N<5>") )
				( member ( signalRef "M_L_CS_N<6>") )
				( member ( signalRef "M_L_CS_N<7>") )
				( objectStatus "@baseboard_fab2_lib.baseboard_fab2(sch_1):m_l_cs_n" )
			)
			( bus "M_L_DQ"
				( memberType ( signal ) )
				( member ( signalRef "M_L_DQ<0>") )
				( member ( signalRef "M_L_DQ<1>") )
				( member ( signalRef "M_L_DQ<2>") )
				( member ( signalRef "M_L_DQ<3>") )
				( member ( signalRef "M_L_DQ<4>") )
				( member ( signalRef "M_L_DQ<5>") )
				( member ( signalRef "M_L_DQ<6>") )
				( member ( signalRef "M_L_DQ<7>") )
				( member ( signalRef "M_L_DQ<8>") )
				( member ( signalRef "M_L_DQ<9>") )
				( member ( signalRef "M_L_DQ<10>") )
				( member ( signalRef "M_L_DQ<11>") )
				( member ( signalRef "M_L_DQ<12>") )
				( member ( signalRef "M_L_DQ<13>") )
				( member ( signalRef "M_L_DQ<14>") )
				( member ( signalRef "M_L_DQ<15>") )
				( member ( signalRef "M_L_DQ<16>") )
				( member ( signalRef "M_L_DQ<17>") )
				( member ( signalRef "M_L_DQ<18>") )
				( member ( signalRef "M_L_DQ<19>") )
				( member ( signalRef "M_L_DQ<20>") )
				( member ( signalRef "M_L_DQ<21>") )
				( member ( signalRef "M_L_DQ<22>") )
				( member ( signalRef "M_L_DQ<23>") )
				( member ( signalRef "M_L_DQ<24>") )
				( member ( signalRef "M_L_DQ<25>") )
				( member ( signalRef "M_L_DQ<26>") )
				( member ( signalRef "M_L_DQ<27>") )
				( member ( signalRef "M_L_DQ<28>") )
				( member ( signalRef "M_L_DQ<29>") )
				( member ( signalRef "M_L_DQ<30>") )
				( member ( signalRef "M_L_DQ<31>") )
				( member ( signalRef "M_L_DQ<32>") )
				( member ( signalRef "M_L_DQ<33>") )
				( member ( signalRef "M_L_DQ<34>") )
				( member ( signalRef "M_L_DQ<35>") )
				( member ( signalRef "M_L_DQ<36>") )
				( member ( signalRef "M_L_DQ<37>") )
				( member ( signalRef "M_L_DQ<38>") )
				( member ( signalRef "M_L_DQ<39>") )
				( member ( signalRef "M_L_DQ<40>") )
				( member ( signalRef "M_L_DQ<41>") )
				( member ( signalRef "M_L_DQ<42>") )
				( member ( signalRef "M_L_DQ<43>") )
				( member ( signalRef "M_L_DQ<44>") )
				( member ( signalRef "M_L_DQ<45>") )
				( member ( signalRef "M_L_DQ<46>") )
				( member ( signalRef "M_L_DQ<47>") )
				( member ( signalRef "M_L_DQ<48>") )
				( member ( signalRef "M_L_DQ<49>") )
				( member ( signalRef "M_L_DQ<50>") )
				( member ( signalRef "M_L_DQ<51>") )
				( member ( signalRef "M_L_DQ<52>") )
				( member ( signalRef "M_L_DQ<53>") )
				( member ( signalRef "M_L_DQ<54>") )
				( member ( signalRef "M_L_DQ<55>") )
				( member ( signalRef "M_L_DQ<56>") )
				( member ( signalRef "M_L_DQ<57>") )
				( member ( signalRef "M_L_DQ<58>") )
				( member ( signalRef "M_L_DQ<59>") )
				( member ( signalRef "M_L_DQ<60>") )
				( member ( signalRef "M_L_DQ<61>") )
				( member ( signalRef "M_L_DQ<62>") )
				( member ( signalRef "M_L_DQ<63>") )
				( objectStatus "@baseboard_fab2_lib.baseboard_fab2(sch_1):m_l_dq" )
			)
			( bus "M_L_DQS_DN"
				( memberType ( signal ) )
				( member ( signalRef "M_L_DQS_DN<0>") )
				( member ( signalRef "M_L_DQS_DN<1>") )
				( member ( signalRef "M_L_DQS_DN<2>") )
				( member ( signalRef "M_L_DQS_DN<3>") )
				( member ( signalRef "M_L_DQS_DN<4>") )
				( member ( signalRef "M_L_DQS_DN<5>") )
				( member ( signalRef "M_L_DQS_DN<6>") )
				( member ( signalRef "M_L_DQS_DN<7>") )
				( member ( signalRef "M_L_DQS_DN<8>") )
				( member ( signalRef "M_L_DQS_DN<9>") )
				( member ( signalRef "M_L_DQS_DN<10>") )
				( member ( signalRef "M_L_DQS_DN<11>") )
				( member ( signalRef "M_L_DQS_DN<12>") )
				( member ( signalRef "M_L_DQS_DN<13>") )
				( member ( signalRef "M_L_DQS_DN<14>") )
				( member ( signalRef "M_L_DQS_DN<15>") )
				( member ( signalRef "M_L_DQS_DN<16>") )
				( member ( signalRef "M_L_DQS_DN<17>") )
				( objectStatus "@baseboard_fab2_lib.baseboard_fab2(sch_1):m_l_dqs_dn" )
			)
			( bus "M_L_DQS_DP"
				( memberType ( signal ) )
				( member ( signalRef "M_L_DQS_DP<0>") )
				( member ( signalRef "M_L_DQS_DP<1>") )
				( member ( signalRef "M_L_DQS_DP<2>") )
				( member ( signalRef "M_L_DQS_DP<3>") )
				( member ( signalRef "M_L_DQS_DP<4>") )
				( member ( signalRef "M_L_DQS_DP<5>") )
				( member ( signalRef "M_L_DQS_DP<6>") )
				( member ( signalRef "M_L_DQS_DP<7>") )
				( member ( signalRef "M_L_DQS_DP<8>") )
				( member ( signalRef "M_L_DQS_DP<9>") )
				( member ( signalRef "M_L_DQS_DP<10>") )
				( member ( signalRef "M_L_DQS_DP<11>") )
				( member ( signalRef "M_L_DQS_DP<12>") )
				( member ( signalRef "M_L_DQS_DP<13>") )
				( member ( signalRef "M_L_DQS_DP<14>") )
				( member ( signalRef "M_L_DQS_DP<15>") )
				( member ( signalRef "M_L_DQS_DP<16>") )
				( member ( signalRef "M_L_DQS_DP<17>") )
				( objectStatus "@baseboard_fab2_lib.baseboard_fab2(sch_1):m_l_dqs_dp" )
			)
			( bus "M_L_ECC"
				( memberType ( signal ) )
				( member ( signalRef "M_L_ECC<0>") )
				( member ( signalRef "M_L_ECC<1>") )
				( member ( signalRef "M_L_ECC<2>") )
				( member ( signalRef "M_L_ECC<3>") )
				( member ( signalRef "M_L_ECC<4>") )
				( member ( signalRef "M_L_ECC<5>") )
				( member ( signalRef "M_L_ECC<6>") )
				( member ( signalRef "M_L_ECC<7>") )
				( objectStatus "@baseboard_fab2_lib.baseboard_fab2(sch_1):m_l_ecc" )
			)
			( bus "M_L_MA"
				( memberType ( signal ) )
				( member ( signalRef "M_L_MA<0>") )
				( member ( signalRef "M_L_MA<1>") )
				( member ( signalRef "M_L_MA<2>") )
				( member ( signalRef "M_L_MA<3>") )
				( member ( signalRef "M_L_MA<4>") )
				( member ( signalRef "M_L_MA<5>") )
				( member ( signalRef "M_L_MA<6>") )
				( member ( signalRef "M_L_MA<7>") )
				( member ( signalRef "M_L_MA<8>") )
				( member ( signalRef "M_L_MA<9>") )
				( member ( signalRef "M_L_MA<10>") )
				( member ( signalRef "M_L_MA<11>") )
				( member ( signalRef "M_L_MA<12>") )
				( member ( signalRef "M_L_MA<13>") )
				( member ( signalRef "M_L_MA<14>") )
				( member ( signalRef "M_L_MA<15>") )
				( member ( signalRef "M_L_MA<16>") )
				( member ( signalRef "M_L_MA<17>") )
				( objectStatus "@baseboard_fab2_lib.baseboard_fab2(sch_1):m_l_ma" )
			)
			( bus "M_L_ODT"
				( memberType ( signal ) )
				( member ( signalRef "M_L_ODT<0>") )
				( member ( signalRef "M_L_ODT<1>") )
				( member ( signalRef "M_L_ODT<2>") )
				( member ( signalRef "M_L_ODT<3>") )
				( objectStatus "@baseboard_fab2_lib.baseboard_fab2(sch_1):m_l_odt" )
			)
			( bus "M_M_BA"
				( memberType ( signal ) )
				( member ( signalRef "M_M_BA<0>") )
				( member ( signalRef "M_M_BA<1>") )
				( objectStatus "@baseboard_fab2_lib.baseboard_fab2(sch_1):m_m_ba" )
			)
			( bus "M_M_BG"
				( memberType ( signal ) )
				( member ( signalRef "M_M_BG<0>") )
				( member ( signalRef "M_M_BG<1>") )
				( objectStatus "@baseboard_fab2_lib.baseboard_fab2(sch_1):m_m_bg" )
			)
			( bus "M_M_C"
				( memberType ( signal ) )
				( member ( signalRef "M_M_C<2>") )
				( objectStatus "@baseboard_fab2_lib.baseboard_fab2(sch_1):m_m_c" )
			)
			( bus "M_M_CKE"
				( memberType ( signal ) )
				( member ( signalRef "M_M_CKE<0>") )
				( member ( signalRef "M_M_CKE<1>") )
				( member ( signalRef "M_M_CKE<2>") )
				( member ( signalRef "M_M_CKE<3>") )
				( objectStatus "@baseboard_fab2_lib.baseboard_fab2(sch_1):m_m_cke" )
			)
			( bus "M_M_CLK_DN"
				( memberType ( signal ) )
				( member ( signalRef "M_M_CLK_DN<0>") )
				( member ( signalRef "M_M_CLK_DN<1>") )
				( member ( signalRef "M_M_CLK_DN<2>") )
				( member ( signalRef "M_M_CLK_DN<3>") )
				( objectStatus "@baseboard_fab2_lib.baseboard_fab2(sch_1):m_m_clk_dn" )
			)
			( bus "M_M_CLK_DP"
				( memberType ( signal ) )
				( member ( signalRef "M_M_CLK_DP<0>") )
				( member ( signalRef "M_M_CLK_DP<1>") )
				( member ( signalRef "M_M_CLK_DP<2>") )
				( member ( signalRef "M_M_CLK_DP<3>") )
				( objectStatus "@baseboard_fab2_lib.baseboard_fab2(sch_1):m_m_clk_dp" )
			)
			( bus "M_M_CS_N"
				( memberType ( signal ) )
				( member ( signalRef "M_M_CS_N<0>") )
				( member ( signalRef "M_M_CS_N<1>") )
				( member ( signalRef "M_M_CS_N<2>") )
				( member ( signalRef "M_M_CS_N<3>") )
				( member ( signalRef "M_M_CS_N<4>") )
				( member ( signalRef "M_M_CS_N<5>") )
				( member ( signalRef "M_M_CS_N<6>") )
				( member ( signalRef "M_M_CS_N<7>") )
				( objectStatus "@baseboard_fab2_lib.baseboard_fab2(sch_1):m_m_cs_n" )
			)
			( bus "M_M_DQ"
				( memberType ( signal ) )
				( member ( signalRef "M_M_DQ<0>") )
				( member ( signalRef "M_M_DQ<1>") )
				( member ( signalRef "M_M_DQ<2>") )
				( member ( signalRef "M_M_DQ<3>") )
				( member ( signalRef "M_M_DQ<4>") )
				( member ( signalRef "M_M_DQ<5>") )
				( member ( signalRef "M_M_DQ<6>") )
				( member ( signalRef "M_M_DQ<7>") )
				( member ( signalRef "M_M_DQ<8>") )
				( member ( signalRef "M_M_DQ<9>") )
				( member ( signalRef "M_M_DQ<10>") )
				( member ( signalRef "M_M_DQ<11>") )
				( member ( signalRef "M_M_DQ<12>") )
				( member ( signalRef "M_M_DQ<13>") )
				( member ( signalRef "M_M_DQ<14>") )
				( member ( signalRef "M_M_DQ<15>") )
				( member ( signalRef "M_M_DQ<16>") )
				( member ( signalRef "M_M_DQ<17>") )
				( member ( signalRef "M_M_DQ<18>") )
				( member ( signalRef "M_M_DQ<19>") )
				( member ( signalRef "M_M_DQ<20>") )
				( member ( signalRef "M_M_DQ<21>") )
				( member ( signalRef "M_M_DQ<22>") )
				( member ( signalRef "M_M_DQ<23>") )
				( member ( signalRef "M_M_DQ<24>") )
				( member ( signalRef "M_M_DQ<25>") )
				( member ( signalRef "M_M_DQ<26>") )
				( member ( signalRef "M_M_DQ<27>") )
				( member ( signalRef "M_M_DQ<28>") )
				( member ( signalRef "M_M_DQ<29>") )
				( member ( signalRef "M_M_DQ<30>") )
				( member ( signalRef "M_M_DQ<31>") )
				( member ( signalRef "M_M_DQ<32>") )
				( member ( signalRef "M_M_DQ<33>") )
				( member ( signalRef "M_M_DQ<34>") )
				( member ( signalRef "M_M_DQ<35>") )
				( member ( signalRef "M_M_DQ<36>") )
				( member ( signalRef "M_M_DQ<37>") )
				( member ( signalRef "M_M_DQ<38>") )
				( member ( signalRef "M_M_DQ<39>") )
				( member ( signalRef "M_M_DQ<40>") )
				( member ( signalRef "M_M_DQ<41>") )
				( member ( signalRef "M_M_DQ<42>") )
				( member ( signalRef "M_M_DQ<43>") )
				( member ( signalRef "M_M_DQ<44>") )
				( member ( signalRef "M_M_DQ<45>") )
				( member ( signalRef "M_M_DQ<46>") )
				( member ( signalRef "M_M_DQ<47>") )
				( member ( signalRef "M_M_DQ<48>") )
				( member ( signalRef "M_M_DQ<49>") )
				( member ( signalRef "M_M_DQ<50>") )
				( member ( signalRef "M_M_DQ<51>") )
				( member ( signalRef "M_M_DQ<52>") )
				( member ( signalRef "M_M_DQ<53>") )
				( member ( signalRef "M_M_DQ<54>") )
				( member ( signalRef "M_M_DQ<55>") )
				( member ( signalRef "M_M_DQ<56>") )
				( member ( signalRef "M_M_DQ<57>") )
				( member ( signalRef "M_M_DQ<58>") )
				( member ( signalRef "M_M_DQ<59>") )
				( member ( signalRef "M_M_DQ<60>") )
				( member ( signalRef "M_M_DQ<61>") )
				( member ( signalRef "M_M_DQ<62>") )
				( member ( signalRef "M_M_DQ<63>") )
				( objectStatus "@baseboard_fab2_lib.baseboard_fab2(sch_1):m_m_dq" )
			)
			( bus "M_M_DQS_DN"
				( memberType ( signal ) )
				( member ( signalRef "M_M_DQS_DN<0>") )
				( member ( signalRef "M_M_DQS_DN<1>") )
				( member ( signalRef "M_M_DQS_DN<2>") )
				( member ( signalRef "M_M_DQS_DN<3>") )
				( member ( signalRef "M_M_DQS_DN<4>") )
				( member ( signalRef "M_M_DQS_DN<5>") )
				( member ( signalRef "M_M_DQS_DN<6>") )
				( member ( signalRef "M_M_DQS_DN<7>") )
				( member ( signalRef "M_M_DQS_DN<8>") )
				( member ( signalRef "M_M_DQS_DN<9>") )
				( member ( signalRef "M_M_DQS_DN<10>") )
				( member ( signalRef "M_M_DQS_DN<11>") )
				( member ( signalRef "M_M_DQS_DN<12>") )
				( member ( signalRef "M_M_DQS_DN<13>") )
				( member ( signalRef "M_M_DQS_DN<14>") )
				( member ( signalRef "M_M_DQS_DN<15>") )
				( member ( signalRef "M_M_DQS_DN<16>") )
				( member ( signalRef "M_M_DQS_DN<17>") )
				( objectStatus "@baseboard_fab2_lib.baseboard_fab2(sch_1):m_m_dqs_dn" )
			)
			( bus "M_M_DQS_DP"
				( memberType ( signal ) )
				( member ( signalRef "M_M_DQS_DP<0>") )
				( member ( signalRef "M_M_DQS_DP<1>") )
				( member ( signalRef "M_M_DQS_DP<2>") )
				( member ( signalRef "M_M_DQS_DP<3>") )
				( member ( signalRef "M_M_DQS_DP<4>") )
				( member ( signalRef "M_M_DQS_DP<5>") )
				( member ( signalRef "M_M_DQS_DP<6>") )
				( member ( signalRef "M_M_DQS_DP<7>") )
				( member ( signalRef "M_M_DQS_DP<8>") )
				( member ( signalRef "M_M_DQS_DP<9>") )
				( member ( signalRef "M_M_DQS_DP<10>") )
				( member ( signalRef "M_M_DQS_DP<11>") )
				( member ( signalRef "M_M_DQS_DP<12>") )
				( member ( signalRef "M_M_DQS_DP<13>") )
				( member ( signalRef "M_M_DQS_DP<14>") )
				( member ( signalRef "M_M_DQS_DP<15>") )
				( member ( signalRef "M_M_DQS_DP<16>") )
				( member ( signalRef "M_M_DQS_DP<17>") )
				( objectStatus "@baseboard_fab2_lib.baseboard_fab2(sch_1):m_m_dqs_dp" )
			)
			( bus "M_M_ECC"
				( memberType ( signal ) )
				( member ( signalRef "M_M_ECC<0>") )
				( member ( signalRef "M_M_ECC<1>") )
				( member ( signalRef "M_M_ECC<2>") )
				( member ( signalRef "M_M_ECC<3>") )
				( member ( signalRef "M_M_ECC<4>") )
				( member ( signalRef "M_M_ECC<5>") )
				( member ( signalRef "M_M_ECC<6>") )
				( member ( signalRef "M_M_ECC<7>") )
				( objectStatus "@baseboard_fab2_lib.baseboard_fab2(sch_1):m_m_ecc" )
			)
			( bus "M_M_MA"
				( memberType ( signal ) )
				( member ( signalRef "M_M_MA<0>") )
				( member ( signalRef "M_M_MA<1>") )
				( member ( signalRef "M_M_MA<2>") )
				( member ( signalRef "M_M_MA<3>") )
				( member ( signalRef "M_M_MA<4>") )
				( member ( signalRef "M_M_MA<5>") )
				( member ( signalRef "M_M_MA<6>") )
				( member ( signalRef "M_M_MA<7>") )
				( member ( signalRef "M_M_MA<8>") )
				( member ( signalRef "M_M_MA<9>") )
				( member ( signalRef "M_M_MA<10>") )
				( member ( signalRef "M_M_MA<11>") )
				( member ( signalRef "M_M_MA<12>") )
				( member ( signalRef "M_M_MA<13>") )
				( member ( signalRef "M_M_MA<14>") )
				( member ( signalRef "M_M_MA<15>") )
				( member ( signalRef "M_M_MA<16>") )
				( member ( signalRef "M_M_MA<17>") )
				( objectStatus "@baseboard_fab2_lib.baseboard_fab2(sch_1):m_m_ma" )
			)
			( bus "M_M_ODT"
				( memberType ( signal ) )
				( member ( signalRef "M_M_ODT<0>") )
				( member ( signalRef "M_M_ODT<1>") )
				( member ( signalRef "M_M_ODT<2>") )
				( member ( signalRef "M_M_ODT<3>") )
				( objectStatus "@baseboard_fab2_lib.baseboard_fab2(sch_1):m_m_odt" )
			)
			( bus "TP_P3E_CPU1_PE1_MP_RXN"
				( memberType ( signal ) )
				( member ( signalRef "TP_P3E_CPU1_PE1_MP_RXN<0>") )
				( member ( signalRef "TP_P3E_CPU1_PE1_MP_RXN<1>") )
				( member ( signalRef "TP_P3E_CPU1_PE1_MP_RXN<2>") )
				( member ( signalRef "TP_P3E_CPU1_PE1_MP_RXN<3>") )
				( member ( signalRef "TP_P3E_CPU1_PE1_MP_RXN<4>") )
				( member ( signalRef "TP_P3E_CPU1_PE1_MP_RXN<5>") )
				( member ( signalRef "TP_P3E_CPU1_PE1_MP_RXN<6>") )
				( member ( signalRef "TP_P3E_CPU1_PE1_MP_RXN<7>") )
				( objectStatus "@baseboard_fab2_lib.baseboard_fab2(sch_1):tp_p3e_cpu1_pe1_mp_rxn" )
			)
			( bus "TP_P3E_CPU1_PE1_MP_RXP"
				( memberType ( signal ) )
				( member ( signalRef "TP_P3E_CPU1_PE1_MP_RXP<0>") )
				( member ( signalRef "TP_P3E_CPU1_PE1_MP_RXP<1>") )
				( member ( signalRef "TP_P3E_CPU1_PE1_MP_RXP<2>") )
				( member ( signalRef "TP_P3E_CPU1_PE1_MP_RXP<3>") )
				( member ( signalRef "TP_P3E_CPU1_PE1_MP_RXP<4>") )
				( member ( signalRef "TP_P3E_CPU1_PE1_MP_RXP<5>") )
				( member ( signalRef "TP_P3E_CPU1_PE1_MP_RXP<6>") )
				( member ( signalRef "TP_P3E_CPU1_PE1_MP_RXP<7>") )
				( objectStatus "@baseboard_fab2_lib.baseboard_fab2(sch_1):tp_p3e_cpu1_pe1_mp_rxp" )
			)
			( bus "TP_P3E_CPU1_PE1_MP_TXN"
				( memberType ( signal ) )
				( member ( signalRef "TP_P3E_CPU1_PE1_MP_TXN<0>") )
				( member ( signalRef "TP_P3E_CPU1_PE1_MP_TXN<1>") )
				( member ( signalRef "TP_P3E_CPU1_PE1_MP_TXN<2>") )
				( member ( signalRef "TP_P3E_CPU1_PE1_MP_TXN<3>") )
				( member ( signalRef "TP_P3E_CPU1_PE1_MP_TXN<4>") )
				( member ( signalRef "TP_P3E_CPU1_PE1_MP_TXN<5>") )
				( member ( signalRef "TP_P3E_CPU1_PE1_MP_TXN<6>") )
				( member ( signalRef "TP_P3E_CPU1_PE1_MP_TXN<7>") )
				( objectStatus "@baseboard_fab2_lib.baseboard_fab2(sch_1):tp_p3e_cpu1_pe1_mp_txn" )
			)
			( bus "TP_P3E_CPU1_PE1_MP_TXP"
				( memberType ( signal ) )
				( member ( signalRef "TP_P3E_CPU1_PE1_MP_TXP<0>") )
				( member ( signalRef "TP_P3E_CPU1_PE1_MP_TXP<1>") )
				( member ( signalRef "TP_P3E_CPU1_PE1_MP_TXP<2>") )
				( member ( signalRef "TP_P3E_CPU1_PE1_MP_TXP<3>") )
				( member ( signalRef "TP_P3E_CPU1_PE1_MP_TXP<4>") )
				( member ( signalRef "TP_P3E_CPU1_PE1_MP_TXP<5>") )
				( member ( signalRef "TP_P3E_CPU1_PE1_MP_TXP<6>") )
				( member ( signalRef "TP_P3E_CPU1_PE1_MP_TXP<7>") )
				( objectStatus "@baseboard_fab2_lib.baseboard_fab2(sch_1):tp_p3e_cpu1_pe1_mp_txp" )
			)
			( bus "TP_P3E_CPU1_PE1_RSR3_RXN"
				( memberType ( signal ) )
				( member ( signalRef "TP_P3E_CPU1_PE1_RSR3_RXN<8>") )
				( member ( signalRef "TP_P3E_CPU1_PE1_RSR3_RXN<9>") )
				( member ( signalRef "TP_P3E_CPU1_PE1_RSR3_RXN<10>") )
				( member ( signalRef "TP_P3E_CPU1_PE1_RSR3_RXN<11>") )
				( member ( signalRef "TP_P3E_CPU1_PE1_RSR3_RXN<12>") )
				( member ( signalRef "TP_P3E_CPU1_PE1_RSR3_RXN<13>") )
				( member ( signalRef "TP_P3E_CPU1_PE1_RSR3_RXN<14>") )
				( member ( signalRef "TP_P3E_CPU1_PE1_RSR3_RXN<15>") )
				( objectStatus "@baseboard_fab2_lib.baseboard_fab2(sch_1):tp_p3e_cpu1_pe1_rsr3_rxn" )
			)
			( bus "TP_P3E_CPU1_PE1_RSR3_RXP"
				( memberType ( signal ) )
				( member ( signalRef "TP_P3E_CPU1_PE1_RSR3_RXP<8>") )
				( member ( signalRef "TP_P3E_CPU1_PE1_RSR3_RXP<9>") )
				( member ( signalRef "TP_P3E_CPU1_PE1_RSR3_RXP<10>") )
				( member ( signalRef "TP_P3E_CPU1_PE1_RSR3_RXP<11>") )
				( member ( signalRef "TP_P3E_CPU1_PE1_RSR3_RXP<12>") )
				( member ( signalRef "TP_P3E_CPU1_PE1_RSR3_RXP<13>") )
				( member ( signalRef "TP_P3E_CPU1_PE1_RSR3_RXP<14>") )
				( member ( signalRef "TP_P3E_CPU1_PE1_RSR3_RXP<15>") )
				( objectStatus "@baseboard_fab2_lib.baseboard_fab2(sch_1):tp_p3e_cpu1_pe1_rsr3_rxp" )
			)
			( bus "TP_P3E_CPU1_PE1_RSR3_TXN"
				( memberType ( signal ) )
				( member ( signalRef "TP_P3E_CPU1_PE1_RSR3_TXN<8>") )
				( member ( signalRef "TP_P3E_CPU1_PE1_RSR3_TXN<9>") )
				( member ( signalRef "TP_P3E_CPU1_PE1_RSR3_TXN<10>") )
				( member ( signalRef "TP_P3E_CPU1_PE1_RSR3_TXN<11>") )
				( member ( signalRef "TP_P3E_CPU1_PE1_RSR3_TXN<12>") )
				( member ( signalRef "TP_P3E_CPU1_PE1_RSR3_TXN<13>") )
				( member ( signalRef "TP_P3E_CPU1_PE1_RSR3_TXN<14>") )
				( member ( signalRef "TP_P3E_CPU1_PE1_RSR3_TXN<15>") )
				( objectStatus "@baseboard_fab2_lib.baseboard_fab2(sch_1):tp_p3e_cpu1_pe1_rsr3_txn" )
			)
			( bus "TP_P3E_CPU1_PE1_RSR3_TXP"
				( memberType ( signal ) )
				( member ( signalRef "TP_P3E_CPU1_PE1_RSR3_TXP<8>") )
				( member ( signalRef "TP_P3E_CPU1_PE1_RSR3_TXP<9>") )
				( member ( signalRef "TP_P3E_CPU1_PE1_RSR3_TXP<10>") )
				( member ( signalRef "TP_P3E_CPU1_PE1_RSR3_TXP<11>") )
				( member ( signalRef "TP_P3E_CPU1_PE1_RSR3_TXP<12>") )
				( member ( signalRef "TP_P3E_CPU1_PE1_RSR3_TXP<13>") )
				( member ( signalRef "TP_P3E_CPU1_PE1_RSR3_TXP<14>") )
				( member ( signalRef "TP_P3E_CPU1_PE1_RSR3_TXP<15>") )
				( objectStatus "@baseboard_fab2_lib.baseboard_fab2(sch_1):tp_p3e_cpu1_pe1_rsr3_txp" )
			)
			( bus "TP_P3E_CPU1_PE2_RSR_RXN"
				( memberType ( signal ) )
				( member ( signalRef "TP_P3E_CPU1_PE2_RSR_RXN<0>") )
				( member ( signalRef "TP_P3E_CPU1_PE2_RSR_RXN<1>") )
				( member ( signalRef "TP_P3E_CPU1_PE2_RSR_RXN<2>") )
				( member ( signalRef "TP_P3E_CPU1_PE2_RSR_RXN<3>") )
				( member ( signalRef "TP_P3E_CPU1_PE2_RSR_RXN<4>") )
				( member ( signalRef "TP_P3E_CPU1_PE2_RSR_RXN<5>") )
				( member ( signalRef "TP_P3E_CPU1_PE2_RSR_RXN<6>") )
				( member ( signalRef "TP_P3E_CPU1_PE2_RSR_RXN<7>") )
				( member ( signalRef "TP_P3E_CPU1_PE2_RSR_RXN<8>") )
				( member ( signalRef "TP_P3E_CPU1_PE2_RSR_RXN<9>") )
				( member ( signalRef "TP_P3E_CPU1_PE2_RSR_RXN<10>") )
				( member ( signalRef "TP_P3E_CPU1_PE2_RSR_RXN<11>") )
				( member ( signalRef "TP_P3E_CPU1_PE2_RSR_RXN<12>") )
				( member ( signalRef "TP_P3E_CPU1_PE2_RSR_RXN<13>") )
				( member ( signalRef "TP_P3E_CPU1_PE2_RSR_RXN<14>") )
				( member ( signalRef "TP_P3E_CPU1_PE2_RSR_RXN<15>") )
				( objectStatus "@baseboard_fab2_lib.baseboard_fab2(sch_1):tp_p3e_cpu1_pe2_rsr_rxn" )
			)
			( bus "TP_P3E_CPU1_PE2_RSR_RXP"
				( memberType ( signal ) )
				( member ( signalRef "TP_P3E_CPU1_PE2_RSR_RXP<0>") )
				( member ( signalRef "TP_P3E_CPU1_PE2_RSR_RXP<1>") )
				( member ( signalRef "TP_P3E_CPU1_PE2_RSR_RXP<2>") )
				( member ( signalRef "TP_P3E_CPU1_PE2_RSR_RXP<3>") )
				( member ( signalRef "TP_P3E_CPU1_PE2_RSR_RXP<4>") )
				( member ( signalRef "TP_P3E_CPU1_PE2_RSR_RXP<5>") )
				( member ( signalRef "TP_P3E_CPU1_PE2_RSR_RXP<6>") )
				( member ( signalRef "TP_P3E_CPU1_PE2_RSR_RXP<7>") )
				( member ( signalRef "TP_P3E_CPU1_PE2_RSR_RXP<8>") )
				( member ( signalRef "TP_P3E_CPU1_PE2_RSR_RXP<9>") )
				( member ( signalRef "TP_P3E_CPU1_PE2_RSR_RXP<10>") )
				( member ( signalRef "TP_P3E_CPU1_PE2_RSR_RXP<11>") )
				( member ( signalRef "TP_P3E_CPU1_PE2_RSR_RXP<12>") )
				( member ( signalRef "TP_P3E_CPU1_PE2_RSR_RXP<13>") )
				( member ( signalRef "TP_P3E_CPU1_PE2_RSR_RXP<14>") )
				( member ( signalRef "TP_P3E_CPU1_PE2_RSR_RXP<15>") )
				( objectStatus "@baseboard_fab2_lib.baseboard_fab2(sch_1):tp_p3e_cpu1_pe2_rsr_rxp" )
			)
			( bus "TP_P3E_CPU1_PE2_RSR_TXN"
				( memberType ( signal ) )
				( member ( signalRef "TP_P3E_CPU1_PE2_RSR_TXN<0>") )
				( member ( signalRef "TP_P3E_CPU1_PE2_RSR_TXN<1>") )
				( member ( signalRef "TP_P3E_CPU1_PE2_RSR_TXN<2>") )
				( member ( signalRef "TP_P3E_CPU1_PE2_RSR_TXN<3>") )
				( member ( signalRef "TP_P3E_CPU1_PE2_RSR_TXN<4>") )
				( member ( signalRef "TP_P3E_CPU1_PE2_RSR_TXN<5>") )
				( member ( signalRef "TP_P3E_CPU1_PE2_RSR_TXN<6>") )
				( member ( signalRef "TP_P3E_CPU1_PE2_RSR_TXN<7>") )
				( member ( signalRef "TP_P3E_CPU1_PE2_RSR_TXN<8>") )
				( member ( signalRef "TP_P3E_CPU1_PE2_RSR_TXN<9>") )
				( member ( signalRef "TP_P3E_CPU1_PE2_RSR_TXN<10>") )
				( member ( signalRef "TP_P3E_CPU1_PE2_RSR_TXN<11>") )
				( member ( signalRef "TP_P3E_CPU1_PE2_RSR_TXN<12>") )
				( member ( signalRef "TP_P3E_CPU1_PE2_RSR_TXN<13>") )
				( member ( signalRef "TP_P3E_CPU1_PE2_RSR_TXN<14>") )
				( member ( signalRef "TP_P3E_CPU1_PE2_RSR_TXN<15>") )
				( objectStatus "@baseboard_fab2_lib.baseboard_fab2(sch_1):tp_p3e_cpu1_pe2_rsr_txn" )
			)
			( bus "TP_P3E_CPU1_PE2_RSR_TXP"
				( memberType ( signal ) )
				( member ( signalRef "TP_P3E_CPU1_PE2_RSR_TXP<0>") )
				( member ( signalRef "TP_P3E_CPU1_PE2_RSR_TXP<1>") )
				( member ( signalRef "TP_P3E_CPU1_PE2_RSR_TXP<2>") )
				( member ( signalRef "TP_P3E_CPU1_PE2_RSR_TXP<3>") )
				( member ( signalRef "TP_P3E_CPU1_PE2_RSR_TXP<4>") )
				( member ( signalRef "TP_P3E_CPU1_PE2_RSR_TXP<5>") )
				( member ( signalRef "TP_P3E_CPU1_PE2_RSR_TXP<6>") )
				( member ( signalRef "TP_P3E_CPU1_PE2_RSR_TXP<7>") )
				( member ( signalRef "TP_P3E_CPU1_PE2_RSR_TXP<8>") )
				( member ( signalRef "TP_P3E_CPU1_PE2_RSR_TXP<9>") )
				( member ( signalRef "TP_P3E_CPU1_PE2_RSR_TXP<10>") )
				( member ( signalRef "TP_P3E_CPU1_PE2_RSR_TXP<11>") )
				( member ( signalRef "TP_P3E_CPU1_PE2_RSR_TXP<12>") )
				( member ( signalRef "TP_P3E_CPU1_PE2_RSR_TXP<13>") )
				( member ( signalRef "TP_P3E_CPU1_PE2_RSR_TXP<14>") )
				( member ( signalRef "TP_P3E_CPU1_PE2_RSR_TXP<15>") )
				( objectStatus "@baseboard_fab2_lib.baseboard_fab2(sch_1):tp_p3e_cpu1_pe2_rsr_txp" )
			)
			( bus "P3E_CPU1_PE3_MP_RXN"
				( memberType ( signal ) )
				( member ( signalRef "P3E_CPU1_PE3_MP_RXN<0>") )
				( member ( signalRef "P3E_CPU1_PE3_MP_RXN<1>") )
				( member ( signalRef "P3E_CPU1_PE3_MP_RXN<2>") )
				( member ( signalRef "P3E_CPU1_PE3_MP_RXN<3>") )
				( member ( signalRef "P3E_CPU1_PE3_MP_RXN<4>") )
				( member ( signalRef "P3E_CPU1_PE3_MP_RXN<5>") )
				( member ( signalRef "P3E_CPU1_PE3_MP_RXN<6>") )
				( member ( signalRef "P3E_CPU1_PE3_MP_RXN<7>") )
				( member ( signalRef "P3E_CPU1_PE3_MP_RXN<8>") )
				( member ( signalRef "P3E_CPU1_PE3_MP_RXN<9>") )
				( member ( signalRef "P3E_CPU1_PE3_MP_RXN<10>") )
				( member ( signalRef "P3E_CPU1_PE3_MP_RXN<11>") )
				( member ( signalRef "P3E_CPU1_PE3_MP_RXN<12>") )
				( member ( signalRef "P3E_CPU1_PE3_MP_RXN<13>") )
				( member ( signalRef "P3E_CPU1_PE3_MP_RXN<14>") )
				( member ( signalRef "P3E_CPU1_PE3_MP_RXN<15>") )
				( objectStatus "@baseboard_fab2_lib.baseboard_fab2(sch_1):p3e_cpu1_pe3_mp_rxn" )
			)
			( bus "P3E_CPU1_PE3_MP_RXP"
				( memberType ( signal ) )
				( member ( signalRef "P3E_CPU1_PE3_MP_RXP<0>") )
				( member ( signalRef "P3E_CPU1_PE3_MP_RXP<1>") )
				( member ( signalRef "P3E_CPU1_PE3_MP_RXP<2>") )
				( member ( signalRef "P3E_CPU1_PE3_MP_RXP<3>") )
				( member ( signalRef "P3E_CPU1_PE3_MP_RXP<4>") )
				( member ( signalRef "P3E_CPU1_PE3_MP_RXP<5>") )
				( member ( signalRef "P3E_CPU1_PE3_MP_RXP<6>") )
				( member ( signalRef "P3E_CPU1_PE3_MP_RXP<7>") )
				( member ( signalRef "P3E_CPU1_PE3_MP_RXP<8>") )
				( member ( signalRef "P3E_CPU1_PE3_MP_RXP<9>") )
				( member ( signalRef "P3E_CPU1_PE3_MP_RXP<10>") )
				( member ( signalRef "P3E_CPU1_PE3_MP_RXP<11>") )
				( member ( signalRef "P3E_CPU1_PE3_MP_RXP<12>") )
				( member ( signalRef "P3E_CPU1_PE3_MP_RXP<13>") )
				( member ( signalRef "P3E_CPU1_PE3_MP_RXP<14>") )
				( member ( signalRef "P3E_CPU1_PE3_MP_RXP<15>") )
				( objectStatus "@baseboard_fab2_lib.baseboard_fab2(sch_1):p3e_cpu1_pe3_mp_rxp" )
			)
			( bus "P3E_CPU1_PE3_MP_TXN"
				( memberType ( signal ) )
				( member ( signalRef "P3E_CPU1_PE3_MP_TXN<0>") )
				( member ( signalRef "P3E_CPU1_PE3_MP_TXN<1>") )
				( member ( signalRef "P3E_CPU1_PE3_MP_TXN<2>") )
				( member ( signalRef "P3E_CPU1_PE3_MP_TXN<3>") )
				( member ( signalRef "P3E_CPU1_PE3_MP_TXN<4>") )
				( member ( signalRef "P3E_CPU1_PE3_MP_TXN<5>") )
				( member ( signalRef "P3E_CPU1_PE3_MP_TXN<6>") )
				( member ( signalRef "P3E_CPU1_PE3_MP_TXN<7>") )
				( member ( signalRef "P3E_CPU1_PE3_MP_TXN<8>") )
				( member ( signalRef "P3E_CPU1_PE3_MP_TXN<9>") )
				( member ( signalRef "P3E_CPU1_PE3_MP_TXN<10>") )
				( member ( signalRef "P3E_CPU1_PE3_MP_TXN<11>") )
				( member ( signalRef "P3E_CPU1_PE3_MP_TXN<12>") )
				( member ( signalRef "P3E_CPU1_PE3_MP_TXN<13>") )
				( member ( signalRef "P3E_CPU1_PE3_MP_TXN<14>") )
				( member ( signalRef "P3E_CPU1_PE3_MP_TXN<15>") )
				( objectStatus "@baseboard_fab2_lib.baseboard_fab2(sch_1):p3e_cpu1_pe3_mp_txn" )
			)
			( bus "P3E_CPU1_PE3_MP_TXP"
				( memberType ( signal ) )
				( member ( signalRef "P3E_CPU1_PE3_MP_TXP<0>") )
				( member ( signalRef "P3E_CPU1_PE3_MP_TXP<1>") )
				( member ( signalRef "P3E_CPU1_PE3_MP_TXP<2>") )
				( member ( signalRef "P3E_CPU1_PE3_MP_TXP<3>") )
				( member ( signalRef "P3E_CPU1_PE3_MP_TXP<4>") )
				( member ( signalRef "P3E_CPU1_PE3_MP_TXP<5>") )
				( member ( signalRef "P3E_CPU1_PE3_MP_TXP<6>") )
				( member ( signalRef "P3E_CPU1_PE3_MP_TXP<7>") )
				( member ( signalRef "P3E_CPU1_PE3_MP_TXP<8>") )
				( member ( signalRef "P3E_CPU1_PE3_MP_TXP<9>") )
				( member ( signalRef "P3E_CPU1_PE3_MP_TXP<10>") )
				( member ( signalRef "P3E_CPU1_PE3_MP_TXP<11>") )
				( member ( signalRef "P3E_CPU1_PE3_MP_TXP<12>") )
				( member ( signalRef "P3E_CPU1_PE3_MP_TXP<13>") )
				( member ( signalRef "P3E_CPU1_PE3_MP_TXP<14>") )
				( member ( signalRef "P3E_CPU1_PE3_MP_TXP<15>") )
				( objectStatus "@baseboard_fab2_lib.baseboard_fab2(sch_1):p3e_cpu1_pe3_mp_txp" )
			)
			( bus "P3E_CPU0_PE1_PCH_C_TXN"
				( memberType ( signal ) )
				( member ( signalRef "P3E_CPU0_PE1_PCH_C_TXN<8>") )
				( member ( signalRef "P3E_CPU0_PE1_PCH_C_TXN<9>") )
				( member ( signalRef "P3E_CPU0_PE1_PCH_C_TXN<10>") )
				( member ( signalRef "P3E_CPU0_PE1_PCH_C_TXN<11>") )
				( member ( signalRef "P3E_CPU0_PE1_PCH_C_TXN<12>") )
				( member ( signalRef "P3E_CPU0_PE1_PCH_C_TXN<13>") )
				( member ( signalRef "P3E_CPU0_PE1_PCH_C_TXN<14>") )
				( member ( signalRef "P3E_CPU0_PE1_PCH_C_TXN<15>") )
				( objectStatus "@baseboard_fab2_lib.baseboard_fab2(sch_1):p3e_cpu0_pe1_pch_c_txn" )
			)
			( bus "P3E_CPU0_PE1_PCH_C_TXP"
				( memberType ( signal ) )
				( member ( signalRef "P3E_CPU0_PE1_PCH_C_TXP<8>") )
				( member ( signalRef "P3E_CPU0_PE1_PCH_C_TXP<9>") )
				( member ( signalRef "P3E_CPU0_PE1_PCH_C_TXP<10>") )
				( member ( signalRef "P3E_CPU0_PE1_PCH_C_TXP<11>") )
				( member ( signalRef "P3E_CPU0_PE1_PCH_C_TXP<12>") )
				( member ( signalRef "P3E_CPU0_PE1_PCH_C_TXP<13>") )
				( member ( signalRef "P3E_CPU0_PE1_PCH_C_TXP<14>") )
				( member ( signalRef "P3E_CPU0_PE1_PCH_C_TXP<15>") )
				( objectStatus "@baseboard_fab2_lib.baseboard_fab2(sch_1):p3e_cpu0_pe1_pch_c_txp" )
			)
			( bus "P3E_CPU0_PE1_PCH_R_RXN"
				( memberType ( signal ) )
				( member ( signalRef "P3E_CPU0_PE1_PCH_R_RXN<8>") )
				( member ( signalRef "P3E_CPU0_PE1_PCH_R_RXN<9>") )
				( member ( signalRef "P3E_CPU0_PE1_PCH_R_RXN<10>") )
				( member ( signalRef "P3E_CPU0_PE1_PCH_R_RXN<11>") )
				( member ( signalRef "P3E_CPU0_PE1_PCH_R_RXN<12>") )
				( member ( signalRef "P3E_CPU0_PE1_PCH_R_RXN<13>") )
				( member ( signalRef "P3E_CPU0_PE1_PCH_R_RXN<14>") )
				( member ( signalRef "P3E_CPU0_PE1_PCH_R_RXN<15>") )
				( objectStatus "@baseboard_fab2_lib.baseboard_fab2(sch_1):p3e_cpu0_pe1_pch_r_rxn" )
			)
			( bus "P3E_CPU0_PE1_PCH_R_RXP"
				( memberType ( signal ) )
				( member ( signalRef "P3E_CPU0_PE1_PCH_R_RXP<8>") )
				( member ( signalRef "P3E_CPU0_PE1_PCH_R_RXP<9>") )
				( member ( signalRef "P3E_CPU0_PE1_PCH_R_RXP<10>") )
				( member ( signalRef "P3E_CPU0_PE1_PCH_R_RXP<11>") )
				( member ( signalRef "P3E_CPU0_PE1_PCH_R_RXP<12>") )
				( member ( signalRef "P3E_CPU0_PE1_PCH_R_RXP<13>") )
				( member ( signalRef "P3E_CPU0_PE1_PCH_R_RXP<14>") )
				( member ( signalRef "P3E_CPU0_PE1_PCH_R_RXP<15>") )
				( objectStatus "@baseboard_fab2_lib.baseboard_fab2(sch_1):p3e_cpu0_pe1_pch_r_rxp" )
			)
			( bus "P3E_CPU0_PE2_SS_C_TXN"
				( memberType ( signal ) )
				( member ( signalRef "P3E_CPU0_PE2_SS_C_TXN<0>") )
				( member ( signalRef "P3E_CPU0_PE2_SS_C_TXN<1>") )
				( member ( signalRef "P3E_CPU0_PE2_SS_C_TXN<2>") )
				( member ( signalRef "P3E_CPU0_PE2_SS_C_TXN<3>") )
				( member ( signalRef "P3E_CPU0_PE2_SS_C_TXN<4>") )
				( member ( signalRef "P3E_CPU0_PE2_SS_C_TXN<5>") )
				( member ( signalRef "P3E_CPU0_PE2_SS_C_TXN<6>") )
				( member ( signalRef "P3E_CPU0_PE2_SS_C_TXN<7>") )
				( member ( signalRef "P3E_CPU0_PE2_SS_C_TXN<8>") )
				( member ( signalRef "P3E_CPU0_PE2_SS_C_TXN<9>") )
				( member ( signalRef "P3E_CPU0_PE2_SS_C_TXN<10>") )
				( member ( signalRef "P3E_CPU0_PE2_SS_C_TXN<11>") )
				( member ( signalRef "P3E_CPU0_PE2_SS_C_TXN<12>") )
				( member ( signalRef "P3E_CPU0_PE2_SS_C_TXN<13>") )
				( member ( signalRef "P3E_CPU0_PE2_SS_C_TXN<14>") )
				( member ( signalRef "P3E_CPU0_PE2_SS_C_TXN<15>") )
				( objectStatus "@baseboard_fab2_lib.baseboard_fab2(sch_1):p3e_cpu0_pe2_ss_c_txn" )
			)
			( bus "P3E_CPU0_PE2_SS_C_TXP"
				( memberType ( signal ) )
				( member ( signalRef "P3E_CPU0_PE2_SS_C_TXP<0>") )
				( member ( signalRef "P3E_CPU0_PE2_SS_C_TXP<1>") )
				( member ( signalRef "P3E_CPU0_PE2_SS_C_TXP<2>") )
				( member ( signalRef "P3E_CPU0_PE2_SS_C_TXP<3>") )
				( member ( signalRef "P3E_CPU0_PE2_SS_C_TXP<4>") )
				( member ( signalRef "P3E_CPU0_PE2_SS_C_TXP<5>") )
				( member ( signalRef "P3E_CPU0_PE2_SS_C_TXP<6>") )
				( member ( signalRef "P3E_CPU0_PE2_SS_C_TXP<7>") )
				( member ( signalRef "P3E_CPU0_PE2_SS_C_TXP<8>") )
				( member ( signalRef "P3E_CPU0_PE2_SS_C_TXP<9>") )
				( member ( signalRef "P3E_CPU0_PE2_SS_C_TXP<10>") )
				( member ( signalRef "P3E_CPU0_PE2_SS_C_TXP<11>") )
				( member ( signalRef "P3E_CPU0_PE2_SS_C_TXP<12>") )
				( member ( signalRef "P3E_CPU0_PE2_SS_C_TXP<13>") )
				( member ( signalRef "P3E_CPU0_PE2_SS_C_TXP<14>") )
				( member ( signalRef "P3E_CPU0_PE2_SS_C_TXP<15>") )
				( objectStatus "@baseboard_fab2_lib.baseboard_fab2(sch_1):p3e_cpu0_pe2_ss_c_txp" )
			)
			( bus "P3E_OCP_CPU0_PE3_C_TXN"
				( memberType ( signal ) )
				( member ( signalRef "P3E_OCP_CPU0_PE3_C_TXN<0>") )
				( member ( signalRef "P3E_OCP_CPU0_PE3_C_TXN<1>") )
				( member ( signalRef "P3E_OCP_CPU0_PE3_C_TXN<2>") )
				( member ( signalRef "P3E_OCP_CPU0_PE3_C_TXN<3>") )
				( member ( signalRef "P3E_OCP_CPU0_PE3_C_TXN<4>") )
				( member ( signalRef "P3E_OCP_CPU0_PE3_C_TXN<5>") )
				( member ( signalRef "P3E_OCP_CPU0_PE3_C_TXN<6>") )
				( member ( signalRef "P3E_OCP_CPU0_PE3_C_TXN<7>") )
				( member ( signalRef "P3E_OCP_CPU0_PE3_C_TXN<8>") )
				( member ( signalRef "P3E_OCP_CPU0_PE3_C_TXN<9>") )
				( member ( signalRef "P3E_OCP_CPU0_PE3_C_TXN<10>") )
				( member ( signalRef "P3E_OCP_CPU0_PE3_C_TXN<11>") )
				( member ( signalRef "P3E_OCP_CPU0_PE3_C_TXN<12>") )
				( member ( signalRef "P3E_OCP_CPU0_PE3_C_TXN<13>") )
				( member ( signalRef "P3E_OCP_CPU0_PE3_C_TXN<14>") )
				( member ( signalRef "P3E_OCP_CPU0_PE3_C_TXN<15>") )
				( objectStatus "@baseboard_fab2_lib.baseboard_fab2(sch_1):p3e_ocp_cpu0_pe3_c_txn" )
			)
			( bus "P3E_OCP_CPU0_PE3_C_TXP"
				( memberType ( signal ) )
				( member ( signalRef "P3E_OCP_CPU0_PE3_C_TXP<0>") )
				( member ( signalRef "P3E_OCP_CPU0_PE3_C_TXP<1>") )
				( member ( signalRef "P3E_OCP_CPU0_PE3_C_TXP<2>") )
				( member ( signalRef "P3E_OCP_CPU0_PE3_C_TXP<3>") )
				( member ( signalRef "P3E_OCP_CPU0_PE3_C_TXP<4>") )
				( member ( signalRef "P3E_OCP_CPU0_PE3_C_TXP<5>") )
				( member ( signalRef "P3E_OCP_CPU0_PE3_C_TXP<6>") )
				( member ( signalRef "P3E_OCP_CPU0_PE3_C_TXP<7>") )
				( member ( signalRef "P3E_OCP_CPU0_PE3_C_TXP<8>") )
				( member ( signalRef "P3E_OCP_CPU0_PE3_C_TXP<9>") )
				( member ( signalRef "P3E_OCP_CPU0_PE3_C_TXP<10>") )
				( member ( signalRef "P3E_OCP_CPU0_PE3_C_TXP<11>") )
				( member ( signalRef "P3E_OCP_CPU0_PE3_C_TXP<12>") )
				( member ( signalRef "P3E_OCP_CPU0_PE3_C_TXP<13>") )
				( member ( signalRef "P3E_OCP_CPU0_PE3_C_TXP<14>") )
				( member ( signalRef "P3E_OCP_CPU0_PE3_C_TXP<15>") )
				( objectStatus "@baseboard_fab2_lib.baseboard_fab2(sch_1):p3e_ocp_cpu0_pe3_c_txp" )
			)
			( bus "P3E_CPU0_PE1_SS_C_TXN"
				( memberType ( signal ) )
				( member ( signalRef "P3E_CPU0_PE1_SS_C_TXN<0>") )
				( member ( signalRef "P3E_CPU0_PE1_SS_C_TXN<1>") )
				( member ( signalRef "P3E_CPU0_PE1_SS_C_TXN<2>") )
				( member ( signalRef "P3E_CPU0_PE1_SS_C_TXN<3>") )
				( member ( signalRef "P3E_CPU0_PE1_SS_C_TXN<4>") )
				( member ( signalRef "P3E_CPU0_PE1_SS_C_TXN<5>") )
				( member ( signalRef "P3E_CPU0_PE1_SS_C_TXN<6>") )
				( member ( signalRef "P3E_CPU0_PE1_SS_C_TXN<7>") )
				( objectStatus "@baseboard_fab2_lib.baseboard_fab2(sch_1):p3e_cpu0_pe1_ss_c_txn" )
			)
			( bus "P3E_CPU0_PE1_SS_C_TXP"
				( memberType ( signal ) )
				( member ( signalRef "P3E_CPU0_PE1_SS_C_TXP<0>") )
				( member ( signalRef "P3E_CPU0_PE1_SS_C_TXP<1>") )
				( member ( signalRef "P3E_CPU0_PE1_SS_C_TXP<2>") )
				( member ( signalRef "P3E_CPU0_PE1_SS_C_TXP<3>") )
				( member ( signalRef "P3E_CPU0_PE1_SS_C_TXP<4>") )
				( member ( signalRef "P3E_CPU0_PE1_SS_C_TXP<5>") )
				( member ( signalRef "P3E_CPU0_PE1_SS_C_TXP<6>") )
				( member ( signalRef "P3E_CPU0_PE1_SS_C_TXP<7>") )
				( objectStatus "@baseboard_fab2_lib.baseboard_fab2(sch_1):p3e_cpu0_pe1_ss_c_txp" )
			)
			( bus "P3E_CPU0_PE1_SS_R_RXN"
				( memberType ( signal ) )
				( member ( signalRef "P3E_CPU0_PE1_SS_R_RXN<0>") )
				( member ( signalRef "P3E_CPU0_PE1_SS_R_RXN<1>") )
				( member ( signalRef "P3E_CPU0_PE1_SS_R_RXN<2>") )
				( member ( signalRef "P3E_CPU0_PE1_SS_R_RXN<3>") )
				( member ( signalRef "P3E_CPU0_PE1_SS_R_RXN<4>") )
				( member ( signalRef "P3E_CPU0_PE1_SS_R_RXN<5>") )
				( member ( signalRef "P3E_CPU0_PE1_SS_R_RXN<6>") )
				( member ( signalRef "P3E_CPU0_PE1_SS_R_RXN<7>") )
				( objectStatus "@baseboard_fab2_lib.baseboard_fab2(sch_1):p3e_cpu0_pe1_ss_r_rxn" )
			)
			( bus "P3E_CPU0_PE1_SS_R_RXP"
				( memberType ( signal ) )
				( member ( signalRef "P3E_CPU0_PE1_SS_R_RXP<0>") )
				( member ( signalRef "P3E_CPU0_PE1_SS_R_RXP<1>") )
				( member ( signalRef "P3E_CPU0_PE1_SS_R_RXP<2>") )
				( member ( signalRef "P3E_CPU0_PE1_SS_R_RXP<3>") )
				( member ( signalRef "P3E_CPU0_PE1_SS_R_RXP<4>") )
				( member ( signalRef "P3E_CPU0_PE1_SS_R_RXP<5>") )
				( member ( signalRef "P3E_CPU0_PE1_SS_R_RXP<6>") )
				( member ( signalRef "P3E_CPU0_PE1_SS_R_RXP<7>") )
				( objectStatus "@baseboard_fab2_lib.baseboard_fab2(sch_1):p3e_cpu0_pe1_ss_r_rxp" )
			)
			( bus "P3E_PCH_M2_RX_DN"
				( memberType ( signal ) )
				( member ( signalRef "P3E_PCH_M2_RX_DN<1>") )
				( member ( signalRef "P3E_PCH_M2_RX_DN<2>") )
				( member ( signalRef "P3E_PCH_M2_RX_DN<3>") )
				( objectStatus "@baseboard_fab2_lib.baseboard_fab2(sch_1):p3e_pch_m2_rx_dn" )
			)
			( bus "P3E_PCH_M2_RX_DP"
				( memberType ( signal ) )
				( member ( signalRef "P3E_PCH_M2_RX_DP<1>") )
				( member ( signalRef "P3E_PCH_M2_RX_DP<2>") )
				( member ( signalRef "P3E_PCH_M2_RX_DP<3>") )
				( objectStatus "@baseboard_fab2_lib.baseboard_fab2(sch_1):p3e_pch_m2_rx_dp" )
			)
			( bus "P3E_PCH_M2_TX_DN"
				( memberType ( signal ) )
				( member ( signalRef "P3E_PCH_M2_TX_DN<1>") )
				( member ( signalRef "P3E_PCH_M2_TX_DN<2>") )
				( member ( signalRef "P3E_PCH_M2_TX_DN<3>") )
				( objectStatus "@baseboard_fab2_lib.baseboard_fab2(sch_1):p3e_pch_m2_tx_dn" )
			)
			( bus "P3E_PCH_M2_TX_DP"
				( memberType ( signal ) )
				( member ( signalRef "P3E_PCH_M2_TX_DP<1>") )
				( member ( signalRef "P3E_PCH_M2_TX_DP<2>") )
				( member ( signalRef "P3E_PCH_M2_TX_DP<3>") )
				( objectStatus "@baseboard_fab2_lib.baseboard_fab2(sch_1):p3e_pch_m2_tx_dp" )
			)
			( bus "SATA6G_PCH_PCIE_UP_SATA_RXN"
				( memberType ( signal ) )
				( member ( signalRef "SATA6G_PCH_PCIE_UP_SATA_RXN<0>") )
				( member ( signalRef "SATA6G_PCH_PCIE_UP_SATA_RXN<1>") )
				( member ( signalRef "SATA6G_PCH_PCIE_UP_SATA_RXN<2>") )
				( member ( signalRef "SATA6G_PCH_PCIE_UP_SATA_RXN<3>") )
				( member ( signalRef "SATA6G_PCH_PCIE_UP_SATA_RXN<4>") )
				( member ( signalRef "SATA6G_PCH_PCIE_UP_SATA_RXN<5>") )
				( member ( signalRef "SATA6G_PCH_PCIE_UP_SATA_RXN<6>") )
				( member ( signalRef "SATA6G_PCH_PCIE_UP_SATA_RXN<7>") )
				( objectStatus "@baseboard_fab2_lib.baseboard_fab2(sch_1):sata6g_pch_pcie_up_sata_rxn" )
			)
			( bus "SATA6G_PCH_PCIE_UP_SATA_RXP"
				( memberType ( signal ) )
				( member ( signalRef "SATA6G_PCH_PCIE_UP_SATA_RXP<0>") )
				( member ( signalRef "SATA6G_PCH_PCIE_UP_SATA_RXP<1>") )
				( member ( signalRef "SATA6G_PCH_PCIE_UP_SATA_RXP<2>") )
				( member ( signalRef "SATA6G_PCH_PCIE_UP_SATA_RXP<3>") )
				( member ( signalRef "SATA6G_PCH_PCIE_UP_SATA_RXP<4>") )
				( member ( signalRef "SATA6G_PCH_PCIE_UP_SATA_RXP<5>") )
				( member ( signalRef "SATA6G_PCH_PCIE_UP_SATA_RXP<6>") )
				( member ( signalRef "SATA6G_PCH_PCIE_UP_SATA_RXP<7>") )
				( objectStatus "@baseboard_fab2_lib.baseboard_fab2(sch_1):sata6g_pch_pcie_up_sata_rxp" )
			)
			( bus "SATA6G_PCH_PCIE_UP_SATA_TXN"
				( memberType ( signal ) )
				( member ( signalRef "SATA6G_PCH_PCIE_UP_SATA_TXN<0>") )
				( member ( signalRef "SATA6G_PCH_PCIE_UP_SATA_TXN<1>") )
				( member ( signalRef "SATA6G_PCH_PCIE_UP_SATA_TXN<2>") )
				( member ( signalRef "SATA6G_PCH_PCIE_UP_SATA_TXN<3>") )
				( member ( signalRef "SATA6G_PCH_PCIE_UP_SATA_TXN<4>") )
				( member ( signalRef "SATA6G_PCH_PCIE_UP_SATA_TXN<5>") )
				( member ( signalRef "SATA6G_PCH_PCIE_UP_SATA_TXN<6>") )
				( member ( signalRef "SATA6G_PCH_PCIE_UP_SATA_TXN<7>") )
				( objectStatus "@baseboard_fab2_lib.baseboard_fab2(sch_1):sata6g_pch_pcie_up_sata_txn" )
			)
			( bus "SATA6G_PCH_PCIE_UP_SATA_TXP"
				( memberType ( signal ) )
				( member ( signalRef "SATA6G_PCH_PCIE_UP_SATA_TXP<0>") )
				( member ( signalRef "SATA6G_PCH_PCIE_UP_SATA_TXP<1>") )
				( member ( signalRef "SATA6G_PCH_PCIE_UP_SATA_TXP<2>") )
				( member ( signalRef "SATA6G_PCH_PCIE_UP_SATA_TXP<3>") )
				( member ( signalRef "SATA6G_PCH_PCIE_UP_SATA_TXP<4>") )
				( member ( signalRef "SATA6G_PCH_PCIE_UP_SATA_TXP<5>") )
				( member ( signalRef "SATA6G_PCH_PCIE_UP_SATA_TXP<6>") )
				( member ( signalRef "SATA6G_PCH_PCIE_UP_SATA_TXP<7>") )
				( objectStatus "@baseboard_fab2_lib.baseboard_fab2(sch_1):sata6g_pch_pcie_up_sata_txp" )
			)
			( bus "DMI_CPU0_PCH_RX_DN"
				( memberType ( signal ) )
				( member ( signalRef "DMI_CPU0_PCH_RX_DN<0>") )
				( member ( signalRef "DMI_CPU0_PCH_RX_DN<1>") )
				( member ( signalRef "DMI_CPU0_PCH_RX_DN<2>") )
				( member ( signalRef "DMI_CPU0_PCH_RX_DN<3>") )
				( objectStatus "@baseboard_fab2_lib.baseboard_fab2(sch_1):dmi_cpu0_pch_rx_dn" )
			)
			( bus "DMI_CPU0_PCH_RX_DP"
				( memberType ( signal ) )
				( member ( signalRef "DMI_CPU0_PCH_RX_DP<0>") )
				( member ( signalRef "DMI_CPU0_PCH_RX_DP<1>") )
				( member ( signalRef "DMI_CPU0_PCH_RX_DP<2>") )
				( member ( signalRef "DMI_CPU0_PCH_RX_DP<3>") )
				( objectStatus "@baseboard_fab2_lib.baseboard_fab2(sch_1):dmi_cpu0_pch_rx_dp" )
			)
			( bus "DMI_CPU0_PCH_TX_C_DN"
				( memberType ( signal ) )
				( member ( signalRef "DMI_CPU0_PCH_TX_C_DN<0>") )
				( member ( signalRef "DMI_CPU0_PCH_TX_C_DN<1>") )
				( member ( signalRef "DMI_CPU0_PCH_TX_C_DN<2>") )
				( member ( signalRef "DMI_CPU0_PCH_TX_C_DN<3>") )
				( objectStatus "@baseboard_fab2_lib.baseboard_fab2(sch_1):dmi_cpu0_pch_tx_c_dn" )
			)
			( bus "DMI_CPU0_PCH_TX_C_DP"
				( memberType ( signal ) )
				( member ( signalRef "DMI_CPU0_PCH_TX_C_DP<0>") )
				( member ( signalRef "DMI_CPU0_PCH_TX_C_DP<1>") )
				( member ( signalRef "DMI_CPU0_PCH_TX_C_DP<2>") )
				( member ( signalRef "DMI_CPU0_PCH_TX_C_DP<3>") )
				( objectStatus "@baseboard_fab2_lib.baseboard_fab2(sch_1):dmi_cpu0_pch_tx_c_dp" )
			)
			( bus "LPC_LAD_IO"
				( memberType ( signal ) )
				( member ( signalRef "LPC_LAD0_IO0") )
				( member ( signalRef "LPC_LAD1_IO1") )
				( member ( signalRef "LPC_LAD2_IO2") )
				( member ( signalRef "LPC_LAD3_IO3") )
				( objectStatus "@baseboard_fab2_lib.baseboard_fab2(sch_1):lpc_lad_io" )
			)
			( bus "P3E_CPU1_PE3_MP_C_TXN"
				( memberType ( signal ) )
				( member ( signalRef "P3E_CPU1_PE3_MP_C_TXN<0>") )
				( member ( signalRef "P3E_CPU1_PE3_MP_C_TXN<1>") )
				( member ( signalRef "P3E_CPU1_PE3_MP_C_TXN<2>") )
				( member ( signalRef "P3E_CPU1_PE3_MP_C_TXN<3>") )
				( member ( signalRef "P3E_CPU1_PE3_MP_C_TXN<4>") )
				( member ( signalRef "P3E_CPU1_PE3_MP_C_TXN<5>") )
				( member ( signalRef "P3E_CPU1_PE3_MP_C_TXN<6>") )
				( member ( signalRef "P3E_CPU1_PE3_MP_C_TXN<7>") )
				( member ( signalRef "P3E_CPU1_PE3_MP_C_TXN<8>") )
				( member ( signalRef "P3E_CPU1_PE3_MP_C_TXN<9>") )
				( member ( signalRef "P3E_CPU1_PE3_MP_C_TXN<10>") )
				( member ( signalRef "P3E_CPU1_PE3_MP_C_TXN<11>") )
				( member ( signalRef "P3E_CPU1_PE3_MP_C_TXN<12>") )
				( member ( signalRef "P3E_CPU1_PE3_MP_C_TXN<13>") )
				( member ( signalRef "P3E_CPU1_PE3_MP_C_TXN<14>") )
				( member ( signalRef "P3E_CPU1_PE3_MP_C_TXN<15>") )
				( objectStatus "@baseboard_fab2_lib.baseboard_fab2(sch_1):p3e_cpu1_pe3_mp_c_txn" )
			)
			( bus "P3E_CPU1_PE3_MP_C_TXP"
				( memberType ( signal ) )
				( member ( signalRef "P3E_CPU1_PE3_MP_C_TXP<0>") )
				( member ( signalRef "P3E_CPU1_PE3_MP_C_TXP<1>") )
				( member ( signalRef "P3E_CPU1_PE3_MP_C_TXP<2>") )
				( member ( signalRef "P3E_CPU1_PE3_MP_C_TXP<3>") )
				( member ( signalRef "P3E_CPU1_PE3_MP_C_TXP<4>") )
				( member ( signalRef "P3E_CPU1_PE3_MP_C_TXP<5>") )
				( member ( signalRef "P3E_CPU1_PE3_MP_C_TXP<6>") )
				( member ( signalRef "P3E_CPU1_PE3_MP_C_TXP<7>") )
				( member ( signalRef "P3E_CPU1_PE3_MP_C_TXP<8>") )
				( member ( signalRef "P3E_CPU1_PE3_MP_C_TXP<9>") )
				( member ( signalRef "P3E_CPU1_PE3_MP_C_TXP<10>") )
				( member ( signalRef "P3E_CPU1_PE3_MP_C_TXP<11>") )
				( member ( signalRef "P3E_CPU1_PE3_MP_C_TXP<12>") )
				( member ( signalRef "P3E_CPU1_PE3_MP_C_TXP<13>") )
				( member ( signalRef "P3E_CPU1_PE3_MP_C_TXP<14>") )
				( member ( signalRef "P3E_CPU1_PE3_MP_C_TXP<15>") )
				( objectStatus "@baseboard_fab2_lib.baseboard_fab2(sch_1):p3e_cpu1_pe3_mp_c_txp" )
			)
			( bus "NC_M2"
				( memberType ( signal ) )
				( member ( signalRef "NC_M2<0>") )
				( member ( signalRef "NC_M2<1>") )
				( objectStatus "@baseboard_fab2_lib.baseboard_fab2(sch_1):nc_m2" )
			)
			( bus "P3E_PCH_M2_TX_C_DN"
				( memberType ( signal ) )
				( member ( signalRef "P3E_PCH_M2_TX_C_DN<1>") )
				( member ( signalRef "P3E_PCH_M2_TX_C_DN<2>") )
				( member ( signalRef "P3E_PCH_M2_TX_C_DN<3>") )
				( objectStatus "@baseboard_fab2_lib.baseboard_fab2(sch_1):p3e_pch_m2_tx_c_dn" )
			)
			( bus "P3E_PCH_M2_TX_C_DP"
				( memberType ( signal ) )
				( member ( signalRef "P3E_PCH_M2_TX_C_DP<1>") )
				( member ( signalRef "P3E_PCH_M2_TX_C_DP<2>") )
				( member ( signalRef "P3E_PCH_M2_TX_C_DP<3>") )
				( objectStatus "@baseboard_fab2_lib.baseboard_fab2(sch_1):p3e_pch_m2_tx_c_dp" )
			)
			( bus "TP_RSVD"
				( memberType ( signal ) )
				( member ( signalRef "TP_RSVD<0>") )
				( objectStatus "@baseboard_fab2_lib.baseboard_fab2(sch_1):tp_rsvd" )
			)
			( bus "P3E_CPU0_PE1_PCH_CON_RXN"
				( memberType ( signal ) )
				( member ( signalRef "P3E_CPU0_PE1_PCH_CON_RXN<8>") )
				( member ( signalRef "P3E_CPU0_PE1_PCH_CON_RXN<9>") )
				( member ( signalRef "P3E_CPU0_PE1_PCH_CON_RXN<10>") )
				( member ( signalRef "P3E_CPU0_PE1_PCH_CON_RXN<11>") )
				( member ( signalRef "P3E_CPU0_PE1_PCH_CON_RXN<12>") )
				( member ( signalRef "P3E_CPU0_PE1_PCH_CON_RXN<13>") )
				( member ( signalRef "P3E_CPU0_PE1_PCH_CON_RXN<14>") )
				( member ( signalRef "P3E_CPU0_PE1_PCH_CON_RXN<15>") )
				( objectStatus "@baseboard_fab2_lib.baseboard_fab2(sch_1):p3e_cpu0_pe1_pch_con_rxn" )
			)
			( bus "P3E_CPU0_PE1_PCH_CON_RXP"
				( memberType ( signal ) )
				( member ( signalRef "P3E_CPU0_PE1_PCH_CON_RXP<8>") )
				( member ( signalRef "P3E_CPU0_PE1_PCH_CON_RXP<9>") )
				( member ( signalRef "P3E_CPU0_PE1_PCH_CON_RXP<10>") )
				( member ( signalRef "P3E_CPU0_PE1_PCH_CON_RXP<11>") )
				( member ( signalRef "P3E_CPU0_PE1_PCH_CON_RXP<12>") )
				( member ( signalRef "P3E_CPU0_PE1_PCH_CON_RXP<13>") )
				( member ( signalRef "P3E_CPU0_PE1_PCH_CON_RXP<14>") )
				( member ( signalRef "P3E_CPU0_PE1_PCH_CON_RXP<15>") )
				( objectStatus "@baseboard_fab2_lib.baseboard_fab2(sch_1):p3e_cpu0_pe1_pch_con_rxp" )
			)
			( bus "P3E_CPU0_PE1_PCH_CON_TXN"
				( memberType ( signal ) )
				( member ( signalRef "P3E_CPU0_PE1_PCH_CON_TXN<8>") )
				( member ( signalRef "P3E_CPU0_PE1_PCH_CON_TXN<9>") )
				( member ( signalRef "P3E_CPU0_PE1_PCH_CON_TXN<10>") )
				( member ( signalRef "P3E_CPU0_PE1_PCH_CON_TXN<11>") )
				( member ( signalRef "P3E_CPU0_PE1_PCH_CON_TXN<12>") )
				( member ( signalRef "P3E_CPU0_PE1_PCH_CON_TXN<13>") )
				( member ( signalRef "P3E_CPU0_PE1_PCH_CON_TXN<14>") )
				( member ( signalRef "P3E_CPU0_PE1_PCH_CON_TXN<15>") )
				( objectStatus "@baseboard_fab2_lib.baseboard_fab2(sch_1):p3e_cpu0_pe1_pch_con_txn" )
			)
			( bus "P3E_CPU0_PE1_PCH_CON_TXP"
				( memberType ( signal ) )
				( member ( signalRef "P3E_CPU0_PE1_PCH_CON_TXP<8>") )
				( member ( signalRef "P3E_CPU0_PE1_PCH_CON_TXP<9>") )
				( member ( signalRef "P3E_CPU0_PE1_PCH_CON_TXP<10>") )
				( member ( signalRef "P3E_CPU0_PE1_PCH_CON_TXP<11>") )
				( member ( signalRef "P3E_CPU0_PE1_PCH_CON_TXP<12>") )
				( member ( signalRef "P3E_CPU0_PE1_PCH_CON_TXP<13>") )
				( member ( signalRef "P3E_CPU0_PE1_PCH_CON_TXP<14>") )
				( member ( signalRef "P3E_CPU0_PE1_PCH_CON_TXP<15>") )
				( objectStatus "@baseboard_fab2_lib.baseboard_fab2(sch_1):p3e_cpu0_pe1_pch_con_txp" )
			)
		)
	)
)
